(kicad_pcb
	(version 20241229)
	(generator "pcbnew")
	(generator_version "9.0")
	(general
		(thickness 1.63)
		(legacy_teardrops no)
	)
	(paper "A4")
	(title_block
		(title "CM4 Baseboard")
		(date "2026-01-05")
		(rev "1.1.1")
		(company "Antmicro Ltd")
		(comment 1 "www.antmicro.com")
	)
	(layers
		(0 "F.Cu" signal)
		(4 "In1.Cu" power)
		(6 "In2.Cu" power)
		(8 "In3.Cu" signal)
		(10 "In4.Cu" signal)
		(2 "B.Cu" signal)
		(9 "F.Adhes" user "F.Adhesive")
		(11 "B.Adhes" user "B.Adhesive")
		(13 "F.Paste" user)
		(15 "B.Paste" user)
		(5 "F.SilkS" user "F.Silkscreen")
		(7 "B.SilkS" user "B.Silkscreen")
		(1 "F.Mask" user)
		(3 "B.Mask" user)
		(17 "Dwgs.User" user "User.Drawings")
		(19 "Cmts.User" user "User.Comments")
		(21 "Eco1.User" user "User.Eco1")
		(23 "Eco2.User" user "User.Eco2")
		(25 "Edge.Cuts" user)
		(27 "Margin" user)
		(31 "F.CrtYd" user "F.Courtyard")
		(29 "B.CrtYd" user "B.Courtyard")
		(35 "F.Fab" user)
		(33 "B.Fab" user)
	)
	(setup
		(stackup
			(layer "F.SilkS"
				(type "Top Silk Screen")
				(color "White")
			)
			(layer "F.Paste"
				(type "Top Solder Paste")
			)
			(layer "F.Mask"
				(type "Top Solder Mask")
				(color "Black")
				(thickness 0.01)
			)
			(layer "F.Cu"
				(type "copper")
				(thickness 0.035)
			)
			(layer "dielectric 1"
				(type "prepreg")
				(thickness 0.12)
				(material "PR2116")
				(epsilon_r 4.2)
				(loss_tangent 0.02)
			)
			(layer "In1.Cu"
				(type "copper")
				(thickness 0.035)
			)
			(layer "dielectric 2"
				(type "core")
				(thickness 0.51)
				(material "FR4-Improved")
				(epsilon_r 4.5)
				(loss_tangent 0.02)
			)
			(layer "In2.Cu"
				(type "copper")
				(thickness 0.035)
			)
			(layer "dielectric 3"
				(type "prepreg")
				(thickness 0.07)
				(material "PR1080")
				(epsilon_r 4.2)
				(loss_tangent 0.02) addsublayer
				(thickness 0.07)
				(material "PR1080")
				(epsilon_r 4.2)
				(loss_tangent 0.02)
			)
			(layer "In3.Cu"
				(type "copper")
				(thickness 0.035)
			)
			(layer "dielectric 4"
				(type "core")
				(thickness 0.51)
				(material "FR4-Improved")
				(epsilon_r 4.5)
				(loss_tangent 0.02)
			)
			(layer "In4.Cu"
				(type "copper")
				(thickness 0.035)
			)
			(layer "dielectric 5"
				(type "prepreg")
				(thickness 0.12)
				(material "PR2116")
				(epsilon_r 4.2)
				(loss_tangent 0.02)
			)
			(layer "B.Cu"
				(type "copper")
				(thickness 0.035)
			)
			(layer "B.Mask"
				(type "Bottom Solder Mask")
				(color "Black")
				(thickness 0.01)
			)
			(layer "B.Paste"
				(type "Bottom Solder Paste")
			)
			(layer "B.SilkS"
				(type "Bottom Silk Screen")
				(color "White")
			)
			(copper_finish "None")
			(dielectric_constraints yes)
		)
		(pad_to_mask_clearance 0)
		(allow_soldermask_bridges_in_footprints no)
		(tenting front back)
		(aux_axis_origin 190.75 204.4)
		(pcbplotparams
			(layerselection 0x00000000_00000000_55555555_5755f5ff)
			(plot_on_all_layers_selection 0x00000000_00000000_00000000_00000000)
			(disableapertmacros no)
			(usegerberextensions no)
			(usegerberattributes no)
			(usegerberadvancedattributes no)
			(creategerberjobfile no)
			(dashed_line_dash_ratio 12.000000)
			(dashed_line_gap_ratio 3.000000)
			(svgprecision 6)
			(plotframeref no)
			(mode 1)
			(useauxorigin no)
			(hpglpennumber 1)
			(hpglpenspeed 20)
			(hpglpendiameter 15.000000)
			(pdf_front_fp_property_popups yes)
			(pdf_back_fp_property_popups yes)
			(pdf_metadata yes)
			(pdf_single_document no)
			(dxfpolygonmode yes)
			(dxfimperialunits yes)
			(dxfusepcbnewfont yes)
			(psnegative no)
			(psa4output no)
			(plot_black_and_white yes)
			(sketchpadsonfab no)
			(plotpadnumbers no)
			(hidednponfab no)
			(sketchdnponfab yes)
			(crossoutdnponfab yes)
			(subtractmaskfromsilk no)
			(outputformat 1)
			(mirror no)
			(drillshape 0)
			(scaleselection 1)
			(outputdirectory "./")
		)
	)
	(net 0 "")
	(net 1 "GNDD")
	(net 2 "Net-(D203-A)")
	(net 3 "GND")
	(net 4 "Net-(D204-A)")
	(net 5 "/Compute module/SDIO.D1")
	(net 6 "/Compute module/SDIO.D0")
	(net 7 "/Compute module/SDIO.CLK")
	(net 8 "/Compute module/SDIO.CMD")
	(net 9 "+3V3")
	(net 10 "+5V")
	(net 11 "/Compute module/SDIO.D3")
	(net 12 "/Compute module/SDIO.D2")
	(net 13 "/Compute module/HDMI.D1_N")
	(net 14 "/Compute module/HDMI.D1_P")
	(net 15 "/Compute module/HDMI.D2_N")
	(net 16 "/Compute module/HDMI.D2_P")
	(net 17 "Net-(Q307-G)")
	(net 18 "V_{IO}")
	(net 19 "/CSI/CSI_3V3")
	(net 20 "/CSI/CSI_5V")
	(net 21 "/Supply/VCC_IN")
	(net 22 "+1V8")
	(net 23 "/Compute module/HDMI.CLK_N")
	(net 24 "/Compute module/USBA_VBUS")
	(net 25 "/Compute module/HDMI.CLK_P")
	(net 26 "/USB/USBD_VBUS")
	(net 27 "/USB/USB_3V3")
	(net 28 "/USB/+5V_{CAP}")
	(net 29 "/USB/USBD_SVBUS")
	(net 30 "/USB/USB_1V2")
	(net 31 "/USB/VREGIN")
	(net 32 "/USB/VCC_USB")
	(net 33 "/Ethernet/VDD")
	(net 34 "/Compute module/HDMI.D0_N")
	(net 35 "/Compute module/HDMI.D0_P")
	(net 36 "/Compute module/UART.0.RX")
	(net 37 "/Compute module/UART.0.TX")
	(net 38 "/Compute module/USB.D_N")
	(net 39 "/Compute module/USB.D_P")
	(net 40 "/Compute module/NVMe.CLK_P")
	(net 41 "/Compute module/NVMe.CLK_N")
	(net 42 "/CSI/CSI1.D0_N")
	(net 43 "VCC")
	(net 44 "/CSI/CSI1.D0_P")
	(net 45 "/Supply/SW_M2")
	(net 46 "/CSI/CSI1.D1_N")
	(net 47 "/Ethernet/POE_12V")
	(net 48 "Net-(U301-BST)")
	(net 49 "/Supply/SW_3V3")
	(net 50 "/CSI/CSI1.D1_P")
	(net 51 "Net-(U302-BST)")
	(net 52 "/CSI/CSI1.CLK_N")
	(net 53 "/CSI/CSI0.D0_N")
	(net 54 "/CSI/CSI1.CLK_P")
	(net 55 "/CSI/CSI0.D0_P")
	(net 56 "/CSI/CSI1.D2_N")
	(net 57 "/CSI/CSI0.D1_N")
	(net 58 "/CSI/CSI1.D2_P")
	(net 59 "/Supply/SW_5V")
	(net 60 "Net-(U303-BST)")
	(net 61 "/Ethernet/PAIR_12")
	(net 62 "/Ethernet/PAIR_36")
	(net 63 "/Ethernet/PAIR_910")
	(net 64 "/Ethernet/PAIR_78")
	(net 65 "3V3_SSD")
	(net 66 "/Supply/VCC_5V")
	(net 67 "/CSI/CSI0.D1_P")
	(net 68 "/CSI/CSI1.D3_N")
	(net 69 "/CSI/CSI0.CLK_N")
	(net 70 "/CSI/CSI1.D3_P")
	(net 71 "/CSI/CSI0.CLK_P")
	(net 72 "/Compute module/DSI.D0_N")
	(net 73 "/Compute module/DSI.D0_P")
	(net 74 "/Compute module/DSI.D1_N")
	(net 75 "/Compute module/DSI.D1_P")
	(net 76 "/Compute module/DSI.CLK_N")
	(net 77 "/Supply/OUT_5V")
	(net 78 "/Supply/OUT_M2")
	(net 79 "/Compute module/ETHERNET.D3_P")
	(net 80 "/Compute module/ETHERNET.D1_P")
	(net 81 "/Compute module/ETHERNET.D3_N")
	(net 82 "/Compute module/ETHERNET.D1_N")
	(net 83 "/Compute module/ETHERNET.D2_N")
	(net 84 "/Compute module/ETHERNET.D0_N")
	(net 85 "/Compute module/ETHERNET.D2_P")
	(net 86 "/Compute module/DSI.CLK_P")
	(net 87 "/Compute module/DSI.D2_N")
	(net 88 "/Compute module/ETHERNET.D0_P")
	(net 89 "/Supply/OUT_3V3")
	(net 90 "/Ethernet/VSS")
	(net 91 "Net-(J401-P4)")
	(net 92 "Net-(C403-Pad1)")
	(net 93 "Net-(U801-V_{DD(A)})")
	(net 94 "Net-(U801-TVDD_IN)")
	(net 95 "Net-(U801-V_{DD(VMID)})")
	(net 96 "/Compute module/DSI.D3_N")
	(net 97 "/Compute module/DSI.D2_P")
	(net 98 "/Compute module/DSI.D3_P")
	(net 99 "Net-(U801-XTAL2)")
	(net 100 "Net-(C811-Pad2)")
	(net 101 "Net-(U801-ANT1)")
	(net 102 "Net-(C812-Pad2)")
	(net 103 "Net-(U801-RXP)")
	(net 104 "Net-(C813-Pad2)")
	(net 105 "Net-(U801-RXN)")
	(net 106 "Net-(C814-Pad2)")
	(net 107 "Net-(U801-ANT2)")
	(net 108 "Net-(U801-CLK_XTAL1)")
	(net 109 "Net-(C816-Pad2)")
	(net 110 "Net-(C817-Pad1)")
	(net 111 "/USB/SW_FTDI")
	(net 112 "Net-(U903-BST)")
	(net 113 "/USB/OUT_FTDI")
	(net 114 "Net-(U905-OSCI)")
	(net 115 "Net-(U905-OSCO)")
	(net 116 "Net-(D401-Pad1)")
	(net 117 "Net-(D401-Pad2)")
	(net 118 "/Compute module/SDIO.CD")
	(net 119 "Net-(D710-C)")
	(net 120 "/Compute module/DSICtrl.IRQ1")
	(net 121 "/Compute module/DSICtrl.~{IRQ2}")
	(net 122 "/Compute module/DSICtrl.EN")
	(net 123 "/Compute module/DSICtrl.~{RST}")
	(net 124 "/Compute module/DSICtrl.DIM")
	(net 125 "/Compute module/DSICtrl.GPIO")
	(net 126 "/Ethernet/ULS-12_CTRL")
	(net 127 "Net-(Q903-G)")
	(net 128 "/Compute module/nEXTRST")
	(net 129 "Net-(J201-Pad73)")
	(net 130 "Net-(J201-Pad76)")
	(net 131 "unconnected-(J201-Pad75)")
	(net 132 "/Compute module/CM4_3V3")
	(net 133 "unconnected-(J201-Pad72)")
	(net 134 "unconnected-(J201-Pad70)")
	(net 135 "unconnected-(J201-Pad68)")
	(net 136 "unconnected-(J201-Pad64)")
	(net 137 "Net-(J201-Pad21)")
	(net 138 "unconnected-(J201-Pad19)")
	(net 139 "/Compute module/T1_P")
	(net 140 "/CSI/I_{2}C_CSI0.SCL")
	(net 141 "/CSI/I_{2}C_CSI0.SDA")
	(net 142 "/CSI/I_{2}C1.SCL")
	(net 143 "/CSI/I_{2}C1.SDA")
	(net 144 "/Compute module/NVMe.~{CLK_REQ}")
	(net 145 "/Compute module/NVMe.~{RST}")
	(net 146 "/Compute module/T1_N")
	(net 147 "/Compute module/R1_P")
	(net 148 "/Compute module/R1_N")
	(net 149 "/Compute module/R2_N")
	(net 150 "/Compute module/T2_P")
	(net 151 "/Compute module/R2_P")
	(net 152 "/Compute module/T2_N")
	(net 153 "/Compute module/T3_N")
	(net 154 "/Compute module/R3_P")
	(net 155 "/Compute module/T3_P")
	(net 156 "/Compute module/R3_N")
	(net 157 "unconnected-(J202-Pad6)")
	(net 158 "/Compute module/NVMe.RX3_N")
	(net 159 "/Compute module/NVMe.RX3_P")
	(net 160 "/Compute module/NVMe.TX3_N")
	(net 161 "/Compute module/NVMe.TX3_P")
	(net 162 "/Compute module/NVMe.RX2_N")
	(net 163 "/Compute module/NVMe.RX2_P")
	(net 164 "/Compute module/NVMe.TX2_N")
	(net 165 "/Compute module/NVMe.TX2_P")
	(net 166 "/Compute module/NVMe.RX1_N")
	(net 167 "/Compute module/NVMe.RX1_P")
	(net 168 "/Compute module/NVMe.TX1_N")
	(net 169 "/Compute module/NVMe.TX1_P")
	(net 170 "/Compute module/NVMe.RX0_N")
	(net 171 "/Compute module/NVMe.RX0_P")
	(net 172 "/Compute module/NVMe.TX0_N")
	(net 173 "/Compute module/NVMe.TX0_P")
	(net 174 "unconnected-(J202-Pad4)")
	(net 175 "Net-(J401-LED_YEL-)")
	(net 176 "Net-(J401-LED_GRN-)")
	(net 177 "unconnected-(J501-NC-Pad69)")
	(net 178 "Net-(J501-SUSCLK)")
	(net 179 "unconnected-(J501-NC-Pad67)")
	(net 180 "unconnected-(J501-NC-Pad58)")
	(net 181 "unconnected-(J501-NC-Pad56)")
	(net 182 "Net-(J501-~{PEWAKE})")
	(net 183 "unconnected-(J501-NC-Pad48)")
	(net 184 "unconnected-(J501-NC-Pad46)")
	(net 185 "Net-(J501-ALERT)")
	(net 186 "/Compute module/UART.1.TX")
	(net 187 "/Compute module/UART.1.RX")
	(net 188 "/Compute module/UART.2.TX")
	(net 189 "/Compute module/UART.2.RX")
	(net 190 "/Compute module/UART.3.TX")
	(net 191 "/Compute module/UART.3.RX")
	(net 192 "Net-(J501-SMB_DATA)")
	(net 193 "Net-(J501-SMB_CLK)")
	(net 194 "unconnected-(J501-NC-Pad38)")
	(net 195 "unconnected-(J501-NC-Pad36)")
	(net 196 "unconnected-(J501-NC-Pad34)")
	(net 197 "unconnected-(J501-NC-Pad32)")
	(net 198 "unconnected-(J501-NC-Pad30)")
	(net 199 "unconnected-(J501-NC-Pad28)")
	(net 200 "unconnected-(J501-NC-Pad26)")
	(net 201 "unconnected-(J501-NC-Pad24)")
	(net 202 "unconnected-(J501-NC-Pad22)")
	(net 203 "/USB/USBA_CC1")
	(net 204 "/USB/USBA_CC2")
	(net 205 "/USB/AD_P")
	(net 206 "/USB/AD_N")
	(net 207 "/USB/USBD_CC1")
	(net 208 "/USB/USBD_CC2")
	(net 209 "/USB/DD_P")
	(net 210 "/USB/DD_N")
	(net 211 "/USB/VCC_PD")
	(net 212 "/Compute module/ETHERNET.LED_ACT")
	(net 213 "/Compute module/SYNC_IN")
	(net 214 "/Compute module/ETHERNET.LED_LINK")
	(net 215 "/Compute module/SYNC_OUT")
	(net 216 "/Compute module/~{EEPROM_WP}")
	(net 217 "/Compute module/GPIO.26")
	(net 218 "/Compute module/GPIO.21")
	(net 219 "/Compute module/GPIO.19")
	(net 220 "/Compute module/GPIO.20")
	(net 221 "/Compute module/GPIO.13{slash}TXD5")
	(net 222 "/Compute module/GPIO.16")
	(net 223 "/Compute module/GPIO.6")
	(net 224 "/Compute module/GPIO.12{slash}RXD5")
	(net 225 "/Compute module/GPIO.5{slash}RXD3")
	(net 226 "/Compute module/GPIO.7")
	(net 227 "/Compute module/GPIO.11")
	(net 228 "/Compute module/GPIO.8{slash}TXD4")
	(net 229 "/Compute module/GPIO.9{slash}RXD4")
	(net 230 "/Compute module/GPIO.25")
	(net 231 "/Compute module/PolarfireID")
	(net 232 "/Compute module/GPIO.10")
	(net 233 "/Compute module/GPIO.24")
	(net 234 "/Compute module/GPIO.22")
	(net 235 "/Compute module/GPIO.23")
	(net 236 "/Compute module/GPIO.27")
	(net 237 "/Compute module/GPIO.18")
	(net 238 "/Compute module/GPIO.17")
	(net 239 "/Compute module/GPIO.14{slash}RXD0")
	(net 240 "/Compute module/GPIO.4{slash}TXD3")
	(net 241 "/Compute module/GPIO.15{slash}TXD0")
	(net 242 "/Compute module/GPIO.3")
	(net 243 "/Compute module/GPIO.2")
	(net 244 "unconnected-(J501-NC-Pad20)")
	(net 245 "unconnected-(J501-NC-Pad8)")
	(net 246 "unconnected-(J501-NC-Pad6)")
	(net 247 "/Compute module/WL_nDis")
	(net 248 "/Compute module/BT_nDis")
	(net 249 "/Compute module/RUN_PG")
	(net 250 "/Compute module/~{RPi_BOOT}")
	(net 251 "/Compute module/GPIO.AIN1")
	(net 252 "/Compute module/~{PWR_LED}")
	(net 253 "/Compute module/GPIO.AIN0")
	(net 254 "/Compute module/CAM_GPIO")
	(net 255 "/Compute module/~{RPi_RST}")
	(net 256 "/Compute module/VDAC_COMP")
	(net 257 "/Compute module/Pf_5V.HPD")
	(net 258 "/Compute module/Pf_5V.SDA")
	(net 259 "/Compute module/Pf_5V.SCL")
	(net 260 "/Compute module/Pf_5V.CEC")
	(net 261 "/Compute module/HDMI.CEC")
	(net 262 "/Compute module/HDMI.HPD")
	(net 263 "Net-(J502-CD2)")
	(net 264 "/Compute module/DSI0_C_N")
	(net 265 "/Compute module/DSI0_C_P")
	(net 266 "/Compute module/HDMI.SDA")
	(net 267 "/Compute module/HDMI.SCL")
	(net 268 "Net-(J502-CD1)")
	(net 269 "unconnected-(J601-Pad1)")
	(net 270 "unconnected-(J601-Pad2)")
	(net 271 "unconnected-(J601-Pad3)")
	(net 272 "unconnected-(J601-Pad4)")
	(net 273 "unconnected-(J601-Pad13)")
	(net 274 "/CSI/CamCtrl.VSYNC0")
	(net 275 "/CSI/CamCtrl.VSYNC1")
	(net 276 "Net-(U204-GPA3)")
	(net 277 "/USB/USBD.D_N")
	(net 278 "/USB/USBD.D_P")
	(net 279 "/Compute module/USB.OTGID")
	(net 280 "unconnected-(J601-Pad14)")
	(net 281 "/USB/EEDATA")
	(net 282 "/USB/EECLK")
	(net 283 "/USB/EECS")
	(net 284 "Net-(U204-GPB6)")
	(net 285 "/Compute module/NFC.EN")
	(net 286 "/Compute module/NFC.IRQ")
	(net 287 "/Compute module/NFC.DWL_REQ")
	(net 288 "/USB/USBA_OUT_EN")
	(net 289 "unconnected-(J601-Pad16)")
	(net 290 "unconnected-(J601-Pad17)")
	(net 291 "unconnected-(J601-Pad31)")
	(net 292 "unconnected-(J601-Pad33)")
	(net 293 "unconnected-(J601-Pad35)")
	(net 294 "unconnected-(J601-Pad36)")
	(net 295 "unconnected-(J601-Pad37)")
	(net 296 "unconnected-(J601-Pad38)")
	(net 297 "unconnected-(J601-Pad43)")
	(net 298 "unconnected-(J601-Pad44)")
	(net 299 "unconnected-(J601-Pad45)")
	(net 300 "unconnected-(J601-Pad46)")
	(net 301 "Net-(R705-R1.1)")
	(net 302 "Net-(R705-R2.1)")
	(net 303 "Net-(R705-R3.1)")
	(net 304 "Net-(R705-R4.1)")
	(net 305 "Net-(R706-R1.1)")
	(net 306 "Net-(R706-R2.1)")
	(net 307 "Net-(R706-R3.1)")
	(net 308 "Net-(R706-R4.1)")
	(net 309 "unconnected-(J701-Pad33)")
	(net 310 "unconnected-(J701-Pad34)")
	(net 311 "unconnected-(J701-Pad35)")
	(net 312 "unconnected-(J701-Pad36)")
	(net 313 "unconnected-(J701-Pad37)")
	(net 314 "unconnected-(J701-Pad38)")
	(net 315 "unconnected-(J701-Pad39)")
	(net 316 "unconnected-(J701-Pad40)")
	(net 317 "/Peripherals/VLED")
	(net 318 "unconnected-(J702-UTILITY{slash}HEAC+-Pad14)")
	(net 319 "Net-(J804-Pad1)")
	(net 320 "Net-(J804-Pad2)")
	(net 321 "unconnected-(J901-SBU_{2}-PadB8)")
	(net 322 "unconnected-(J901-SBU_{1}-PadA8)")
	(net 323 "unconnected-(J902-SBU_{2}-PadB8)")
	(net 324 "unconnected-(J902-SBU_{1}-PadA8)")
	(net 325 "Net-(U801-TX1)")
	(net 326 "Net-(U801-TX2)")
	(net 327 "Net-(Q201-D)")
	(net 328 "/Compute module/NFC.WKUP_REQ")
	(net 329 "Net-(Q207-G)")
	(net 330 "Net-(Q209-D)")
	(net 331 "Net-(Q210-D)")
	(net 332 "Net-(Q301-REF)")
	(net 333 "Net-(Q301-BIAS)")
	(net 334 "Net-(Q302-REF)")
	(net 335 "Net-(Q302-BIAS)")
	(net 336 "Net-(Q303-REF)")
	(net 337 "Net-(Q303-BIAS)")
	(net 338 "/USB/USBD_IN_EN")
	(net 339 "/Ethernet/POE_ACTIVE")
	(net 340 "Net-(U906-VBUS_DET)")
	(net 341 "Net-(Q902-G)")
	(net 342 "Net-(R211-Pad1)")
	(net 343 "/USB/EN_FTDI")
	(net 344 "/USB/FB_FTDI")
	(net 345 "Net-(U204-A2)")
	(net 346 "Net-(U204-A1)")
	(net 347 "/Compute module/ExpanderINT")
	(net 348 "Net-(U204-~{RESET})")
	(net 349 "Net-(U204-A0)")
	(net 350 "/Supply/EN_3V3")
	(net 351 "/Supply/EN_5V")
	(net 352 "Net-(U303-PG)")
	(net 353 "/Supply/FB_5V")
	(net 354 "/Supply/FB_M2")
	(net 355 "/Supply/FB_3V3")
	(net 356 "/Ethernet/AMPS_CTL")
	(net 357 "/Ethernet/REF")
	(net 358 "/Ethernet/MPS_DUTY")
	(net 359 "/Ethernet/CLSA")
	(net 360 "/Ethernet/CLSB")
	(net 361 "/Ethernet/DEN")
	(net 362 "/Ethernet/TPH")
	(net 363 "/Ethernet/PG")
	(net 364 "/Ethernet/TPL")
	(net 365 "/Ethernet/~{BT}")
	(net 366 "Net-(R418-Pad2)")
	(net 367 "Net-(R421-Pad1)")
	(net 368 "Net-(U403-TRIM)")
	(net 369 "/CSI/CamCtrl.EN")
	(net 370 "Net-(U601-FLG)")
	(net 371 "Net-(U602-FLG)")
	(net 372 "Net-(U601-ISET)")
	(net 373 "Net-(U602-ISET)")
	(net 374 "Net-(U801-I2C_ADR0)")
	(net 375 "Net-(U801-I2C_ADR1)")
	(net 376 "Net-(U901-ISET)")
	(net 377 "Net-(U902-DO)")
	(net 378 "Net-(U905-REF)")
	(net 379 "Net-(U905-~{RESET})")
	(net 380 "/Compute module/NVMe_EN")
	(net 381 "Net-(U801-DCDC_EN)")
	(net 382 "Net-(U801-CLK_REQ)")
	(net 383 "Net-(U801-V_{DD(HF)})")
	(net 384 "Net-(U905-GPIO6)")
	(net 385 "Net-(U905-GPIO7)")
	(net 386 "/Compute module/~{POE EN}")
	(net 387 "unconnected-(U204-NC-Pad7)")
	(net 388 "unconnected-(U204-NC-Pad10)")
	(net 389 "unconnected-(U204-INTB-Pad15)")
	(net 390 "unconnected-(U303-MODE-Pad4)")
	(net 391 "unconnected-(U303-FSEL-Pad5)")
	(net 392 "unconnected-(U303-SS{slash}TR-Pad10)")
	(net 393 "unconnected-(U401-~{AUTCLS}-Pad10)")
	(net 394 "unconnected-(U401-NC-Pad14)")
	(net 395 "unconnected-(U401-NC-Pad15)")
	(net 396 "unconnected-(U401-IRSHDL_EN-Pad16)")
	(net 397 "unconnected-(U401-NC-Pad20)")
	(net 398 "unconnected-(U801-IC-Pad11)")
	(net 399 "unconnected-(U801-NC-Pad32)")
	(net 400 "unconnected-(U801-NC-Pad33)")
	(net 401 "unconnected-(U801-NC-Pad34)")
	(net 402 "unconnected-(U801-NC-Pad35)")
	(net 403 "unconnected-(U801-NC-Pad36)")
	(net 404 "unconnected-(U801-IC-Pad38)")
	(net 405 "unconnected-(U901-FLG-Pad3)")
	(net 406 "unconnected-(U902-NC-Pad7)")
	(net 407 "unconnected-(S203-Pad3)")
	(net 408 "unconnected-(U905-DDBUS7-Pad57)")
	(net 409 "unconnected-(U905-DDBUS6-Pad56)")
	(net 410 "unconnected-(U905-DDBUS5-Pad53)")
	(net 411 "unconnected-(U905-DDBUS4-Pad52)")
	(net 412 "unconnected-(U905-DDBUS3-Pad51)")
	(net 413 "unconnected-(U905-DDBUS2-Pad50)")
	(net 414 "unconnected-(U905-CDBUS7-Pad44)")
	(net 415 "unconnected-(U905-CDBUS6-Pad43)")
	(net 416 "unconnected-(U905-CDBUS5-Pad42)")
	(net 417 "unconnected-(U905-CDBUS4-Pad40)")
	(net 418 "unconnected-(U905-CDBUS3-Pad39)")
	(net 419 "unconnected-(U905-CDBUS2-Pad38)")
	(net 420 "unconnected-(U905-VPP-Pad35)")
	(net 421 "unconnected-(U905-FSOURCE-Pad34)")
	(net 422 "unconnected-(U905-BDBUS7-Pad26)")
	(net 423 "unconnected-(U905-BDBUS6-Pad25)")
	(net 424 "unconnected-(U905-BDBUS4-Pad23)")
	(net 425 "unconnected-(U905-BDBUS3-Pad22)")
	(net 426 "unconnected-(U905-ADBUS7-Pad18)")
	(net 427 "unconnected-(U905-ADBUS6-Pad17)")
	(net 428 "unconnected-(U905-ADBUS5-Pad16)")
	(net 429 "unconnected-(U905-ADBUS4-Pad15)")
	(net 430 "unconnected-(U905-ADBUS3-Pad14)")
	(net 431 "unconnected-(U905-ADBUS2-Pad13)")
	(net 432 "Net-(U906-CURRENT_MODE)")
	(net 433 "Net-(U906-DIR)")
	(net 434 "Net-(U906-PORT)")
	(net 435 "Net-(U906-~{VCONN_FAULT})")
	(net 436 "Net-(U906-OUT1)")
	(net 437 "Net-(U906-OUT2)")
	(net 438 "Net-(U905-PD2_SVBUS)")
	(net 439 "Net-(U905-PD2_CC1)")
	(net 440 "Net-(U905-PD2_CC2)")
	(net 441 "Net-(U905-GPIO4)")
	(net 442 "Net-(U905-GPIO5)")
	(net 443 "/Supply/V_{BUS}")
	(net 444 "Net-(Q211-D)")
	(net 445 "Net-(D201-C)")
	(net 446 "/Compute module/GPIO.1{slash}SCL0")
	(net 447 "/Compute module/GPIO.0{slash}SDA0")
	(net 448 "Net-(U905-GPIO0)")
	(net 449 "Net-(U905-GPIO1)")
	(net 450 "Net-(U905-GPIO2)")
	(net 451 "/Display/CEC")
	(net 452 "/Display/SCL")
	(net 453 "/Display/SDA")
	(net 454 "/Display/HPD")
	(net 455 "Net-(Q905-D)")
	(net 456 "/USB/BDBUS0")
	(net 457 "/USB/BDBUS1")
	(net 458 "/USB/BDBUS2")
	(net 459 "unconnected-(U904-A4-Pad5)")
	(net 460 "unconnected-(U904-NC-Pad6)")
	(net 461 "unconnected-(U904-NC-Pad9)")
	(net 462 "unconnected-(U904-B4-Pad10)")
	(net 463 "/USB/I2C_EN")
	(net 464 "Net-(D709-C)")
	(net 465 "Net-(D205-C)")
	(net 466 "Net-(D206-C)")
	(net 467 "Net-(D202-C)")
	(net 468 "Net-(D202-A)")
	(net 469 "Net-(D207-C)")
	(net 470 "Net-(D503-C)")
	(net 471 "Net-(D910-C)")
	(net 472 "Net-(D301-C)")
	(net 473 "Net-(D302-A)")
	(net 474 "Net-(D304-A)")
	(net 475 "Net-(D305-A)")
	(net 476 "Net-(D306-A)")
	(net 477 "Net-(D404-A)")
	(net 478 "Net-(D503-A)")
	(net 479 "Net-(D601-A)")
	(net 480 "Net-(D602-A)")
	(net 481 "Net-(D710-A)")
	(net 482 "Net-(D905-A)")
	(net 483 "Net-(D906-A)")
	(net 484 "Net-(D907-A)")
	(net 485 "Net-(D908-C)")
	(net 486 "Net-(D911-C)")
	(net 487 "Net-(D911-A)")
	(net 488 "Net-(D912-C)")
	(net 489 "Net-(D912-A)")
	(net 490 "Net-(Q905-G)")
	(net 491 "Net-(Q206-G)")
	(net 492 "unconnected-(Q301-NC-Pad1)")
	(net 493 "unconnected-(Q301-NC-Pad5)")
	(net 494 "unconnected-(Q302-NC-Pad1)")
	(net 495 "unconnected-(Q302-NC-Pad5)")
	(net 496 "unconnected-(Q303-NC-Pad1)")
	(net 497 "unconnected-(Q303-NC-Pad5)")
	(net 498 "Net-(D906-C)")
	(net 499 "Net-(Q906-G)")
	(net 500 "Net-(Q214-D)")
	(net 501 "Net-(U801-V_{DD(UP)})")
	(net 502 "Net-(BT801-+)")
	(net 503 "Net-(D811-C)")
	(net 504 "unconnected-(U802-SQW{slash}OUT-Pad7)")
	(net 505 "Net-(U802-X1)")
	(net 506 "Net-(U802-X2)")
	(footprint "antmicro-footprints:R_0402_1005Metric"
		(layer "F.Cu")
		(at 140.137962 132.6765 180)
		(descr "Resistor SMD 0402")
		(tags "resistor SMD 0402")
		(property "Reference" "R239"
			(at 0.87 -0.54 0)
			(layer "F.SilkS")
			(effects
				(font
					(size 0.7 0.7)
					(thickness 0.15)
				)
				(justify right bottom)
			)
		)
		(property "Value" "R_0R_0402"
			(at -1.011843 1.772047 0)
			(layer "F.Fab")
			(effects
				(font
					(size 0.7 0.7)
					(thickness 0.15)
				)
				(justify right bottom)
			)
		)
		(property "Datasheet" "https://industrial.panasonic.com/cdbs/www-data/pdf/RDA0000/AOA0000C301.pdf"
			(at 0 0 180)
			(layer "F.Fab")
			(hide yes)
			(effects
				(font
					(size 1.27 1.27)
					(thickness 0.15)
				)
			)
		)
		(property "Manufacturer" "Panasonic"
			(at 0 0 180)
			(unlocked yes)
			(layer "F.Fab")
			(hide yes)
			(effects
				(font
					(size 1 1)
					(thickness 0.15)
				)
			)
		)
		(property "MPN" "ERJ2GE0R00X"
			(at 0 0 180)
			(unlocked yes)
			(layer "F.Fab")
			(hide yes)
			(effects
				(font
					(size 1 1)
					(thickness 0.15)
				)
			)
		)
		(property "Val" "0R"
			(at 0 0 180)
			(unlocked yes)
			(layer "F.Fab")
			(hide yes)
			(effects
				(font
					(size 1 1)
					(thickness 0.15)
				)
			)
		)
		(property "License" "Apache-2.0"
			(at 0 0 180)
			(unlocked yes)
			(layer "F.Fab")
			(hide yes)
			(effects
				(font
					(size 1 1)
					(thickness 0.15)
				)
			)
		)
		(property "Author" "Antmicro"
			(at 0 0 180)
			(unlocked yes)
			(layer "F.Fab")
			(hide yes)
			(effects
				(font
					(size 1 1)
					(thickness 0.15)
				)
			)
		)
		(property "Tolerance" "~"
			(at 0 0 180)
			(unlocked yes)
			(layer "F.Fab")
			(hide yes)
			(effects
				(font
					(size 1 1)
					(thickness 0.15)
				)
			)
		)
		(property "Current" "1A"
			(at 0 0 180)
			(unlocked yes)
			(layer "F.Fab")
			(hide yes)
			(effects
				(font
					(size 1 1)
					(thickness 0.15)
				)
			)
		)
		(sheetname "/Compute module/")
		(sheetfile "compute-module.kicad_sch")
		(attr smd)
		(fp_rect
			(start -0.925 -0.47)
			(end 0.925 0.47)
			(stroke
				(width 0.05)
				(type default)
			)
			(fill no)
			(layer "F.CrtYd")
		)
		(fp_rect
			(start -0.5 -0.25)
			(end 0.5 0.25)
			(stroke
				(width 0.15)
				(type solid)
			)
			(fill no)
			(layer "F.Fab")
		)
		(fp_text user "License: Apache-2.0"
			(at -0.95 5.169 180)
			(layer "F.Fab")
			(effects
				(font
					(size 0.7 0.7)
					(thickness 0.15)
				)
				(justify left bottom)
			)
		)
		(fp_text user "Author: Antmicro"
			(at -0.95 4.169 180)
			(layer "F.Fab")
			(effects
				(font
					(size 0.7 0.7)
					(thickness 0.15)
				)
				(justify left bottom)
			)
		)
		(fp_text user "${REFERENCE}"
			(at -0.95 3.168 180)
			(layer "F.Fab")
			(effects
				(font
					(size 0.7 0.7)
					(thickness 0.15)
				)
				(justify left bottom)
			)
		)
		(pad "1" smd roundrect
			(at -0.48 0 180)
			(size 0.59 0.64)
			(layers "F.Cu" "F.Mask" "F.Paste")
			(roundrect_rratio 0.25)
			(net 447 "/Compute module/GPIO.0{slash}SDA0")
			(pintype "passive")
		)
		(pad "2" smd roundrect
			(at 0.48 0 180)
			(size 0.59 0.64)
			(layers "F.Cu" "F.Mask" "F.Paste")
			(roundrect_rratio 0.25)
			(net 141 "/CSI/I_{2}C_CSI0.SDA")
			(pintype "passive")
		)
	)
	(footprint "antmicro-footprints:TP_SMD_0.75mm"
		(layer "F.Cu")
		(at 59.967962 170.9165)
		(property "Reference" "TP403"
			(at -3.85 0.45 0)
			(layer "F.SilkS")
			(effects
				(font
					(size 0.7 0.7)
					(thickness 0.15)
				)
				(justify left bottom)
			)
		)
		(property "Value" "TP_0.75mm_SMD"
			(at 0 1.2 0)
			(layer "F.Fab")
			(effects
				(font
					(size 0.7 0.7)
					(thickness 0.15)
				)
				(justify left bottom)
			)
		)
		(property "MPN" ""
			(at 0 0 0)
			(unlocked yes)
			(layer "F.Fab")
			(hide yes)
			(effects
				(font
					(size 1 1)
					(thickness 0.15)
				)
			)
		)
		(property "Manufacturer" ""
			(at 0 0 0)
			(unlocked yes)
			(layer "F.Fab")
			(hide yes)
			(effects
				(font
					(size 1 1)
					(thickness 0.15)
				)
			)
		)
		(property "Author" "Antmicro"
			(at 0 0 0)
			(unlocked yes)
			(layer "F.Fab")
			(hide yes)
			(effects
				(font
					(size 1 1)
					(thickness 0.15)
				)
			)
		)
		(property "License" "Apache-2.0"
			(at 0 0 0)
			(unlocked yes)
			(layer "F.Fab")
			(hide yes)
			(effects
				(font
					(size 1 1)
					(thickness 0.15)
				)
			)
		)
		(sheetname "/Ethernet/")
		(sheetfile "ethernet.kicad_sch")
		(attr exclude_from_pos_files exclude_from_bom)
		(fp_circle
			(center 0 0)
			(end 0.475 0)
			(stroke
				(width 0.05)
				(type default)
			)
			(fill no)
			(layer "F.CrtYd")
		)
		(fp_text user "Author: Antmicro"
			(at -0.4 3.901 0)
			(layer "F.Fab")
			(effects
				(font
					(size 0.7 0.7)
					(thickness 0.15)
				)
				(justify left bottom)
			)
		)
		(fp_text user "License: Apache-2.0"
			(at -0.4 5.101 0)
			(layer "F.Fab")
			(effects
				(font
					(size 0.7 0.7)
					(thickness 0.15)
				)
				(justify left bottom)
			)
		)
		(fp_text user "${REFERENCE}"
			(at -0.4 2.7 0)
			(layer "F.Fab")
			(effects
				(font
					(size 0.7 0.7)
					(thickness 0.15)
				)
				(justify left bottom)
			)
		)
		(pad "1" smd circle
			(at 0 0)
			(size 0.75 0.75)
			(layers "F.Cu" "F.Mask")
			(net 47 "/Ethernet/POE_12V")
			(pinfunction "1")
			(pintype "passive")
		)
	)
	(footprint "antmicro-footprints:R_0402_1005Metric"
		(layer "F.Cu")
		(at 73.4 162.05)
		(descr "Resistor SMD 0402")
		(tags "resistor SMD 0402")
		(property "Reference" "R327"
			(at -8.76 -1.08 0)
			(layer "F.SilkS")
			(effects
				(font
					(size 0.7 0.7)
					(thickness 0.15)
				)
				(justify left bottom)
			)
		)
		(property "Value" "R_470R_0402"
			(at -1.011843 1.772047 0)
			(layer "F.Fab")
			(effects
				(font
					(size 0.7 0.7)
					(thickness 0.15)
				)
				(justify left bottom)
			)
		)
		(property "Datasheet" "https://www.bourns.com/docs/product-datasheets/cr.pdf"
			(at 0 0 0)
			(layer "F.Fab")
			(hide yes)
			(effects
				(font
					(size 1.27 1.27)
					(thickness 0.15)
				)
			)
		)
		(property "Manufacturer" "Bourns"
			(at 0 0 0)
			(unlocked yes)
			(layer "F.Fab")
			(hide yes)
			(effects
				(font
					(size 1 1)
					(thickness 0.15)
				)
			)
		)
		(property "MPN" "CR0402-FX-4700GLF"
			(at 0 0 0)
			(unlocked yes)
			(layer "F.Fab")
			(hide yes)
			(effects
				(font
					(size 1 1)
					(thickness 0.15)
				)
			)
		)
		(property "Val" "470R"
			(at 0 0 0)
			(unlocked yes)
			(layer "F.Fab")
			(hide yes)
			(effects
				(font
					(size 1 1)
					(thickness 0.15)
				)
			)
		)
		(property "License" "Apache-2.0"
			(at 0 0 0)
			(unlocked yes)
			(layer "F.Fab")
			(hide yes)
			(effects
				(font
					(size 1 1)
					(thickness 0.15)
				)
			)
		)
		(property "Author" "Antmicro"
			(at 0 0 0)
			(unlocked yes)
			(layer "F.Fab")
			(hide yes)
			(effects
				(font
					(size 1 1)
					(thickness 0.15)
				)
			)
		)
		(property "Tolerance" "1%"
			(at 0 0 0)
			(unlocked yes)
			(layer "F.Fab")
			(hide yes)
			(effects
				(font
					(size 1 1)
					(thickness 0.15)
				)
			)
		)
		(sheetname "/Supply/")
		(sheetfile "supply.kicad_sch")
		(attr smd)
		(fp_rect
			(start -0.925 -0.47)
			(end 0.925 0.47)
			(stroke
				(width 0.05)
				(type default)
			)
			(fill no)
			(layer "F.CrtYd")
		)
		(fp_rect
			(start -0.5 -0.25)
			(end 0.5 0.25)
			(stroke
				(width 0.15)
				(type solid)
			)
			(fill no)
			(layer "F.Fab")
		)
		(fp_text user "License: Apache-2.0"
			(at -0.95 5.169 0)
			(layer "F.Fab")
			(effects
				(font
					(size 0.7 0.7)
					(thickness 0.15)
				)
				(justify left bottom)
			)
		)
		(fp_text user "${REFERENCE}"
			(at -0.95 3.168 0)
			(layer "F.Fab")
			(effects
				(font
					(size 0.7 0.7)
					(thickness 0.15)
				)
				(justify left bottom)
			)
		)
		(fp_text user "Author: Antmicro"
			(at -0.95 4.169 0)
			(layer "F.Fab")
			(effects
				(font
					(size 0.7 0.7)
					(thickness 0.15)
				)
				(justify left bottom)
			)
		)
		(pad "1" smd roundrect
			(at -0.48 0)
			(size 0.59 0.64)
			(layers "F.Cu" "F.Mask" "F.Paste")
			(roundrect_rratio 0.25)
			(net 476 "Net-(D306-A)")
			(pintype "passive")
		)
		(pad "2" smd roundrect
			(at 0.48 0)
			(size 0.59 0.64)
			(layers "F.Cu" "F.Mask" "F.Paste")
			(roundrect_rratio 0.25)
			(net 9 "+3V3")
			(pintype "passive")
		)
	)
	(footprint "antmicro-footprints:TP_SMD_0.75mm"
		(layer "F.Cu")
		(at 76.692962 167.2165 180)
		(property "Reference" "TP208"
			(at 8.865 0.96 0)
			(layer "F.SilkS")
			(effects
				(font
					(size 0.7 0.7)
					(thickness 0.15)
				)
				(justify right bottom)
			)
		)
		(property "Value" "TP_0.75mm_SMD"
			(at 0 1.2 0)
			(layer "F.Fab")
			(effects
				(font
					(size 0.7 0.7)
					(thickness 0.15)
				)
				(justify right bottom)
			)
		)
		(property "Author" "Antmicro"
			(at 0 0 180)
			(unlocked yes)
			(layer "F.Fab")
			(hide yes)
			(effects
				(font
					(size 1 1)
					(thickness 0.15)
				)
			)
		)
		(property "License" "Apache-2.0"
			(at 0 0 180)
			(unlocked yes)
			(layer "F.Fab")
			(hide yes)
			(effects
				(font
					(size 1 1)
					(thickness 0.15)
				)
			)
		)
		(property "MPN" ""
			(at 0 0 180)
			(unlocked yes)
			(layer "F.Fab")
			(hide yes)
			(effects
				(font
					(size 1 1)
					(thickness 0.15)
				)
			)
		)
		(property "Manufacturer" ""
			(at 0 0 180)
			(unlocked yes)
			(layer "F.Fab")
			(hide yes)
			(effects
				(font
					(size 1 1)
					(thickness 0.15)
				)
			)
		)
		(sheetname "/Compute module/")
		(sheetfile "compute-module.kicad_sch")
		(attr exclude_from_pos_files exclude_from_bom)
		(fp_circle
			(center 0 0)
			(end 0.475 0)
			(stroke
				(width 0.05)
				(type default)
			)
			(fill no)
			(layer "F.CrtYd")
		)
		(fp_text user "License: Apache-2.0"
			(at -0.4 5.101 180)
			(layer "F.Fab")
			(effects
				(font
					(size 0.7 0.7)
					(thickness 0.15)
				)
				(justify left bottom)
			)
		)
		(fp_text user "Author: Antmicro"
			(at -0.4 3.901 180)
			(layer "F.Fab")
			(effects
				(font
					(size 0.7 0.7)
					(thickness 0.15)
				)
				(justify left bottom)
			)
		)
		(fp_text user "${REFERENCE}"
			(at -0.4 2.7 180)
			(layer "F.Fab")
			(effects
				(font
					(size 0.7 0.7)
					(thickness 0.15)
				)
				(justify left bottom)
			)
		)
		(pad "1" smd circle
			(at 0 0 180)
			(size 0.75 0.75)
			(layers "F.Cu" "F.Mask")
			(net 255 "/Compute module/~{RPi_RST}")
			(pinfunction "1")
			(pintype "passive")
		)
	)
	(footprint "antmicro-footprints:SOT-23-3"
		(layer "F.Cu")
		(at 83.967962 157.1165 -90)
		(property "Reference" "Q212"
			(at 2.74 -1.36 180)
			(layer "F.SilkS")
			(effects
				(font
					(size 0.7 0.7)
					(thickness 0.15)
				)
				(justify right bottom)
			)
		)
		(property "Value" "SSM3J332R"
			(at -1.9 2.7 90)
			(layer "F.Fab")
			(effects
				(font
					(size 0.7 0.7)
					(thickness 0.15)
				)
				(justify right bottom)
			)
		)
		(property "Datasheet" "https://www.mouser.com/datasheet/2/408/SSM3J332R_datasheet_en_20181015-1150575.pdf"
			(at 0 0 270)
			(layer "F.Fab")
			(hide yes)
			(effects
				(font
					(size 1.27 1.27)
					(thickness 0.15)
				)
			)
		)
		(property "MPN" "SSM3J332R,LF"
			(at 0 0 270)
			(unlocked yes)
			(layer "F.Fab")
			(hide yes)
			(effects
				(font
					(size 1 1)
					(thickness 0.15)
				)
			)
		)
		(property "Manufacturer" "Toshiba"
			(at 0 0 270)
			(unlocked yes)
			(layer "F.Fab")
			(hide yes)
			(effects
				(font
					(size 1 1)
					(thickness 0.15)
				)
			)
		)
		(property "Author" "Antmicro"
			(at 0 0 270)
			(unlocked yes)
			(layer "F.Fab")
			(hide yes)
			(effects
				(font
					(size 1 1)
					(thickness 0.15)
				)
			)
		)
		(property "License" "Apache-2.0"
			(at 0 0 270)
			(unlocked yes)
			(layer "F.Fab")
			(hide yes)
			(effects
				(font
					(size 1 1)
					(thickness 0.15)
				)
			)
		)
		(sheetname "/Compute module/")
		(sheetfile "compute-module.kicad_sch")
		(attr smd)
		(fp_line
			(start -0.7 1.5)
			(end -0.7 1.35)
			(stroke
				(width 0.15)
				(type solid)
			)
			(layer "F.SilkS")
		)
		(fp_line
			(start 0.7 1.5)
			(end -0.7 1.5)
			(stroke
				(width 0.15)
				(type solid)
			)
			(layer "F.SilkS")
		)
		(fp_line
			(start 0.7 0.4)
			(end 0.7 1.5)
			(stroke
				(width 0.15)
				(type solid)
			)
			(layer "F.SilkS")
		)
		(fp_line
			(start 0.7 -0.4)
			(end 0.7 -1.5)
			(stroke
				(width 0.15)
				(type solid)
			)
			(layer "F.SilkS")
		)
		(fp_line
			(start -1.45 -1.35)
			(end -0.85 -1.35)
			(stroke
				(width 0.15)
				(type solid)
			)
			(layer "F.SilkS")
		)
		(fp_line
			(start -0.85 -1.35)
			(end -0.7 -1.5)
			(stroke
				(width 0.15)
				(type solid)
			)
			(layer "F.SilkS")
		)
		(fp_line
			(start 0.7 -1.5)
			(end -0.7 -1.5)
			(stroke
				(width 0.15)
				(type solid)
			)
			(layer "F.SilkS")
		)
		(fp_line
			(start -0.85 1.65)
			(end -0.85 1.4)
			(stroke
				(width 0.05)
				(type solid)
			)
			(layer "F.CrtYd")
		)
		(fp_line
			(start 0.85 1.65)
			(end -0.85 1.65)
			(stroke
				(width 0.05)
				(type solid)
			)
			(layer "F.CrtYd")
		)
		(fp_line
			(start -1.75 1.4)
			(end -1.75 0.5)
			(stroke
				(width 0.05)
				(type solid)
			)
			(layer "F.CrtYd")
		)
		(fp_line
			(start -0.85 1.4)
			(end -1.75 1.4)
			(stroke
				(width 0.05)
				(type solid)
			)
			(layer "F.CrtYd")
		)
		(fp_line
			(start -1.75 0.5)
			(end -0.85 0.5)
			(stroke
				(width 0.05)
				(type solid)
			)
			(layer "F.CrtYd")
		)
		(fp_line
			(start -0.85 0.5)
			(end -0.85 -0.5)
			(stroke
				(width 0.05)
				(type solid)
			)
			(layer "F.CrtYd")
		)
		(fp_line
			(start 0.85 0.45)
			(end 0.85 1.65)
			(stroke
				(width 0.05)
				(type solid)
			)
			(layer "F.CrtYd")
		)
		(fp_line
			(start 1.75 0.45)
			(end 0.85 0.45)
			(stroke
				(width 0.05)
				(type solid)
			)
			(layer "F.CrtYd")
		)
		(fp_line
			(start 0.825 -0.45)
			(end 1.75 -0.45)
			(stroke
				(width 0.05)
				(type solid)
			)
			(layer "F.CrtYd")
		)
		(fp_line
			(start 1.75 -0.45)
			(end 1.75 0.45)
			(stroke
				(width 0.05)
				(type solid)
			)
			(layer "F.CrtYd")
		)
		(fp_line
			(start -1.75 -0.5)
			(end -1.75 -1.4)
			(stroke
				(width 0.05)
				(type solid)
			)
			(layer "F.CrtYd")
		)
		(fp_line
			(start -0.85 -0.5)
			(end -1.75 -0.5)
			(stroke
				(width 0.05)
				(type solid)
			)
			(layer "F.CrtYd")
		)
		(fp_line
			(start -0.9 -1.4)
			(end -1.75 -1.4)
			(stroke
				(width 0.05)
				(type solid)
			)
			(layer "F.CrtYd")
		)
		(fp_line
			(start -0.9 -1.6)
			(end -0.9 -1.4)
			(stroke
				(width 0.05)
				(type solid)
			)
			(layer "F.CrtYd")
		)
		(fp_line
			(start -0.9 -1.6)
			(end 0.825 -1.6)
			(stroke
				(width 0.05)
				(type solid)
			)
			(layer "F.CrtYd")
		)
		(fp_line
			(start 0.825 -1.6)
			(end 0.825 -0.45)
			(stroke
				(width 0.05)
				(type solid)
			)
			(layer "F.CrtYd")
		)
		(fp_line
			(start -0.712 1.519)
			(end 0.688 1.519)
			(stroke
				(width 0.15)
				(type solid)
			)
			(layer "F.Fab")
		)
		(fp_line
			(start 0.688 1.519)
			(end 0.688 -1.52)
			(stroke
				(width 0.15)
				(type solid)
			)
			(layer "F.Fab")
		)
		(fp_line
			(start -0.712 -1.325)
			(end -0.712 1.523)
			(stroke
				(width 0.15)
				(type solid)
			)
			(layer "F.Fab")
		)
		(fp_line
			(start -0.437 -1.526)
			(end -0.712 -1.325)
			(stroke
				(width 0.15)
				(type solid)
			)
			(layer "F.Fab")
		)
		(fp_line
			(start -0.437 -1.526)
			(end 0.688 -1.526)
			(stroke
				(width 0.15)
				(type solid)
			)
			(layer "F.Fab")
		)
		(fp_text user "${REFERENCE}"
			(at -1.837 4 270)
			(layer "F.Fab")
			(effects
				(font
					(size 0.7 0.7)
					(thickness 0.15)
				)
				(justify left bottom)
			)
		)
		(fp_text user "License: Apache-2.0"
			(at -1.8 6.8 270)
			(layer "F.Fab")
			(effects
				(font
					(size 0.7 0.7)
					(thickness 0.15)
				)
				(justify left bottom)
			)
		)
		(fp_text user "Author: Antmicro"
			(at -1.837 5.3 270)
			(layer "F.Fab")
			(effects
				(font
					(size 0.7 0.7)
					(thickness 0.15)
				)
				(justify left bottom)
			)
		)
		(pad "1" smd roundrect
			(at -1.1 -0.951 270)
			(size 1 0.6)
			(layers "F.Cu" "F.Mask" "F.Paste")
			(roundrect_rratio 0.15)
			(net 444 "Net-(Q211-D)")
			(pinfunction "G")
			(pintype "input")
		)
		(pad "2" smd roundrect
			(at -1.1 0.949 270)
			(size 1 0.6)
			(layers "F.Cu" "F.Mask" "F.Paste")
			(roundrect_rratio 0.15)
			(net 24 "/Compute module/USBA_VBUS")
			(pinfunction "S")
			(pintype "passive")
		)
		(pad "3" smd roundrect
			(at 1.1 -0.0005 270)
			(size 1 0.6)
			(layers "F.Cu" "F.Mask" "F.Paste")
			(roundrect_rratio 0.15)
			(net 238 "/Compute module/GPIO.17")
			(pinfunction "D")
			(pintype "passive")
		)
	)
	(footprint "antmicro-footprints:R_0402_1005Metric"
		(layer "F.Cu")
		(at 46.547962 132.8365 180)
		(descr "Resistor SMD 0402")
		(tags "resistor SMD 0402")
		(property "Reference" "R403"
			(at 1.18 -0.38 0)
			(layer "F.SilkS")
			(effects
				(font
					(size 0.7 0.7)
					(thickness 0.15)
				)
				(justify right bottom)
			)
		)
		(property "Value" "R_0R_0402"
			(at -1.011843 1.772047 0)
			(layer "F.Fab")
			(effects
				(font
					(size 0.7 0.7)
					(thickness 0.15)
				)
				(justify right bottom)
			)
		)
		(property "Datasheet" "https://industrial.panasonic.com/cdbs/www-data/pdf/RDA0000/AOA0000C301.pdf"
			(at 0 0 180)
			(layer "F.Fab")
			(hide yes)
			(effects
				(font
					(size 1.27 1.27)
					(thickness 0.15)
				)
			)
		)
		(property "Manufacturer" "Panasonic"
			(at 0 0 180)
			(unlocked yes)
			(layer "F.Fab")
			(hide yes)
			(effects
				(font
					(size 1 1)
					(thickness 0.15)
				)
			)
		)
		(property "MPN" "ERJ2GE0R00X"
			(at 0 0 180)
			(unlocked yes)
			(layer "F.Fab")
			(hide yes)
			(effects
				(font
					(size 1 1)
					(thickness 0.15)
				)
			)
		)
		(property "Val" "0R"
			(at 0 0 180)
			(unlocked yes)
			(layer "F.Fab")
			(hide yes)
			(effects
				(font
					(size 1 1)
					(thickness 0.15)
				)
			)
		)
		(property "License" "Apache-2.0"
			(at 0 0 180)
			(unlocked yes)
			(layer "F.Fab")
			(hide yes)
			(effects
				(font
					(size 1 1)
					(thickness 0.15)
				)
			)
		)
		(property "Author" "Antmicro"
			(at 0 0 180)
			(unlocked yes)
			(layer "F.Fab")
			(hide yes)
			(effects
				(font
					(size 1 1)
					(thickness 0.15)
				)
			)
		)
		(property "Tolerance" "~"
			(at 0 0 180)
			(unlocked yes)
			(layer "F.Fab")
			(hide yes)
			(effects
				(font
					(size 1 1)
					(thickness 0.15)
				)
			)
		)
		(property "Current" "1A"
			(at 0 0 180)
			(unlocked yes)
			(layer "F.Fab")
			(hide yes)
			(effects
				(font
					(size 1 1)
					(thickness 0.15)
				)
			)
		)
		(sheetname "/Ethernet/")
		(sheetfile "ethernet.kicad_sch")
		(attr smd)
		(fp_rect
			(start -0.925 -0.47)
			(end 0.925 0.47)
			(stroke
				(width 0.05)
				(type default)
			)
			(fill no)
			(layer "F.CrtYd")
		)
		(fp_rect
			(start -0.5 -0.25)
			(end 0.5 0.25)
			(stroke
				(width 0.15)
				(type solid)
			)
			(fill no)
			(layer "F.Fab")
		)
		(fp_text user "Author: Antmicro"
			(at -0.95 4.169 180)
			(layer "F.Fab")
			(effects
				(font
					(size 0.7 0.7)
					(thickness 0.15)
				)
				(justify left bottom)
			)
		)
		(fp_text user "${REFERENCE}"
			(at -0.95 3.168 180)
			(layer "F.Fab")
			(effects
				(font
					(size 0.7 0.7)
					(thickness 0.15)
				)
				(justify left bottom)
			)
		)
		(fp_text user "License: Apache-2.0"
			(at -0.95 5.169 180)
			(layer "F.Fab")
			(effects
				(font
					(size 0.7 0.7)
					(thickness 0.15)
				)
				(justify left bottom)
			)
		)
		(pad "1" smd roundrect
			(at -0.48 0 180)
			(size 0.59 0.64)
			(layers "F.Cu" "F.Mask" "F.Paste")
			(roundrect_rratio 0.25)
			(net 358 "/Ethernet/MPS_DUTY")
			(pintype "passive")
		)
		(pad "2" smd roundrect
			(at 0.48 0 180)
			(size 0.59 0.64)
			(layers "F.Cu" "F.Mask" "F.Paste")
			(roundrect_rratio 0.25)
			(net 90 "/Ethernet/VSS")
			(pintype "passive")
		)
	)
	(footprint "antmicro-footprints:Switch_Slide_CAS-120TA"
		(layer "F.Cu")
		(at 141.577962 122.7665 -90)
		(property "Reference" "S203"
			(at -3.2665 -1.972038 90)
			(layer "F.SilkS")
			(effects
				(font
					(size 0.7 0.7)
					(thickness 0.15)
				)
				(justify right bottom)
			)
		)
		(property "Value" "CAS-120TA"
			(at 5.95 3.2 90)
			(layer "F.Fab")
			(effects
				(font
					(size 0.7 0.7)
					(thickness 0.15)
				)
				(justify right bottom)
			)
		)
		(property "Datasheet" "https://www.nidec-components.com/e/catalog/switch/cas.pdf"
			(at 0 0 270)
			(layer "F.Fab")
			(hide yes)
			(effects
				(font
					(size 1.27 1.27)
					(thickness 0.15)
				)
			)
		)
		(property "MPN" "CAS-120TA"
			(at 0 0 270)
			(unlocked yes)
			(layer "F.Fab")
			(hide yes)
			(effects
				(font
					(size 1 1)
					(thickness 0.15)
				)
			)
		)
		(property "Manufacturer" "Nidec Components"
			(at 0 0 270)
			(unlocked yes)
			(layer "F.Fab")
			(hide yes)
			(effects
				(font
					(size 1 1)
					(thickness 0.15)
				)
			)
		)
		(property "Author" "Antmicro"
			(at 0 0 270)
			(unlocked yes)
			(layer "F.Fab")
			(hide yes)
			(effects
				(font
					(size 1 1)
					(thickness 0.15)
				)
			)
		)
		(property "License" "Apache-2.0"
			(at 0 0 270)
			(unlocked yes)
			(layer "F.Fab")
			(hide yes)
			(effects
				(font
					(size 1 1)
					(thickness 0.15)
				)
			)
		)
		(sheetname "/Compute module/")
		(sheetfile "compute-module.kicad_sch")
		(attr smd)
		(fp_circle
			(center -3.502 1.148)
			(end -3.452 1.148)
			(stroke
				(width 0.15)
				(type solid)
			)
			(fill yes)
			(layer "F.SilkS")
		)
		(fp_rect
			(start -3.202 -1.901)
			(end 3.2 1.898)
			(stroke
				(width 0.05)
				(type solid)
			)
			(fill no)
			(layer "F.CrtYd")
		)
		(fp_line
			(start -2.9 1.148)
			(end 2.898 1.148)
			(stroke
				(width 0.15)
				(type solid)
			)
			(layer "F.Fab")
		)
		(fp_line
			(start -2.9 1.148)
			(end -2.9 -1.151)
			(stroke
				(width 0.15)
				(type solid)
			)
			(layer "F.Fab")
		)
		(fp_line
			(start 2.898 -1.151)
			(end 2.898 1.148)
			(stroke
				(width 0.15)
				(type solid)
			)
			(layer "F.Fab")
		)
		(fp_line
			(start 2.898 -1.151)
			(end -2.9 -1.151)
			(stroke
				(width 0.15)
				(type solid)
			)
			(layer "F.Fab")
		)
		(fp_text user "${REFERENCE}"
			(at -3.15 5.2 270)
			(layer "F.Fab")
			(effects
				(font
					(size 0.7 0.7)
					(thickness 0.15)
				)
				(justify left bottom)
			)
		)
		(fp_text user "License: Apache-2.0"
			(at -3.15 7.6 270)
			(layer "F.Fab")
			(effects
				(font
					(size 0.7 0.7)
					(thickness 0.15)
				)
				(justify left bottom)
			)
		)
		(fp_text user "Author: Antmicro"
			(at -3.15 6.4 270)
			(layer "F.Fab")
			(effects
				(font
					(size 0.7 0.7)
					(thickness 0.15)
				)
				(justify left bottom)
			)
		)
		(pad "1" smd rect
			(at -1.75 1.148 270)
			(size 1 1.6)
			(layers "F.Cu" "F.Mask" "F.Paste")
			(net 279 "/Compute module/USB.OTGID")
			(pintype "passive")
		)
		(pad "2" smd rect
			(at 0 -1.151 270)
			(size 1 1.6)
			(layers "F.Cu" "F.Mask" "F.Paste")
			(net 342 "Net-(R211-Pad1)")
			(pintype "passive")
		)
		(pad "3" smd rect
			(at 1.749 1.148 270)
			(size 1 1.6)
			(layers "F.Cu" "F.Mask" "F.Paste")
			(net 407 "unconnected-(S203-Pad3)")
			(pintype "passive+no_connect")
		)
	)
	(footprint "antmicro-footprints:R_0402_1005Metric"
		(layer "F.Cu")
		(at 54.817962 133.7265 180)
		(descr "Resistor SMD 0402")
		(tags "resistor SMD 0402")
		(property "Reference" "R417"
			(at -1.632038 5.2265 0)
			(layer "F.SilkS")
			(effects
				(font
					(size 0.7 0.7)
					(thickness 0.15)
				)
				(justify right bottom)
			)
		)
		(property "Value" "R_0R_0402"
			(at -1.011843 1.772047 0)
			(layer "F.Fab")
			(effects
				(font
					(size 0.7 0.7)
					(thickness 0.15)
				)
				(justify right bottom)
			)
		)
		(property "Datasheet" "https://industrial.panasonic.com/cdbs/www-data/pdf/RDA0000/AOA0000C301.pdf"
			(at 0 0 180)
			(layer "F.Fab")
			(hide yes)
			(effects
				(font
					(size 1.27 1.27)
					(thickness 0.15)
				)
			)
		)
		(property "Manufacturer" "Panasonic"
			(at 0 0 180)
			(unlocked yes)
			(layer "F.Fab")
			(hide yes)
			(effects
				(font
					(size 1 1)
					(thickness 0.15)
				)
			)
		)
		(property "MPN" "ERJ2GE0R00X"
			(at 0 0 180)
			(unlocked yes)
			(layer "F.Fab")
			(hide yes)
			(effects
				(font
					(size 1 1)
					(thickness 0.15)
				)
			)
		)
		(property "Val" "0R"
			(at 0 0 180)
			(unlocked yes)
			(layer "F.Fab")
			(hide yes)
			(effects
				(font
					(size 1 1)
					(thickness 0.15)
				)
			)
		)
		(property "License" "Apache-2.0"
			(at 0 0 180)
			(unlocked yes)
			(layer "F.Fab")
			(hide yes)
			(effects
				(font
					(size 1 1)
					(thickness 0.15)
				)
			)
		)
		(property "Author" "Antmicro"
			(at 0 0 180)
			(unlocked yes)
			(layer "F.Fab")
			(hide yes)
			(effects
				(font
					(size 1 1)
					(thickness 0.15)
				)
			)
		)
		(property "Tolerance" "~"
			(at 0 0 180)
			(unlocked yes)
			(layer "F.Fab")
			(hide yes)
			(effects
				(font
					(size 1 1)
					(thickness 0.15)
				)
			)
		)
		(property "Current" "1A"
			(at 0 0 180)
			(unlocked yes)
			(layer "F.Fab")
			(hide yes)
			(effects
				(font
					(size 1 1)
					(thickness 0.15)
				)
			)
		)
		(sheetname "/Ethernet/")
		(sheetfile "ethernet.kicad_sch")
		(attr smd exclude_from_pos_files exclude_from_bom dnp)
		(fp_rect
			(start -0.925 -0.47)
			(end 0.925 0.47)
			(stroke
				(width 0.05)
				(type default)
			)
			(fill no)
			(layer "F.CrtYd")
		)
		(fp_rect
			(start -0.5 -0.25)
			(end 0.5 0.25)
			(stroke
				(width 0.15)
				(type solid)
			)
			(fill no)
			(layer "F.Fab")
		)
		(fp_text user "License: Apache-2.0"
			(at -0.95 5.169 180)
			(layer "F.Fab")
			(effects
				(font
					(size 0.7 0.7)
					(thickness 0.15)
				)
				(justify left bottom)
			)
		)
		(fp_text user "Author: Antmicro"
			(at -0.95 4.169 180)
			(layer "F.Fab")
			(effects
				(font
					(size 0.7 0.7)
					(thickness 0.15)
				)
				(justify left bottom)
			)
		)
		(fp_text user "${REFERENCE}"
			(at -0.95 3.168 180)
			(layer "F.Fab")
			(effects
				(font
					(size 0.7 0.7)
					(thickness 0.15)
				)
				(justify left bottom)
			)
		)
		(pad "1" smd roundrect
			(at -0.48 0 180)
			(size 0.59 0.64)
			(layers "F.Cu" "F.Mask" "F.Paste")
			(roundrect_rratio 0.25)
			(net 126 "/Ethernet/ULS-12_CTRL")
			(pintype "passive")
		)
		(pad "2" smd roundrect
			(at 0.48 0 180)
			(size 0.59 0.64)
			(layers "F.Cu" "F.Mask" "F.Paste")
			(roundrect_rratio 0.25)
			(net 339 "/Ethernet/POE_ACTIVE")
			(pintype "passive")
		)
	)
	(footprint "antmicro-footprints:C_0402_1005Metric"
		(layer "F.Cu")
		(at 61.117962 177.6915 -90)
		(descr "Capacitor SMD 0402")
		(tags "capacitor SMD 0402")
		(property "Reference" "C826"
			(at -2.805 14.88 90)
			(layer "F.SilkS")
			(effects
				(font
					(size 0.7 0.7)
					(thickness 0.15)
				)
				(justify right bottom)
			)
		)
		(property "Value" "C_template_name_0402"
			(at -1.022927 2.155213 90)
			(layer "F.Fab")
			(effects
				(font
					(size 0.7 0.7)
					(thickness 0.15)
				)
				(justify right bottom)
			)
		)
		(property "Datasheet" "template_datasheet"
			(at 0 0 270)
			(layer "F.Fab")
			(hide yes)
			(effects
				(font
					(size 1.27 1.27)
					(thickness 0.15)
				)
			)
		)
		(property "MPN" "template_MPN"
			(at 0 0 270)
			(unlocked yes)
			(layer "F.Fab")
			(hide yes)
			(effects
				(font
					(size 1 1)
					(thickness 0.15)
				)
			)
		)
		(property "Manufacturer" "template_manufacturer"
			(at 0 0 270)
			(unlocked yes)
			(layer "F.Fab")
			(hide yes)
			(effects
				(font
					(size 1 1)
					(thickness 0.15)
				)
			)
		)
		(property "License" "Apache-2.0"
			(at 0 0 270)
			(unlocked yes)
			(layer "F.Fab")
			(hide yes)
			(effects
				(font
					(size 1 1)
					(thickness 0.15)
				)
			)
		)
		(property "Author" "Antmicro"
			(at 0 0 270)
			(unlocked yes)
			(layer "F.Fab")
			(hide yes)
			(effects
				(font
					(size 1 1)
					(thickness 0.15)
				)
			)
		)
		(property "Val" "template_value"
			(at 0 0 270)
			(unlocked yes)
			(layer "F.Fab")
			(hide yes)
			(effects
				(font
					(size 1 1)
					(thickness 0.15)
				)
			)
		)
		(property "Voltage" "template_voltage"
			(at 0 0 270)
			(unlocked yes)
			(layer "F.Fab")
			(hide yes)
			(effects
				(font
					(size 1 1)
					(thickness 0.15)
				)
			)
		)
		(property "Dielectric" "template_dielectric"
			(at 0 0 270)
			(unlocked yes)
			(layer "F.Fab")
			(hide yes)
			(effects
				(font
					(size 1 1)
					(thickness 0.15)
				)
			)
		)
		(sheetname "/Peripherals/")
		(sheetfile "peripherals.kicad_sch")
		(attr smd exclude_from_pos_files exclude_from_bom dnp)
		(fp_rect
			(start -0.925 -0.47)
			(end 0.925 0.47)
			(stroke
				(width 0.05)
				(type default)
			)
			(fill no)
			(layer "F.CrtYd")
		)
		(fp_line
			(start -0.494 0.248)
			(end -0.494 -0.25)
			(stroke
				(width 0.15)
				(type solid)
			)
			(layer "F.Fab")
		)
		(fp_line
			(start 0.504 0.248)
			(end -0.494 0.248)
			(stroke
				(width 0.15)
				(type solid)
			)
			(layer "F.Fab")
		)
		(fp_line
			(start -0.494 -0.25)
			(end 0.504 -0.25)
			(stroke
				(width 0.15)
				(type solid)
			)
			(layer "F.Fab")
		)
		(fp_line
			(start 0.504 -0.25)
			(end 0.504 0.248)
			(stroke
				(width 0.15)
				(type solid)
			)
			(layer "F.Fab")
		)
		(fp_text user "License: Apache-2.0"
			(at -0.939 5.799 270)
			(layer "F.Fab")
			(effects
				(font
					(size 0.7 0.7)
					(thickness 0.15)
				)
				(justify left bottom)
			)
		)
		(fp_text user "Author: Antmicro"
			(at -0.939 3.399 270)
			(layer "F.Fab")
			(effects
				(font
					(size 0.7 0.7)
					(thickness 0.15)
				)
				(justify left bottom)
			)
		)
		(fp_text user "${REFERENCE}"
			(at -0.939 4.599 270)
			(layer "F.Fab")
			(effects
				(font
					(size 0.7 0.7)
					(thickness 0.15)
				)
				(justify left bottom)
			)
		)
		(pad "1" smd roundrect
			(at -0.48 0 270)
			(size 0.59 0.64)
			(layers "F.Cu" "F.Mask" "F.Paste")
			(roundrect_rratio 0.25)
			(net 3 "GND")
			(pintype "passive")
		)
		(pad "2" smd roundrect
			(at 0.48 0 270)
			(size 0.59 0.64)
			(layers "F.Cu" "F.Mask" "F.Paste")
			(roundrect_rratio 0.25)
			(net 100 "Net-(C811-Pad2)")
			(pintype "passive")
		)
	)
	(footprint "antmicro-footprints:UQFN-12_2x1.7mm_P0.4mm_Texas_RUT"
		(layer "F.Cu")
		(at 89.192962 152.3165 90)
		(descr "Texas_R_PUQFN-N12")
		(tags "Texas_R_PUQFN-N12")
		(property "Reference" "U203"
			(at 1.22 -1.445 180)
			(layer "F.SilkS")
			(effects
				(font
					(size 0.7 0.7)
					(thickness 0.15)
				)
				(justify left bottom)
			)
		)
		(property "Value" "TXB0104_UQFN"
			(at 0 2.35 90)
			(layer "F.Fab")
			(effects
				(font
					(size 0.7 0.7)
					(thickness 0.15)
				)
				(justify left bottom)
			)
		)
		(property "Datasheet" "http://www.ti.com/lit/ds/symlink/txb0104.pdf"
			(at 0 0 90)
			(layer "F.Fab")
			(hide yes)
			(effects
				(font
					(size 1.27 1.27)
					(thickness 0.15)
				)
			)
		)
		(property "Manufacturer" "Texas Instruments"
			(at 0 0 90)
			(unlocked yes)
			(layer "F.Fab")
			(hide yes)
			(effects
				(font
					(size 1 1)
					(thickness 0.15)
				)
			)
		)
		(property "MPN" "TXB0104RUTR"
			(at 0 0 90)
			(unlocked yes)
			(layer "F.Fab")
			(hide yes)
			(effects
				(font
					(size 1 1)
					(thickness 0.15)
				)
			)
		)
		(property "Author" "Antmicro"
			(at 0 0 90)
			(unlocked yes)
			(layer "F.Fab")
			(hide yes)
			(effects
				(font
					(size 1 1)
					(thickness 0.15)
				)
			)
		)
		(property "License" "Apache-2.0"
			(at 0 0 90)
			(unlocked yes)
			(layer "F.Fab")
			(hide yes)
			(effects
				(font
					(size 1 1)
					(thickness 0.15)
				)
			)
		)
		(property ki_fp_filters "Texas*R*PUQFN*N12*")
		(sheetname "/Compute module/")
		(sheetfile "compute-module.kicad_sch")
		(attr smd)
		(fp_line
			(start 0.597 -1.301)
			(end -0.55 -1.301)
			(stroke
				(width 0.15)
				(type solid)
			)
			(layer "F.SilkS")
		)
		(fp_line
			(start 0.497 1.3)
			(end -0.5 1.3)
			(stroke
				(width 0.15)
				(type solid)
			)
			(layer "F.SilkS")
		)
		(fp_circle
			(center -0.85 -1.2)
			(end -0.8 -1.2)
			(stroke
				(width 0.15)
				(type solid)
			)
			(fill yes)
			(layer "F.SilkS")
		)
		(fp_rect
			(start -1.1 -1.3)
			(end 1.1 1.3)
			(stroke
				(width 0.05)
				(type solid)
			)
			(fill no)
			(layer "F.CrtYd")
		)
		(fp_line
			(start 0.847 -1)
			(end 0.847 0.997)
			(stroke
				(width 0.15)
				(type solid)
			)
			(layer "F.Fab")
		)
		(fp_line
			(start -0.5 -1)
			(end 0.847 -1)
			(stroke
				(width 0.15)
				(type solid)
			)
			(layer "F.Fab")
		)
		(fp_line
			(start -0.5 -1)
			(end -0.85 -0.5)
			(stroke
				(width 0.15)
				(type solid)
			)
			(layer "F.Fab")
		)
		(fp_line
			(start 0.847 0.997)
			(end -0.85 0.997)
			(stroke
				(width 0.15)
				(type solid)
			)
			(layer "F.Fab")
		)
		(fp_line
			(start -0.85 0.997)
			(end -0.85 -0.5)
			(stroke
				(width 0.15)
				(type solid)
			)
			(layer "F.Fab")
		)
		(fp_text user "Author: Antmicro"
			(at -1.1 4.35 90)
			(layer "F.Fab")
			(effects
				(font
					(size 0.7 0.7)
					(thickness 0.15)
				)
				(justify left bottom)
			)
		)
		(fp_text user "License: Apache-2.0"
			(at -1.1 6.75 90)
			(layer "F.Fab")
			(effects
				(font
					(size 0.7 0.7)
					(thickness 0.15)
				)
				(justify left bottom)
			)
		)
		(fp_text user "${REFERENCE}"
			(at -1.1 5.55 90)
			(layer "F.Fab")
			(effects
				(font
					(size 0.7 0.7)
					(thickness 0.15)
				)
				(justify left bottom)
			)
		)
		(pad "1" smd rect
			(at -0.653 -0.803)
			(size 0.2 0.6)
			(layers "F.Cu" "F.Mask" "F.Paste")
			(net 18 "V_{IO}")
			(pinfunction "VCCA")
			(pintype "power_in")
		)
		(pad "1" smd rect
			(at -0.425 -0.975 90)
			(size 0.15 0.25)
			(layers "F.Cu" "F.Mask" "F.Paste")
			(net 18 "V_{IO}")
			(pinfunction "VCCA")
			(pintype "power_in")
		)
		(pad "2" smd rect
			(at -0.653 -0.403)
			(size 0.2 0.6)
			(layers "F.Cu" "F.Mask" "F.Paste")
			(net 239 "/Compute module/GPIO.14{slash}RXD0")
			(pinfunction "A1")
			(pintype "tri_state")
		)
		(pad "3" smd rect
			(at -0.653 0)
			(size 0.2 0.6)
			(layers "F.Cu" "F.Mask" "F.Paste")
			(net 241 "/Compute module/GPIO.15{slash}TXD0")
			(pinfunction "A2")
			(pintype "tri_state")
		)
		(pad "4" smd rect
			(at -0.653 0.4)
			(size 0.2 0.6)
			(layers "F.Cu" "F.Mask" "F.Paste")
			(net 224 "/Compute module/GPIO.12{slash}RXD5")
			(pinfunction "A3")
			(pintype "tri_state")
		)
		(pad "5" smd rect
			(at -0.653 0.8)
			(size 0.2 0.6)
			(layers "F.Cu" "F.Mask" "F.Paste")
			(net 221 "/Compute module/GPIO.13{slash}TXD5")
			(pinfunction "A4")
			(pintype "tri_state")
		)
		(pad "6" smd rect
			(at 0 0.8)
			(size 0.6 0.2)
			(layers "F.Cu" "F.Mask" "F.Paste")
			(net 3 "GND")
			(pinfunction "GND")
			(pintype "power_in")
		)
		(pad "7" smd rect
			(at 0.65 0.8)
			(size 0.2 0.6)
			(layers "F.Cu" "F.Mask" "F.Paste")
			(net 186 "/Compute module/UART.1.TX")
			(pinfunction "B4")
			(pintype "tri_state")
		)
		(pad "8" smd rect
			(at 0.65 0.4)
			(size 0.2 0.6)
			(layers "F.Cu" "F.Mask" "F.Paste")
			(net 187 "/Compute module/UART.1.RX")
			(pinfunction "B3")
			(pintype "tri_state")
		)
		(pad "9" smd rect
			(at 0.65 0)
			(size 0.2 0.6)
			(layers "F.Cu" "F.Mask" "F.Paste")
			(net 37 "/Compute module/UART.0.TX")
			(pinfunction "B2")
			(pintype "tri_state")
		)
		(pad "10" smd rect
			(at 0.65 -0.403)
			(size 0.2 0.6)
			(layers "F.Cu" "F.Mask" "F.Paste")
			(net 36 "/Compute module/UART.0.RX")
			(pinfunction "B1")
			(pintype "tri_state")
		)
		(pad "11" smd rect
			(at 0.65 -0.803)
			(size 0.2 0.6)
			(layers "F.Cu" "F.Mask" "F.Paste")
			(net 9 "+3V3")
			(pinfunction "VCCB")
			(pintype "power_in")
		)
		(pad "12" smd rect
			(at 0 -0.803)
			(size 0.6 0.2)
			(layers "F.Cu" "F.Mask" "F.Paste")
			(net 18 "V_{IO}")
			(pinfunction "OE")
			(pintype "input")
		)
	)
	(footprint "antmicro-footprints:C_0402_1005Metric"
		(layer "F.Cu")
		(at 95.897962 121.7165)
		(descr "Capacitor SMD 0402")
		(tags "capacitor SMD 0402")
		(property "Reference" "C901"
			(at 24.885 25.855 0)
			(layer "F.SilkS")
			(effects
				(font
					(size 0.7 0.7)
					(thickness 0.15)
				)
				(justify left bottom)
			)
		)
		(property "Value" "C_100n_0402"
			(at -1.022927 2.155213 0)
			(layer "F.Fab")
			(effects
				(font
					(size 0.7 0.7)
					(thickness 0.15)
				)
				(justify left bottom)
			)
		)
		(property "Datasheet" "https://www.murata.com/products/productdetail?partno=GRM155R61H104KE14%23"
			(at 0 0 0)
			(layer "F.Fab")
			(hide yes)
			(effects
				(font
					(size 1.27 1.27)
					(thickness 0.15)
				)
			)
		)
		(property "Manufacturer" "Murata"
			(at 0 0 0)
			(unlocked yes)
			(layer "F.Fab")
			(hide yes)
			(effects
				(font
					(size 1 1)
					(thickness 0.15)
				)
			)
		)
		(property "MPN" "GRM155R61H104KE14D"
			(at 0 0 0)
			(unlocked yes)
			(layer "F.Fab")
			(hide yes)
			(effects
				(font
					(size 1 1)
					(thickness 0.15)
				)
			)
		)
		(property "Val" "100n"
			(at 0 0 0)
			(unlocked yes)
			(layer "F.Fab")
			(hide yes)
			(effects
				(font
					(size 1 1)
					(thickness 0.15)
				)
			)
		)
		(property "License" "Apache-2.0"
			(at 0 0 0)
			(unlocked yes)
			(layer "F.Fab")
			(hide yes)
			(effects
				(font
					(size 1 1)
					(thickness 0.15)
				)
			)
		)
		(property "Author" "Antmicro"
			(at 0 0 0)
			(unlocked yes)
			(layer "F.Fab")
			(hide yes)
			(effects
				(font
					(size 1 1)
					(thickness 0.15)
				)
			)
		)
		(property "Voltage" "50V"
			(at 0 0 0)
			(unlocked yes)
			(layer "F.Fab")
			(hide yes)
			(effects
				(font
					(size 1 1)
					(thickness 0.15)
				)
			)
		)
		(property "Dielectric" "X5R"
			(at 0 0 0)
			(unlocked yes)
			(layer "F.Fab")
			(hide yes)
			(effects
				(font
					(size 1 1)
					(thickness 0.15)
				)
			)
		)
		(sheetname "/USB/")
		(sheetfile "usb.kicad_sch")
		(attr smd)
		(fp_rect
			(start -0.925 -0.47)
			(end 0.925 0.47)
			(stroke
				(width 0.05)
				(type default)
			)
			(fill no)
			(layer "F.CrtYd")
		)
		(fp_line
			(start -0.494 -0.25)
			(end 0.504 -0.25)
			(stroke
				(width 0.15)
				(type solid)
			)
			(layer "F.Fab")
		)
		(fp_line
			(start -0.494 0.248)
			(end -0.494 -0.25)
			(stroke
				(width 0.15)
				(type solid)
			)
			(layer "F.Fab")
		)
		(fp_line
			(start 0.504 -0.25)
			(end 0.504 0.248)
			(stroke
				(width 0.15)
				(type solid)
			)
			(layer "F.Fab")
		)
		(fp_line
			(start 0.504 0.248)
			(end -0.494 0.248)
			(stroke
				(width 0.15)
				(type solid)
			)
			(layer "F.Fab")
		)
		(fp_text user "${REFERENCE}"
			(at -0.939 4.599 0)
			(layer "F.Fab")
			(effects
				(font
					(size 0.7 0.7)
					(thickness 0.15)
				)
				(justify left bottom)
			)
		)
		(fp_text user "Author: Antmicro"
			(at -0.939 3.399 0)
			(layer "F.Fab")
			(effects
				(font
					(size 0.7 0.7)
					(thickness 0.15)
				)
				(justify left bottom)
			)
		)
		(fp_text user "License: Apache-2.0"
			(at -0.939 5.799 0)
			(layer "F.Fab")
			(effects
				(font
					(size 0.7 0.7)
					(thickness 0.15)
				)
				(justify left bottom)
			)
		)
		(pad "1" smd roundrect
			(at -0.48 0)
			(size 0.59 0.64)
			(layers "F.Cu" "F.Mask" "F.Paste")
			(roundrect_rratio 0.25)
			(net 24 "/Compute module/USBA_VBUS")
			(pintype "passive")
		)
		(pad "2" smd roundrect
			(at 0.48 0)
			(size 0.59 0.64)
			(layers "F.Cu" "F.Mask" "F.Paste")
			(roundrect_rratio 0.25)
			(net 3 "GND")
			(pintype "passive")
		)
	)
	(footprint "antmicro-footprints:C_0402_1005Metric"
		(layer "F.Cu")
		(at 95.897962 122.6565 180)
		(descr "Capacitor SMD 0402")
		(tags "capacitor SMD 0402")
		(property "Reference" "C908"
			(at -27.635 -25.995 0)
			(layer "F.SilkS")
			(effects
				(font
					(size 0.7 0.7)
					(thickness 0.15)
				)
				(justify right bottom)
			)
		)
		(property "Value" "C_10u_0402"
			(at -1.022927 2.155213 0)
			(layer "F.Fab")
			(effects
				(font
					(size 0.7 0.7)
					(thickness 0.15)
				)
				(justify right bottom)
			)
		)
		(property "Datasheet" "https://www.yageo.com/en/Chart/Download/pdf/CC0402MRX5R5BB106"
			(at 0 0 180)
			(layer "F.Fab")
			(hide yes)
			(effects
				(font
					(size 1.27 1.27)
					(thickness 0.15)
				)
			)
		)
		(property "MPN" "CC0402MRX5R5BB106"
			(at 0 0 180)
			(unlocked yes)
			(layer "F.Fab")
			(hide yes)
			(effects
				(font
					(size 1 1)
					(thickness 0.15)
				)
			)
		)
		(property "Manufacturer" "YAGEO"
			(at 0 0 180)
			(unlocked yes)
			(layer "F.Fab")
			(hide yes)
			(effects
				(font
					(size 1 1)
					(thickness 0.15)
				)
			)
		)
		(property "License" "Apache-2.0"
			(at 0 0 180)
			(unlocked yes)
			(layer "F.Fab")
			(hide yes)
			(effects
				(font
					(size 1 1)
					(thickness 0.15)
				)
			)
		)
		(property "Author" "Antmicro"
			(at 0 0 180)
			(unlocked yes)
			(layer "F.Fab")
			(hide yes)
			(effects
				(font
					(size 1 1)
					(thickness 0.15)
				)
			)
		)
		(property "Val" "10u"
			(at 0 0 180)
			(unlocked yes)
			(layer "F.Fab")
			(hide yes)
			(effects
				(font
					(size 1 1)
					(thickness 0.15)
				)
			)
		)
		(property "Voltage" ""
			(at 0 0 180)
			(unlocked yes)
			(layer "F.Fab")
			(hide yes)
			(effects
				(font
					(size 1 1)
					(thickness 0.15)
				)
			)
		)
		(property "Dielectric" ""
			(at 0 0 180)
			(unlocked yes)
			(layer "F.Fab")
			(hide yes)
			(effects
				(font
					(size 1 1)
					(thickness 0.15)
				)
			)
		)
		(sheetname "/USB/")
		(sheetfile "usb.kicad_sch")
		(attr smd)
		(fp_rect
			(start -0.925 -0.47)
			(end 0.925 0.47)
			(stroke
				(width 0.05)
				(type default)
			)
			(fill no)
			(layer "F.CrtYd")
		)
		(fp_line
			(start 0.504 0.248)
			(end -0.494 0.248)
			(stroke
				(width 0.15)
				(type solid)
			)
			(layer "F.Fab")
		)
		(fp_line
			(start 0.504 -0.25)
			(end 0.504 0.248)
			(stroke
				(width 0.15)
				(type solid)
			)
			(layer "F.Fab")
		)
		(fp_line
			(start -0.494 0.248)
			(end -0.494 -0.25)
			(stroke
				(width 0.15)
				(type solid)
			)
			(layer "F.Fab")
		)
		(fp_line
			(start -0.494 -0.25)
			(end 0.504 -0.25)
			(stroke
				(width 0.15)
				(type solid)
			)
			(layer "F.Fab")
		)
		(fp_text user "Author: Antmicro"
			(at -0.939 3.399 180)
			(layer "F.Fab")
			(effects
				(font
					(size 0.7 0.7)
					(thickness 0.15)
				)
				(justify left bottom)
			)
		)
		(fp_text user "License: Apache-2.0"
			(at -0.939 5.799 180)
			(layer "F.Fab")
			(effects
				(font
					(size 0.7 0.7)
					(thickness 0.15)
				)
				(justify left bottom)
			)
		)
		(fp_text user "${REFERENCE}"
			(at -0.939 4.599 180)
			(layer "F.Fab")
			(effects
				(font
					(size 0.7 0.7)
					(thickness 0.15)
				)
				(justify left bottom)
			)
		)
		(pad "1" smd roundrect
			(at -0.48 0 180)
			(size 0.59 0.64)
			(layers "F.Cu" "F.Mask" "F.Paste")
			(roundrect_rratio 0.25)
			(net 3 "GND")
			(pintype "passive")
		)
		(pad "2" smd roundrect
			(at 0.48 0 180)
			(size 0.59 0.64)
			(layers "F.Cu" "F.Mask" "F.Paste")
			(roundrect_rratio 0.25)
			(net 24 "/Compute module/USBA_VBUS")
			(pintype "passive")
		)
	)
	(footprint "antmicro-footprints:TP_SMD_0.75mm"
		(layer "F.Cu")
		(at 53.4 127.45)
		(property "Reference" "TP401"
			(at -0.2 -0.8 90)
			(layer "F.SilkS")
			(effects
				(font
					(size 0.7 0.7)
					(thickness 0.15)
				)
				(justify left bottom)
			)
		)
		(property "Value" "TP_0.75mm_SMD"
			(at 0 1.2 0)
			(layer "F.Fab")
			(effects
				(font
					(size 0.7 0.7)
					(thickness 0.15)
				)
				(justify left bottom)
			)
		)
		(property "MPN" ""
			(at 0 0 0)
			(unlocked yes)
			(layer "F.Fab")
			(hide yes)
			(effects
				(font
					(size 1 1)
					(thickness 0.15)
				)
			)
		)
		(property "Manufacturer" ""
			(at 0 0 0)
			(unlocked yes)
			(layer "F.Fab")
			(hide yes)
			(effects
				(font
					(size 1 1)
					(thickness 0.15)
				)
			)
		)
		(property "Author" "Antmicro"
			(at 0 0 0)
			(unlocked yes)
			(layer "F.Fab")
			(hide yes)
			(effects
				(font
					(size 1 1)
					(thickness 0.15)
				)
			)
		)
		(property "License" "Apache-2.0"
			(at 0 0 0)
			(unlocked yes)
			(layer "F.Fab")
			(hide yes)
			(effects
				(font
					(size 1 1)
					(thickness 0.15)
				)
			)
		)
		(sheetname "/Ethernet/")
		(sheetfile "ethernet.kicad_sch")
		(attr exclude_from_pos_files exclude_from_bom)
		(fp_circle
			(center 0 0)
			(end 0.475 0)
			(stroke
				(width 0.05)
				(type default)
			)
			(fill no)
			(layer "F.CrtYd")
		)
		(fp_text user "License: Apache-2.0"
			(at -0.4 5.101 0)
			(layer "F.Fab")
			(effects
				(font
					(size 0.7 0.7)
					(thickness 0.15)
				)
				(justify left bottom)
			)
		)
		(fp_text user "${REFERENCE}"
			(at -0.4 2.7 0)
			(layer "F.Fab")
			(effects
				(font
					(size 0.7 0.7)
					(thickness 0.15)
				)
				(justify left bottom)
			)
		)
		(fp_text user "Author: Antmicro"
			(at -0.4 3.901 0)
			(layer "F.Fab")
			(effects
				(font
					(size 0.7 0.7)
					(thickness 0.15)
				)
				(justify left bottom)
			)
		)
		(pad "1" smd circle
			(at 0 0)
			(size 0.75 0.75)
			(layers "F.Cu" "F.Mask")
			(net 33 "/Ethernet/VDD")
			(pinfunction "1")
			(pintype "passive")
		)
	)
	(footprint "antmicro-footprints:R_0402_1005Metric"
		(layer "F.Cu")
		(at 76.197962 147.1165 180)
		(descr "Resistor SMD 0402")
		(tags "resistor SMD 0402")
		(property "Reference" "R210"
			(at -1.22 4.95 180)
			(layer "F.SilkS")
			(effects
				(font
					(size 0.7 0.7)
					(thickness 0.15)
				)
				(justify right bottom)
			)
		)
		(property "Value" "R_470R_0402"
			(at -1.011843 1.772047 0)
			(layer "F.Fab")
			(effects
				(font
					(size 0.7 0.7)
					(thickness 0.15)
				)
				(justify right bottom)
			)
		)
		(property "Datasheet" "https://www.bourns.com/docs/product-datasheets/cr.pdf"
			(at 0 0 180)
			(layer "F.Fab")
			(hide yes)
			(effects
				(font
					(size 1.27 1.27)
					(thickness 0.15)
				)
			)
		)
		(property "Manufacturer" "Bourns"
			(at 0 0 180)
			(unlocked yes)
			(layer "F.Fab")
			(hide yes)
			(effects
				(font
					(size 1 1)
					(thickness 0.15)
				)
			)
		)
		(property "MPN" "CR0402-FX-4700GLF"
			(at 0 0 180)
			(unlocked yes)
			(layer "F.Fab")
			(hide yes)
			(effects
				(font
					(size 1 1)
					(thickness 0.15)
				)
			)
		)
		(property "Val" "470R"
			(at 0 0 180)
			(unlocked yes)
			(layer "F.Fab")
			(hide yes)
			(effects
				(font
					(size 1 1)
					(thickness 0.15)
				)
			)
		)
		(property "License" "Apache-2.0"
			(at 0 0 180)
			(unlocked yes)
			(layer "F.Fab")
			(hide yes)
			(effects
				(font
					(size 1 1)
					(thickness 0.15)
				)
			)
		)
		(property "Author" "Antmicro"
			(at 0 0 180)
			(unlocked yes)
			(layer "F.Fab")
			(hide yes)
			(effects
				(font
					(size 1 1)
					(thickness 0.15)
				)
			)
		)
		(property "Tolerance" "1%"
			(at 0 0 180)
			(unlocked yes)
			(layer "F.Fab")
			(hide yes)
			(effects
				(font
					(size 1 1)
					(thickness 0.15)
				)
			)
		)
		(sheetname "/Compute module/")
		(sheetfile "compute-module.kicad_sch")
		(attr smd)
		(fp_rect
			(start -0.925 -0.47)
			(end 0.925 0.47)
			(stroke
				(width 0.05)
				(type default)
			)
			(fill no)
			(layer "F.CrtYd")
		)
		(fp_rect
			(start -0.5 -0.25)
			(end 0.5 0.25)
			(stroke
				(width 0.15)
				(type solid)
			)
			(fill no)
			(layer "F.Fab")
		)
		(fp_text user "License: Apache-2.0"
			(at -0.95 5.169 180)
			(layer "F.Fab")
			(effects
				(font
					(size 0.7 0.7)
					(thickness 0.15)
				)
				(justify left bottom)
			)
		)
		(fp_text user "Author: Antmicro"
			(at -0.95 4.169 180)
			(layer "F.Fab")
			(effects
				(font
					(size 0.7 0.7)
					(thickness 0.15)
				)
				(justify left bottom)
			)
		)
		(fp_text user "${REFERENCE}"
			(at -0.95 3.168 180)
			(layer "F.Fab")
			(effects
				(font
					(size 0.7 0.7)
					(thickness 0.15)
				)
				(justify left bottom)
			)
		)
		(pad "1" smd roundrect
			(at -0.48 0 180)
			(size 0.59 0.64)
			(layers "F.Cu" "F.Mask" "F.Paste")
			(roundrect_rratio 0.25)
			(net 3 "GND")
			(pintype "passive")
		)
		(pad "2" smd roundrect
			(at 0.48 0 180)
			(size 0.59 0.64)
			(layers "F.Cu" "F.Mask" "F.Paste")
			(roundrect_rratio 0.25)
			(net 467 "Net-(D202-C)")
			(pintype "passive")
		)
	)
	(footprint "antmicro-footprints:C_0402_1005Metric"
		(layer "F.Cu")
		(at 86.742962 132.5415 90)
		(descr "Capacitor SMD 0402")
		(tags "capacitor SMD 0402")
		(property "Reference" "C921"
			(at 0.355 -0.545 90)
			(layer "F.SilkS")
			(effects
				(font
					(size 0.7 0.7)
					(thickness 0.15)
				)
				(justify left bottom)
			)
		)
		(property "Value" "C_100n_0402"
			(at -1.022927 2.155213 90)
			(layer "F.Fab")
			(effects
				(font
					(size 0.7 0.7)
					(thickness 0.15)
				)
				(justify left bottom)
			)
		)
		(property "Datasheet" "https://www.murata.com/products/productdetail?partno=GRM155R61H104KE14%23"
			(at 0 0 90)
			(layer "F.Fab")
			(hide yes)
			(effects
				(font
					(size 1.27 1.27)
					(thickness 0.15)
				)
			)
		)
		(property "Manufacturer" "Murata"
			(at 0 0 90)
			(unlocked yes)
			(layer "F.Fab")
			(hide yes)
			(effects
				(font
					(size 1 1)
					(thickness 0.15)
				)
			)
		)
		(property "MPN" "GRM155R61H104KE14D"
			(at 0 0 90)
			(unlocked yes)
			(layer "F.Fab")
			(hide yes)
			(effects
				(font
					(size 1 1)
					(thickness 0.15)
				)
			)
		)
		(property "Val" "100n"
			(at 0 0 90)
			(unlocked yes)
			(layer "F.Fab")
			(hide yes)
			(effects
				(font
					(size 1 1)
					(thickness 0.15)
				)
			)
		)
		(property "License" "Apache-2.0"
			(at 0 0 90)
			(unlocked yes)
			(layer "F.Fab")
			(hide yes)
			(effects
				(font
					(size 1 1)
					(thickness 0.15)
				)
			)
		)
		(property "Author" "Antmicro"
			(at 0 0 90)
			(unlocked yes)
			(layer "F.Fab")
			(hide yes)
			(effects
				(font
					(size 1 1)
					(thickness 0.15)
				)
			)
		)
		(property "Voltage" "50V"
			(at 0 0 90)
			(unlocked yes)
			(layer "F.Fab")
			(hide yes)
			(effects
				(font
					(size 1 1)
					(thickness 0.15)
				)
			)
		)
		(property "Dielectric" "X5R"
			(at 0 0 90)
			(unlocked yes)
			(layer "F.Fab")
			(hide yes)
			(effects
				(font
					(size 1 1)
					(thickness 0.15)
				)
			)
		)
		(sheetname "/USB/")
		(sheetfile "usb.kicad_sch")
		(attr smd)
		(fp_rect
			(start -0.925 -0.47)
			(end 0.925 0.47)
			(stroke
				(width 0.05)
				(type default)
			)
			(fill no)
			(layer "F.CrtYd")
		)
		(fp_line
			(start 0.504 -0.25)
			(end 0.504 0.248)
			(stroke
				(width 0.15)
				(type solid)
			)
			(layer "F.Fab")
		)
		(fp_line
			(start -0.494 -0.25)
			(end 0.504 -0.25)
			(stroke
				(width 0.15)
				(type solid)
			)
			(layer "F.Fab")
		)
		(fp_line
			(start 0.504 0.248)
			(end -0.494 0.248)
			(stroke
				(width 0.15)
				(type solid)
			)
			(layer "F.Fab")
		)
		(fp_line
			(start -0.494 0.248)
			(end -0.494 -0.25)
			(stroke
				(width 0.15)
				(type solid)
			)
			(layer "F.Fab")
		)
		(fp_text user "${REFERENCE}"
			(at -0.939 4.599 90)
			(layer "F.Fab")
			(effects
				(font
					(size 0.7 0.7)
					(thickness 0.15)
				)
				(justify left bottom)
			)
		)
		(fp_text user "License: Apache-2.0"
			(at -0.939 5.799 90)
			(layer "F.Fab")
			(effects
				(font
					(size 0.7 0.7)
					(thickness 0.15)
				)
				(justify left bottom)
			)
		)
		(fp_text user "Author: Antmicro"
			(at -0.939 3.399 90)
			(layer "F.Fab")
			(effects
				(font
					(size 0.7 0.7)
					(thickness 0.15)
				)
				(justify left bottom)
			)
		)
		(pad "1" smd roundrect
			(at -0.48 0 90)
			(size 0.59 0.64)
			(layers "F.Cu" "F.Mask" "F.Paste")
			(roundrect_rratio 0.25)
			(net 30 "/USB/USB_1V2")
			(pintype "passive")
		)
		(pad "2" smd roundrect
			(at 0.48 0 90)
			(size 0.59 0.64)
			(layers "F.Cu" "F.Mask" "F.Paste")
			(roundrect_rratio 0.25)
			(net 3 "GND")
			(pintype "passive")
		)
	)
	(footprint "antmicro-footprints:SOT-523"
		(layer "F.Cu")
		(at 54.717962 135.3165 -90)
		(property "Reference" "Q401"
			(at 1.8335 -0.832038 180)
			(layer "F.SilkS")
			(effects
				(font
					(size 0.7 0.7)
					(thickness 0.15)
				)
				(justify right bottom)
			)
		)
		(property "Value" "PJE138K"
			(at 0.1 1.824 90)
			(layer "F.Fab")
			(effects
				(font
					(size 0.7 0.7)
					(thickness 0.15)
				)
				(justify right bottom)
			)
		)
		(property "Datasheet" "https://www.mouser.com/datasheet/2/1057/PJE138K-1876698.pdf"
			(at 0 0 270)
			(layer "F.Fab")
			(hide yes)
			(effects
				(font
					(size 1.27 1.27)
					(thickness 0.15)
				)
			)
		)
		(property "MPN" "PJE138K_R1_00001"
			(at 0 0 270)
			(unlocked yes)
			(layer "F.Fab")
			(hide yes)
			(effects
				(font
					(size 1 1)
					(thickness 0.15)
				)
			)
		)
		(property "Manufacturer" "PANJIT"
			(at 0 0 270)
			(unlocked yes)
			(layer "F.Fab")
			(hide yes)
			(effects
				(font
					(size 1 1)
					(thickness 0.15)
				)
			)
		)
		(property "Author" "Antmicro"
			(at 0 0 270)
			(unlocked yes)
			(layer "F.Fab")
			(hide yes)
			(effects
				(font
					(size 1 1)
					(thickness 0.15)
				)
			)
		)
		(property "License" "Apache-2.0"
			(at 0 0 270)
			(unlocked yes)
			(layer "F.Fab")
			(hide yes)
			(effects
				(font
					(size 1 1)
					(thickness 0.15)
				)
			)
		)
		(sheetname "/Ethernet/")
		(sheetfile "ethernet.kicad_sch")
		(attr smd)
		(fp_line
			(start -0.927 -0.051)
			(end -0.927 -0.351)
			(stroke
				(width 0.15)
				(type solid)
			)
			(layer "F.SilkS")
		)
		(fp_line
			(start -0.927 -0.351)
			(end -0.725 -0.551)
			(stroke
				(width 0.15)
				(type solid)
			)
			(layer "F.SilkS")
		)
		(fp_line
			(start -0.725 -0.551)
			(end -0.277 -0.551)
			(stroke
				(width 0.15)
				(type solid)
			)
			(layer "F.SilkS")
		)
		(fp_line
			(start -0.277 -0.551)
			(end -0.277 -0.75)
			(stroke
				(width 0.15)
				(type solid)
			)
			(layer "F.SilkS")
		)
		(fp_circle
			(center -0.9652 0.9652)
			(end -0.9152 0.9652)
			(stroke
				(width 0.15)
				(type solid)
			)
			(fill yes)
			(layer "F.SilkS")
		)
		(fp_line
			(start -1.12 1.15)
			(end 1.1 1.15)
			(stroke
				(width 0.05)
				(type solid)
			)
			(layer "F.CrtYd")
		)
		(fp_line
			(start -1.12 -1.16)
			(end -1.12 1.15)
			(stroke
				(width 0.05)
				(type solid)
			)
			(layer "F.CrtYd")
		)
		(fp_line
			(start -1.12 -1.16)
			(end 1.1 -1.16)
			(stroke
				(width 0.05)
				(type solid)
			)
			(layer "F.CrtYd")
		)
		(fp_line
			(start 1.1 -1.16)
			(end 1.1 1.15)
			(stroke
				(width 0.05)
				(type solid)
			)
			(layer "F.CrtYd")
		)
		(fp_line
			(start 0.8 0.424)
			(end -0.802 0.424)
			(stroke
				(width 0.15)
				(type solid)
			)
			(layer "F.Fab")
		)
		(fp_line
			(start -0.802 -0.276)
			(end -0.802 0.424)
			(stroke
				(width 0.15)
				(type solid)
			)
			(layer "F.Fab")
		)
		(fp_line
			(start -0.652 -0.425)
			(end -0.802 -0.276)
			(stroke
				(width 0.15)
				(type solid)
			)
			(layer "F.Fab")
		)
		(fp_line
			(start 0.8 -0.425)
			(end 0.8 0.424)
			(stroke
				(width 0.15)
				(type solid)
			)
			(layer "F.Fab")
		)
		(fp_line
			(start 0.8 -0.425)
			(end -0.652 -0.425)
			(stroke
				(width 0.15)
				(type solid)
			)
			(layer "F.Fab")
		)
		(fp_circle
			(center -0.9652 0.9652)
			(end -0.9144 0.9652)
			(stroke
				(width 0.15)
				(type solid)
			)
			(fill no)
			(layer "F.Fab")
		)
		(fp_text user "${REFERENCE}"
			(at -1.12 3.824 270)
			(layer "F.Fab")
			(effects
				(font
					(size 0.7 0.7)
					(thickness 0.15)
				)
				(justify left bottom)
			)
		)
		(fp_text user "Author: Antmicro"
			(at -1.12 6.224 270)
			(layer "F.Fab")
			(effects
				(font
					(size 0.7 0.7)
					(thickness 0.15)
				)
				(justify left bottom)
			)
		)
		(fp_text user "License: Apache-2.0"
			(at -1.12 5.024 270)
			(layer "F.Fab")
			(effects
				(font
					(size 0.7 0.7)
					(thickness 0.15)
				)
				(justify left bottom)
			)
		)
		(pad "1" smd rect
			(at -0.5 0.65 270)
			(size 0.4 0.51)
			(layers "F.Cu" "F.Mask" "F.Paste")
			(net 339 "/Ethernet/POE_ACTIVE")
			(pinfunction "G")
			(pintype "input")
		)
		(pad "2" smd rect
			(at 0.498 0.65 270)
			(size 0.4 0.51)
			(layers "F.Cu" "F.Mask" "F.Paste")
			(net 1 "GNDD")
			(pinfunction "S")
			(pintype "passive")
		)
		(pad "3" smd rect
			(at 0 -0.652 270)
			(size 0.4 0.51)
			(layers "F.Cu" "F.Mask" "F.Paste")
			(net 126 "/Ethernet/ULS-12_CTRL")
			(pinfunction "D")
			(pintype "passive")
		)
	)
	(footprint "antmicro-footprints:Conn_JST_SH_1x2_SM02B-SRSS-TB-LF-SN"
		(layer "F.Cu")
		(at 55.117962 176.8255 -90)
		(property "Reference" "J804"
			(at -2.2255 0.167962 0)
			(layer "F.SilkS")
			(effects
				(font
					(size 0.7 0.7)
					(thickness 0.15)
				)
				(justify left bottom)
			)
		)
		(property "Value" "JST_SH_1x2_SM02B-SRSS-TB-LF-SN"
			(at -2.7 6.195 90)
			(layer "F.Fab")
			(effects
				(font
					(size 0.7 0.7)
					(thickness 0.15)
				)
				(justify right bottom)
			)
		)
		(property "Datasheet" "https://www.jst-mfg.com/product/pdf/eng/eSH.pdf"
			(at 0 0 270)
			(layer "F.Fab")
			(hide yes)
			(effects
				(font
					(size 1.27 1.27)
					(thickness 0.15)
				)
			)
		)
		(property "MPN" "SM02B-SRSS-TB(LF)(SN)"
			(at 0 0 270)
			(unlocked yes)
			(layer "F.Fab")
			(hide yes)
			(effects
				(font
					(size 1 1)
					(thickness 0.15)
				)
			)
		)
		(property "Manufacturer" "JST Automotive Connectors"
			(at 0 0 270)
			(unlocked yes)
			(layer "F.Fab")
			(hide yes)
			(effects
				(font
					(size 1 1)
					(thickness 0.15)
				)
			)
		)
		(property "Author" "Antmicro"
			(at 0 0 270)
			(unlocked yes)
			(layer "F.Fab")
			(hide yes)
			(effects
				(font
					(size 1 1)
					(thickness 0.15)
				)
			)
		)
		(property "License" "Apache-2.0"
			(at 0 0 270)
			(unlocked yes)
			(layer "F.Fab")
			(hide yes)
			(effects
				(font
					(size 1 1)
					(thickness 0.15)
				)
			)
		)
		(sheetname "/Peripherals/")
		(sheetfile "peripherals.kicad_sch")
		(attr smd)
		(fp_line
			(start -0.9 2.6)
			(end 0.9 2.6)
			(stroke
				(width 0.15)
				(type solid)
			)
			(layer "F.SilkS")
		)
		(fp_line
			(start -2 -1.651)
			(end -2 0.7)
			(stroke
				(width 0.15)
				(type solid)
			)
			(layer "F.SilkS")
		)
		(fp_line
			(start -2 -1.651)
			(end -1 -1.651)
			(stroke
				(width 0.15)
				(type solid)
			)
			(layer "F.SilkS")
		)
		(fp_line
			(start 2 -1.651)
			(end 2 0.7)
			(stroke
				(width 0.15)
				(type solid)
			)
			(layer "F.SilkS")
		)
		(fp_line
			(start 2 -1.651)
			(end 1 -1.651)
			(stroke
				(width 0.15)
				(type solid)
			)
			(layer "F.SilkS")
		)
		(fp_circle
			(center -1.1 -2.4)
			(end -1.05 -2.4)
			(stroke
				(width 0.15)
				(type solid)
			)
			(fill yes)
			(layer "F.SilkS")
		)
		(fp_rect
			(start -2.55 -2.92)
			(end 2.55 2.95)
			(stroke
				(width 0.05)
				(type solid)
			)
			(fill no)
			(layer "F.CrtYd")
		)
		(fp_rect
			(start -2 -2.475)
			(end 2 2.475)
			(stroke
				(width 0.15)
				(type solid)
			)
			(fill no)
			(layer "F.Fab")
		)
		(fp_text user "Author: Antmicro"
			(at -2.7 10.595 270)
			(layer "F.Fab")
			(effects
				(font
					(size 0.7 0.7)
					(thickness 0.15)
				)
				(justify left bottom)
			)
		)
		(fp_text user "${REFERENCE}"
			(at -2.7 8.195 270)
			(layer "F.Fab")
			(effects
				(font
					(size 0.7 0.7)
					(thickness 0.15)
				)
				(justify left bottom)
			)
		)
		(fp_text user "License: Apache-2.0"
			(at -2.7 9.395 270)
			(layer "F.Fab")
			(effects
				(font
					(size 0.7 0.7)
					(thickness 0.15)
				)
				(justify left bottom)
			)
		)
		(pad "1" smd roundrect
			(at -0.5 -1.975)
			(size 1.55 0.6)
			(layers "F.Cu" "F.Mask" "F.Paste")
			(roundrect_rratio 0.25)
			(net 319 "Net-(J804-Pad1)")
			(pintype "passive")
		)
		(pad "2" smd roundrect
			(at 0.5 -1.975)
			(size 1.55 0.6)
			(layers "F.Cu" "F.Mask" "F.Paste")
			(roundrect_rratio 0.25)
			(net 320 "Net-(J804-Pad2)")
			(pintype "passive")
		)
		(pad "MP" smd roundrect
			(at -1.8 1.9)
			(size 1.8 1.2)
			(layers "F.Cu" "F.Mask" "F.Paste")
			(roundrect_rratio 0.25)
			(net 3 "GND")
			(pintype "passive")
		)
		(pad "MP" smd roundrect
			(at 1.8 1.9)
			(size 1.8 1.2)
			(layers "F.Cu" "F.Mask" "F.Paste")
			(roundrect_rratio 0.25)
			(net 3 "GND")
			(pintype "passive")
		)
	)
	(footprint "antmicro-footprints:LED_0603_1608Metric_G"
		(layer "F.Cu")
		(at 75.767962 150.2915 180)
		(descr "LED SMD 0603 Green")
		(tags "LED SMD 0603 Green")
		(property "Reference" "D205"
			(at -1.15 6.125 0)
			(layer "F.SilkS")
			(effects
				(font
					(size 0.7 0.7)
					(thickness 0.15)
				)
				(justify right bottom)
			)
		)
		(property "Value" "LED_G_0603_KP-1608CGCK"
			(at -0.001 1.599 0)
			(layer "F.Fab")
			(effects
				(font
					(size 0.7 0.7)
					(thickness 0.15)
				)
				(justify right bottom)
			)
		)
		(property "Datasheet" "http://www.kingbright.com/attachments/file/psearch//000/00/00/KP-1608CGCK(Ver.23B).pdf"
			(at 0 0 180)
			(layer "F.Fab")
			(hide yes)
			(effects
				(font
					(size 1.27 1.27)
					(thickness 0.15)
				)
			)
		)
		(property "MPN" "KP-1608CGCK"
			(at 0 0 180)
			(unlocked yes)
			(layer "F.Fab")
			(hide yes)
			(effects
				(font
					(size 1 1)
					(thickness 0.15)
				)
			)
		)
		(property "Manufacturer" "Kingbright"
			(at 0 0 180)
			(unlocked yes)
			(layer "F.Fab")
			(hide yes)
			(effects
				(font
					(size 1 1)
					(thickness 0.15)
				)
			)
		)
		(property "Color" "Green"
			(at 0 0 180)
			(unlocked yes)
			(layer "F.Fab")
			(hide yes)
			(effects
				(font
					(size 1 1)
					(thickness 0.15)
				)
			)
		)
		(property "Author" "Antmicro"
			(at 0 0 180)
			(unlocked yes)
			(layer "F.Fab")
			(hide yes)
			(effects
				(font
					(size 1 1)
					(thickness 0.15)
				)
			)
		)
		(property "License" "Apache-2.0"
			(at 0 0 180)
			(unlocked yes)
			(layer "F.Fab")
			(hide yes)
			(effects
				(font
					(size 1 1)
					(thickness 0.15)
				)
			)
		)
		(sheetname "/Compute module/")
		(sheetfile "compute-module.kicad_sch")
		(attr smd)
		(fp_line
			(start 0.22 0.35)
			(end -0.22 0.35)
			(stroke
				(width 0.15)
				(type solid)
			)
			(layer "F.SilkS")
		)
		(fp_line
			(start 0.22 -0.35)
			(end -0.22 -0.35)
			(stroke
				(width 0.15)
				(type solid)
			)
			(layer "F.SilkS")
		)
		(fp_line
			(start 0.105328 0.201008)
			(end 0.105328 -0.198992)
			(stroke
				(width 0.1)
				(type solid)
			)
			(layer "F.SilkS")
		)
		(fp_line
			(start 0.105328 0.201008)
			(end -0.094672 0.001008)
			(stroke
				(width 0.1)
				(type solid)
			)
			(layer "F.SilkS")
		)
		(fp_line
			(start 0.105328 0.001008)
			(end 0.24 0.001)
			(stroke
				(width 0.1)
				(type solid)
			)
			(layer "F.SilkS")
		)
		(fp_line
			(start -0.094672 0.201008)
			(end -0.094672 -0.198992)
			(stroke
				(width 0.1)
				(type solid)
			)
			(layer "F.SilkS")
		)
		(fp_line
			(start -0.094672 0.001008)
			(end 0.105328 -0.198992)
			(stroke
				(width 0.1)
				(type solid)
			)
			(layer "F.SilkS")
		)
		(fp_line
			(start -0.094672 0.001008)
			(end -0.24 0.001008)
			(stroke
				(width 0.1)
				(type solid)
			)
			(layer "F.SilkS")
		)
		(fp_line
			(start -1.18 -0.319)
			(end -1.18 0.321)
			(stroke
				(width 0.15)
				(type solid)
			)
			(layer "F.SilkS")
		)
		(fp_rect
			(start 1.25 0.65)
			(end -1.25 -0.65)
			(stroke
				(width 0.05)
				(type solid)
			)
			(fill no)
			(layer "F.CrtYd")
		)
		(fp_line
			(start 0.599 0)
			(end 0.201 0)
			(stroke
				(width 0.15)
				(type solid)
			)
			(layer "F.Fab")
		)
		(fp_line
			(start 0.201 0.2)
			(end 0.201 0)
			(stroke
				(width 0.15)
				(type solid)
			)
			(layer "F.Fab")
		)
		(fp_line
			(start 0.201 0)
			(end 0.201 -0.202)
			(stroke
				(width 0.15)
				(type solid)
			)
			(layer "F.Fab")
		)
		(fp_line
			(start 0.201 -0.202)
			(end -0.101 0)
			(stroke
				(width 0.15)
				(type solid)
			)
			(layer "F.Fab")
		)
		(fp_line
			(start -0.101 0)
			(end 0.201 0.2)
			(stroke
				(width 0.15)
				(type solid)
			)
			(layer "F.Fab")
		)
		(fp_line
			(start -0.199 0.2)
			(end -0.199 0.1)
			(stroke
				(width 0.15)
				(type solid)
			)
			(layer "F.Fab")
		)
		(fp_line
			(start -0.199 0)
			(end -0.597 0)
			(stroke
				(width 0.15)
				(type solid)
			)
			(layer "F.Fab")
		)
		(fp_line
			(start -0.199 -0.202)
			(end -0.199 0.1)
			(stroke
				(width 0.15)
				(type solid)
			)
			(layer "F.Fab")
		)
		(fp_rect
			(start 0.848 0.4)
			(end -0.85 -0.402)
			(stroke
				(width 0.15)
				(type solid)
			)
			(fill no)
			(layer "F.Fab")
		)
		(fp_text user "${REFERENCE}"
			(at -1.4224 5.999 180)
			(layer "F.Fab")
			(effects
				(font
					(size 0.7 0.7)
					(thickness 0.15)
				)
				(justify left bottom)
			)
		)
		(fp_text user "Author: Antmicro"
			(at -1.4224 4.799 180)
			(layer "F.Fab")
			(effects
				(font
					(size 0.7 0.7)
					(thickness 0.15)
				)
				(justify left bottom)
			)
		)
		(fp_text user "License: Apache-2.0"
			(at -1.4224 3.599 180)
			(layer "F.Fab")
			(effects
				(font
					(size 0.7 0.7)
					(thickness 0.15)
				)
				(justify left bottom)
			)
		)
		(pad "1" smd roundrect
			(at -0.7 0)
			(size 0.8 1)
			(layers "F.Cu" "F.Mask" "F.Paste")
			(roundrect_rratio 0.2)
			(net 465 "Net-(D205-C)")
			(pinfunction "C")
			(pintype "passive")
		)
		(pad "2" smd roundrect
			(at 0.7 0)
			(size 0.8 1)
			(layers "F.Cu" "F.Mask" "F.Paste")
			(roundrect_rratio 0.2)
			(net 10 "+5V")
			(pinfunction "A")
			(pintype "passive")
		)
	)
	(footprint "antmicro-footprints:TP_SMD_0.75mm"
		(layer "F.Cu")
		(at 95.517962 139.757236)
		(property "Reference" "TP907"
			(at 0.45 0.519264 0)
			(layer "F.SilkS")
			(effects
				(font
					(size 0.7 0.7)
					(thickness 0.15)
				)
				(justify left bottom)
			)
		)
		(property "Value" "TP_0.75mm_SMD"
			(at 0 1.2 0)
			(layer "F.Fab")
			(effects
				(font
					(size 0.7 0.7)
					(thickness 0.15)
				)
				(justify left bottom)
			)
		)
		(property "MPN" ""
			(at 0 0 0)
			(unlocked yes)
			(layer "F.Fab")
			(hide yes)
			(effects
				(font
					(size 1 1)
					(thickness 0.15)
				)
			)
		)
		(property "Manufacturer" ""
			(at 0 0 0)
			(unlocked yes)
			(layer "F.Fab")
			(hide yes)
			(effects
				(font
					(size 1 1)
					(thickness 0.15)
				)
			)
		)
		(property "Author" "Antmicro"
			(at 0 0 0)
			(unlocked yes)
			(layer "F.Fab")
			(hide yes)
			(effects
				(font
					(size 1 1)
					(thickness 0.15)
				)
			)
		)
		(property "License" "Apache-2.0"
			(at 0 0 0)
			(unlocked yes)
			(layer "F.Fab")
			(hide yes)
			(effects
				(font
					(size 1 1)
					(thickness 0.15)
				)
			)
		)
		(sheetname "/USB/")
		(sheetfile "usb.kicad_sch")
		(attr exclude_from_pos_files exclude_from_bom)
		(fp_circle
			(center 0 0)
			(end 0.475 0)
			(stroke
				(width 0.05)
				(type default)
			)
			(fill no)
			(layer "F.CrtYd")
		)
		(fp_text user "Author: Antmicro"
			(at -0.4 3.901 0)
			(layer "F.Fab")
			(effects
				(font
					(size 0.7 0.7)
					(thickness 0.15)
				)
				(justify left bottom)
			)
		)
		(fp_text user "${REFERENCE}"
			(at -0.4 2.7 0)
			(layer "F.Fab")
			(effects
				(font
					(size 0.7 0.7)
					(thickness 0.15)
				)
				(justify left bottom)
			)
		)
		(fp_text user "License: Apache-2.0"
			(at -0.4 5.101 0)
			(layer "F.Fab")
			(effects
				(font
					(size 0.7 0.7)
					(thickness 0.15)
				)
				(justify left bottom)
			)
		)
		(pad "1" smd circle
			(at 0 0)
			(size 0.75 0.75)
			(layers "F.Cu" "F.Mask")
			(net 384 "Net-(U905-GPIO6)")
			(pinfunction "1")
			(pintype "passive")
		)
	)
	(footprint "antmicro-footprints:TSOT23-6"
		(layer "F.Cu")
		(at 137.317962 158.6165 -90)
		(property "Reference" "U601"
			(at 1.53 -2.17 90)
			(layer "F.SilkS")
			(effects
				(font
					(size 0.7 0.7)
					(thickness 0.15)
				)
				(justify right bottom)
			)
		)
		(property "Value" "AP22615A_TSOT26"
			(at 0 2.6 90)
			(layer "F.Fab")
			(effects
				(font
					(size 0.7 0.7)
					(thickness 0.15)
				)
				(justify right bottom)
			)
		)
		(property "Datasheet" "https://www.mouser.com/datasheet/2/115/DIOD_S_A0008958405_1-2543193.pdf"
			(at 0 0 270)
			(layer "F.Fab")
			(hide yes)
			(effects
				(font
					(size 1.27 1.27)
					(thickness 0.15)
				)
			)
		)
		(property "MPN" "AP22615AWU-7"
			(at 0 0 270)
			(unlocked yes)
			(layer "F.Fab")
			(hide yes)
			(effects
				(font
					(size 1 1)
					(thickness 0.15)
				)
			)
		)
		(property "Manufacturer" "Diodes Incorporated"
			(at 0 0 270)
			(unlocked yes)
			(layer "F.Fab")
			(hide yes)
			(effects
				(font
					(size 1 1)
					(thickness 0.15)
				)
			)
		)
		(property "Author" "Antmicro"
			(at 0 0 270)
			(unlocked yes)
			(layer "F.Fab")
			(hide yes)
			(effects
				(font
					(size 1 1)
					(thickness 0.15)
				)
			)
		)
		(property "License" "Apache-2.0"
			(at 0 0 270)
			(unlocked yes)
			(layer "F.Fab")
			(hide yes)
			(effects
				(font
					(size 1 1)
					(thickness 0.15)
				)
			)
		)
		(sheetname "/CSI/")
		(sheetfile "csi.kicad_sch")
		(attr smd)
		(fp_line
			(start -1 1.55)
			(end -1 1.4)
			(stroke
				(width 0.15)
				(type solid)
			)
			(layer "F.SilkS")
		)
		(fp_line
			(start 1 1.55)
			(end -1 1.55)
			(stroke
				(width 0.15)
				(type solid)
			)
			(layer "F.SilkS")
		)
		(fp_line
			(start 1 1.55)
			(end 1 1.4)
			(stroke
				(width 0.15)
				(type solid)
			)
			(layer "F.SilkS")
		)
		(fp_line
			(start 1 -1.497)
			(end 1 -1.375)
			(stroke
				(width 0.15)
				(type solid)
			)
			(layer "F.SilkS")
		)
		(fp_line
			(start 1 -1.497)
			(end -1 -1.5)
			(stroke
				(width 0.15)
				(type solid)
			)
			(layer "F.SilkS")
		)
		(fp_line
			(start -1 -1.5)
			(end -1 -1.375)
			(stroke
				(width 0.15)
				(type solid)
			)
			(layer "F.SilkS")
		)
		(fp_circle
			(center -1.44 -1.5)
			(end -1.39 -1.5)
			(stroke
				(width 0.15)
				(type solid)
			)
			(fill yes)
			(layer "F.SilkS")
		)
		(fp_rect
			(start 1.93 -1.7)
			(end -1.93 1.7)
			(stroke
				(width 0.05)
				(type solid)
			)
			(fill no)
			(layer "F.CrtYd")
		)
		(fp_line
			(start -0.45 -1.521)
			(end -0.876 -1.096)
			(stroke
				(width 0.15)
				(type solid)
			)
			(layer "F.Fab")
		)
		(fp_rect
			(start 0.875 1.528)
			(end -0.875 -1.525)
			(stroke
				(width 0.15)
				(type solid)
			)
			(fill no)
			(layer "F.Fab")
		)
		(fp_text user "${REFERENCE}"
			(at -1.93 3.8 270)
			(layer "F.Fab")
			(effects
				(font
					(size 0.7 0.7)
					(thickness 0.15)
				)
				(justify left bottom)
			)
		)
		(fp_text user "Author: Antmicro"
			(at -1.93 5 270)
			(layer "F.Fab")
			(effects
				(font
					(size 0.7 0.7)
					(thickness 0.15)
				)
				(justify left bottom)
			)
		)
		(fp_text user "License: Apache-2.0"
			(at -1.93 6.199 270)
			(layer "F.Fab")
			(effects
				(font
					(size 0.7 0.7)
					(thickness 0.15)
				)
				(justify left bottom)
			)
		)
		(pad "1" smd rect
			(at -1.301 -0.947 180)
			(size 0.7 1.2)
			(layers "F.Cu" "F.Mask" "F.Paste")
			(net 20 "/CSI/CSI_5V")
			(pinfunction "OUT")
			(pintype "power_out")
		)
		(pad "2" smd rect
			(at -1.301 0.004 180)
			(size 0.7 1.2)
			(layers "F.Cu" "F.Mask" "F.Paste")
			(net 3 "GND")
			(pinfunction "GND")
			(pintype "power_in")
		)
		(pad "3" smd rect
			(at -1.301 0.954 180)
			(size 0.7 1.2)
			(layers "F.Cu" "F.Mask" "F.Paste")
			(net 370 "Net-(U601-FLG)")
			(pinfunction "FLG")
			(pintype "output")
		)
		(pad "4" smd rect
			(at 1.299 0.954 180)
			(size 0.7 1.2)
			(layers "F.Cu" "F.Mask" "F.Paste")
			(net 369 "/CSI/CamCtrl.EN")
			(pinfunction "EN")
			(pintype "input")
		)
		(pad "5" smd rect
			(at 1.299 0.004 180)
			(size 0.7 1.2)
			(layers "F.Cu" "F.Mask" "F.Paste")
			(net 372 "Net-(U601-ISET)")
			(pinfunction "ISET")
			(pintype "passive")
		)
		(pad "6" smd rect
			(at 1.299 -0.947 180)
			(size 0.7 1.2)
			(layers "F.Cu" "F.Mask" "F.Paste")
			(net 10 "+5V")
			(pinfunction "IN")
			(pintype "power_in")
		)
	)
	(footprint "antmicro-footprints:R_0402_1005Metric"
		(layer "F.Cu")
		(at 66.342962 143.9165 180)
		(descr "Resistor SMD 0402")
		(tags "resistor SMD 0402")
		(property "Reference" "R1"
			(at -0.425 0.55 0)
			(layer "F.SilkS")
			(effects
				(font
					(size 0.7 0.7)
					(thickness 0.15)
				)
				(justify right bottom)
			)
		)
		(property "Value" "R_100k_0402"
			(at -1.011843 1.772047 0)
			(layer "F.Fab")
			(effects
				(font
					(size 0.7 0.7)
					(thickness 0.15)
				)
				(justify right bottom)
			)
		)
		(property "Datasheet" "https://www.bourns.com/docs/product-datasheets/cr.pdf"
			(at 0 0 180)
			(layer "F.Fab")
			(hide yes)
			(effects
				(font
					(size 1.27 1.27)
					(thickness 0.15)
				)
			)
		)
		(property "Manufacturer" "Bourns"
			(at 0 0 180)
			(unlocked yes)
			(layer "F.Fab")
			(hide yes)
			(effects
				(font
					(size 1 1)
					(thickness 0.15)
				)
			)
		)
		(property "MPN" "CR0402-FX-1003GLF"
			(at 0 0 180)
			(unlocked yes)
			(layer "F.Fab")
			(hide yes)
			(effects
				(font
					(size 1 1)
					(thickness 0.15)
				)
			)
		)
		(property "Val" "100k"
			(at 0 0 180)
			(unlocked yes)
			(layer "F.Fab")
			(hide yes)
			(effects
				(font
					(size 1 1)
					(thickness 0.15)
				)
			)
		)
		(property "License" "Apache-2.0"
			(at 0 0 180)
			(unlocked yes)
			(layer "F.Fab")
			(hide yes)
			(effects
				(font
					(size 1 1)
					(thickness 0.15)
				)
			)
		)
		(property "Author" "Antmicro"
			(at 0 0 180)
			(unlocked yes)
			(layer "F.Fab")
			(hide yes)
			(effects
				(font
					(size 1 1)
					(thickness 0.15)
				)
			)
		)
		(property "Tolerance" "1%"
			(at 0 0 180)
			(unlocked yes)
			(layer "F.Fab")
			(hide yes)
			(effects
				(font
					(size 1 1)
					(thickness 0.15)
				)
			)
		)
		(sheetname "/Compute module/")
		(sheetfile "compute-module.kicad_sch")
		(attr smd)
		(fp_rect
			(start -0.925 -0.47)
			(end 0.925 0.47)
			(stroke
				(width 0.05)
				(type default)
			)
			(fill no)
			(layer "F.CrtYd")
		)
		(fp_rect
			(start -0.5 -0.25)
			(end 0.5 0.25)
			(stroke
				(width 0.15)
				(type solid)
			)
			(fill no)
			(layer "F.Fab")
		)
		(fp_text user "${REFERENCE}"
			(at -0.95 3.168 180)
			(layer "F.Fab")
			(effects
				(font
					(size 0.7 0.7)
					(thickness 0.15)
				)
				(justify left bottom)
			)
		)
		(fp_text user "License: Apache-2.0"
			(at -0.95 5.169 180)
			(layer "F.Fab")
			(effects
				(font
					(size 0.7 0.7)
					(thickness 0.15)
				)
				(justify left bottom)
			)
		)
		(fp_text user "Author: Antmicro"
			(at -0.95 4.169 180)
			(layer "F.Fab")
			(effects
				(font
					(size 0.7 0.7)
					(thickness 0.15)
				)
				(justify left bottom)
			)
		)
		(pad "1" smd roundrect
			(at -0.48 0 180)
			(size 0.59 0.64)
			(layers "F.Cu" "F.Mask" "F.Paste")
			(roundrect_rratio 0.25)
			(net 491 "Net-(Q206-G)")
			(pintype "passive")
		)
		(pad "2" smd roundrect
			(at 0.48 0 180)
			(size 0.59 0.64)
			(layers "F.Cu" "F.Mask" "F.Paste")
			(roundrect_rratio 0.25)
			(net 9 "+3V3")
			(pintype "passive")
		)
	)
	(footprint "antmicro-footprints:LED_0603_1608Metric_G"
		(layer "F.Cu")
		(at 132.187962 156.0165 180)
		(descr "LED SMD 0603 Green")
		(tags "LED SMD 0603 Green")
		(property "Reference" "D602"
			(at -0.38 1.05 0)
			(layer "F.SilkS")
			(effects
				(font
					(size 0.7 0.7)
					(thickness 0.15)
				)
				(justify right bottom)
			)
		)
		(property "Value" "LED_G_0603_KP-1608CGCK"
			(at -0.001 1.599 0)
			(layer "F.Fab")
			(effects
				(font
					(size 0.7 0.7)
					(thickness 0.15)
				)
				(justify right bottom)
			)
		)
		(property "Datasheet" "http://www.kingbright.com/attachments/file/psearch//000/00/00/KP-1608CGCK(Ver.23B).pdf"
			(at 0 0 180)
			(layer "F.Fab")
			(hide yes)
			(effects
				(font
					(size 1.27 1.27)
					(thickness 0.15)
				)
			)
		)
		(property "MPN" "KP-1608CGCK"
			(at 0 0 180)
			(unlocked yes)
			(layer "F.Fab")
			(hide yes)
			(effects
				(font
					(size 1 1)
					(thickness 0.15)
				)
			)
		)
		(property "Manufacturer" "Kingbright"
			(at 0 0 180)
			(unlocked yes)
			(layer "F.Fab")
			(hide yes)
			(effects
				(font
					(size 1 1)
					(thickness 0.15)
				)
			)
		)
		(property "Color" "Green"
			(at 0 0 180)
			(unlocked yes)
			(layer "F.Fab")
			(hide yes)
			(effects
				(font
					(size 1 1)
					(thickness 0.15)
				)
			)
		)
		(property "Author" "Antmicro"
			(at 0 0 180)
			(unlocked yes)
			(layer "F.Fab")
			(hide yes)
			(effects
				(font
					(size 1 1)
					(thickness 0.15)
				)
			)
		)
		(property "License" "Apache-2.0"
			(at 0 0 180)
			(unlocked yes)
			(layer "F.Fab")
			(hide yes)
			(effects
				(font
					(size 1 1)
					(thickness 0.15)
				)
			)
		)
		(sheetname "/CSI/")
		(sheetfile "csi.kicad_sch")
		(attr smd)
		(fp_line
			(start 0.22 0.35)
			(end -0.22 0.35)
			(stroke
				(width 0.15)
				(type solid)
			)
			(layer "F.SilkS")
		)
		(fp_line
			(start 0.22 -0.35)
			(end -0.22 -0.35)
			(stroke
				(width 0.15)
				(type solid)
			)
			(layer "F.SilkS")
		)
		(fp_line
			(start 0.105328 0.201008)
			(end 0.105328 -0.198992)
			(stroke
				(width 0.1)
				(type solid)
			)
			(layer "F.SilkS")
		)
		(fp_line
			(start 0.105328 0.201008)
			(end -0.094672 0.001008)
			(stroke
				(width 0.1)
				(type solid)
			)
			(layer "F.SilkS")
		)
		(fp_line
			(start 0.105328 0.001008)
			(end 0.24 0.001)
			(stroke
				(width 0.1)
				(type solid)
			)
			(layer "F.SilkS")
		)
		(fp_line
			(start -0.094672 0.201008)
			(end -0.094672 -0.198992)
			(stroke
				(width 0.1)
				(type solid)
			)
			(layer "F.SilkS")
		)
		(fp_line
			(start -0.094672 0.001008)
			(end 0.105328 -0.198992)
			(stroke
				(width 0.1)
				(type solid)
			)
			(layer "F.SilkS")
		)
		(fp_line
			(start -0.094672 0.001008)
			(end -0.24 0.001008)
			(stroke
				(width 0.1)
				(type solid)
			)
			(layer "F.SilkS")
		)
		(fp_line
			(start -1.18 -0.319)
			(end -1.18 0.321)
			(stroke
				(width 0.15)
				(type solid)
			)
			(layer "F.SilkS")
		)
		(fp_rect
			(start 1.25 0.65)
			(end -1.25 -0.65)
			(stroke
				(width 0.05)
				(type solid)
			)
			(fill no)
			(layer "F.CrtYd")
		)
		(fp_line
			(start 0.599 0)
			(end 0.201 0)
			(stroke
				(width 0.15)
				(type solid)
			)
			(layer "F.Fab")
		)
		(fp_line
			(start 0.201 0.2)
			(end 0.201 0)
			(stroke
				(width 0.15)
				(type solid)
			)
			(layer "F.Fab")
		)
		(fp_line
			(start 0.201 0)
			(end 0.201 -0.202)
			(stroke
				(width 0.15)
				(type solid)
			)
			(layer "F.Fab")
		)
		(fp_line
			(start 0.201 -0.202)
			(end -0.101 0)
			(stroke
				(width 0.15)
				(type solid)
			)
			(layer "F.Fab")
		)
		(fp_line
			(start -0.101 0)
			(end 0.201 0.2)
			(stroke
				(width 0.15)
				(type solid)
			)
			(layer "F.Fab")
		)
		(fp_line
			(start -0.199 0.2)
			(end -0.199 0.1)
			(stroke
				(width 0.15)
				(type solid)
			)
			(layer "F.Fab")
		)
		(fp_line
			(start -0.199 0)
			(end -0.597 0)
			(stroke
				(width 0.15)
				(type solid)
			)
			(layer "F.Fab")
		)
		(fp_line
			(start -0.199 -0.202)
			(end -0.199 0.1)
			(stroke
				(width 0.15)
				(type solid)
			)
			(layer "F.Fab")
		)
		(fp_rect
			(start 0.848 0.4)
			(end -0.85 -0.402)
			(stroke
				(width 0.15)
				(type solid)
			)
			(fill no)
			(layer "F.Fab")
		)
		(fp_text user "Author: Antmicro"
			(at -1.4224 4.799 180)
			(layer "F.Fab")
			(effects
				(font
					(size 0.7 0.7)
					(thickness 0.15)
				)
				(justify left bottom)
			)
		)
		(fp_text user "License: Apache-2.0"
			(at -1.4224 3.599 180)
			(layer "F.Fab")
			(effects
				(font
					(size 0.7 0.7)
					(thickness 0.15)
				)
				(justify left bottom)
			)
		)
		(fp_text user "${REFERENCE}"
			(at -1.4224 5.999 180)
			(layer "F.Fab")
			(effects
				(font
					(size 0.7 0.7)
					(thickness 0.15)
				)
				(justify left bottom)
			)
		)
		(pad "1" smd roundrect
			(at -0.7 0)
			(size 0.8 1)
			(layers "F.Cu" "F.Mask" "F.Paste")
			(roundrect_rratio 0.2)
			(net 3 "GND")
			(pinfunction "C")
			(pintype "passive")
		)
		(pad "2" smd roundrect
			(at 0.7 0)
			(size 0.8 1)
			(layers "F.Cu" "F.Mask" "F.Paste")
			(roundrect_rratio 0.2)
			(net 480 "Net-(D602-A)")
			(pinfunction "A")
			(pintype "passive")
		)
	)
	(footprint "antmicro-footprints:TP_SMD_0.75mm"
		(layer "F.Cu")
		(at 118.142962 125.25 180)
		(property "Reference" "TP502"
			(at -3.85 -0.5 0)
			(layer "F.SilkS")
			(effects
				(font
					(size 0.7 0.7)
					(thickness 0.15)
				)
				(justify right bottom)
			)
		)
		(property "Value" "TP_0.75mm_SMD"
			(at 0 1.2 0)
			(layer "F.Fab")
			(effects
				(font
					(size 0.7 0.7)
					(thickness 0.15)
				)
				(justify right bottom)
			)
		)
		(property "MPN" ""
			(at 0 0 180)
			(unlocked yes)
			(layer "F.Fab")
			(hide yes)
			(effects
				(font
					(size 1 1)
					(thickness 0.15)
				)
			)
		)
		(property "Manufacturer" ""
			(at 0 0 180)
			(unlocked yes)
			(layer "F.Fab")
			(hide yes)
			(effects
				(font
					(size 1 1)
					(thickness 0.15)
				)
			)
		)
		(property "Author" "Antmicro"
			(at 0 0 180)
			(unlocked yes)
			(layer "F.Fab")
			(hide yes)
			(effects
				(font
					(size 1 1)
					(thickness 0.15)
				)
			)
		)
		(property "License" "Apache-2.0"
			(at 0 0 180)
			(unlocked yes)
			(layer "F.Fab")
			(hide yes)
			(effects
				(font
					(size 1 1)
					(thickness 0.15)
				)
			)
		)
		(sheetname "/NVMe & microSD/")
		(sheetfile "nvme-micro-sd.kicad_sch")
		(attr exclude_from_pos_files exclude_from_bom)
		(fp_circle
			(center 0 0)
			(end 0.475 0)
			(stroke
				(width 0.05)
				(type default)
			)
			(fill no)
			(layer "F.CrtYd")
		)
		(fp_text user "License: Apache-2.0"
			(at -0.4 5.101 180)
			(layer "F.Fab")
			(effects
				(font
					(size 0.7 0.7)
					(thickness 0.15)
				)
				(justify left bottom)
			)
		)
		(fp_text user "Author: Antmicro"
			(at -0.4 3.901 180)
			(layer "F.Fab")
			(effects
				(font
					(size 0.7 0.7)
					(thickness 0.15)
				)
				(justify left bottom)
			)
		)
		(fp_text user "${REFERENCE}"
			(at -0.4 2.7 180)
			(layer "F.Fab")
			(effects
				(font
					(size 0.7 0.7)
					(thickness 0.15)
				)
				(justify left bottom)
			)
		)
		(pad "1" smd circle
			(at 0 0 180)
			(size 0.75 0.75)
			(layers "F.Cu" "F.Mask")
			(net 185 "Net-(J501-ALERT)")
			(pinfunction "1")
			(pintype "passive")
		)
	)
	(footprint "antmicro-footprints:C_0402_1005Metric"
		(layer "F.Cu")
		(at 89.667962 132.442236 180)
		(descr "Capacitor SMD 0402")
		(tags "capacitor SMD 0402")
		(property "Reference" "C920"
			(at -1.39 4.060736 0)
			(layer "F.SilkS")
			(effects
				(font
					(size 0.7 0.7)
					(thickness 0.15)
				)
				(justify right bottom)
			)
		)
		(property "Value" "C_100n_0402"
			(at -1.022927 2.155213 0)
			(layer "F.Fab")
			(effects
				(font
					(size 0.7 0.7)
					(thickness 0.15)
				)
				(justify right bottom)
			)
		)
		(property "Datasheet" "https://www.murata.com/products/productdetail?partno=GRM155R61H104KE14%23"
			(at 0 0 180)
			(layer "F.Fab")
			(hide yes)
			(effects
				(font
					(size 1.27 1.27)
					(thickness 0.15)
				)
			)
		)
		(property "Manufacturer" "Murata"
			(at 0 0 180)
			(unlocked yes)
			(layer "F.Fab")
			(hide yes)
			(effects
				(font
					(size 1 1)
					(thickness 0.15)
				)
			)
		)
		(property "MPN" "GRM155R61H104KE14D"
			(at 0 0 180)
			(unlocked yes)
			(layer "F.Fab")
			(hide yes)
			(effects
				(font
					(size 1 1)
					(thickness 0.15)
				)
			)
		)
		(property "Val" "100n"
			(at 0 0 180)
			(unlocked yes)
			(layer "F.Fab")
			(hide yes)
			(effects
				(font
					(size 1 1)
					(thickness 0.15)
				)
			)
		)
		(property "License" "Apache-2.0"
			(at 0 0 180)
			(unlocked yes)
			(layer "F.Fab")
			(hide yes)
			(effects
				(font
					(size 1 1)
					(thickness 0.15)
				)
			)
		)
		(property "Author" "Antmicro"
			(at 0 0 180)
			(unlocked yes)
			(layer "F.Fab")
			(hide yes)
			(effects
				(font
					(size 1 1)
					(thickness 0.15)
				)
			)
		)
		(property "Voltage" "50V"
			(at 0 0 180)
			(unlocked yes)
			(layer "F.Fab")
			(hide yes)
			(effects
				(font
					(size 1 1)
					(thickness 0.15)
				)
			)
		)
		(property "Dielectric" "X5R"
			(at 0 0 180)
			(unlocked yes)
			(layer "F.Fab")
			(hide yes)
			(effects
				(font
					(size 1 1)
					(thickness 0.15)
				)
			)
		)
		(sheetname "/USB/")
		(sheetfile "usb.kicad_sch")
		(attr smd)
		(fp_rect
			(start -0.925 -0.47)
			(end 0.925 0.47)
			(stroke
				(width 0.05)
				(type default)
			)
			(fill no)
			(layer "F.CrtYd")
		)
		(fp_line
			(start 0.504 0.248)
			(end -0.494 0.248)
			(stroke
				(width 0.15)
				(type solid)
			)
			(layer "F.Fab")
		)
		(fp_line
			(start 0.504 -0.25)
			(end 0.504 0.248)
			(stroke
				(width 0.15)
				(type solid)
			)
			(layer "F.Fab")
		)
		(fp_line
			(start -0.494 0.248)
			(end -0.494 -0.25)
			(stroke
				(width 0.15)
				(type solid)
			)
			(layer "F.Fab")
		)
		(fp_line
			(start -0.494 -0.25)
			(end 0.504 -0.25)
			(stroke
				(width 0.15)
				(type solid)
			)
			(layer "F.Fab")
		)
		(fp_text user "${REFERENCE}"
			(at -0.939 4.599 180)
			(layer "F.Fab")
			(effects
				(font
					(size 0.7 0.7)
					(thickness 0.15)
				)
				(justify left bottom)
			)
		)
		(fp_text user "Author: Antmicro"
			(at -0.939 3.399 180)
			(layer "F.Fab")
			(effects
				(font
					(size 0.7 0.7)
					(thickness 0.15)
				)
				(justify left bottom)
			)
		)
		(fp_text user "License: Apache-2.0"
			(at -0.939 5.799 180)
			(layer "F.Fab")
			(effects
				(font
					(size 0.7 0.7)
					(thickness 0.15)
				)
				(justify left bottom)
			)
		)
		(pad "1" smd roundrect
			(at -0.48 0 180)
			(size 0.59 0.64)
			(layers "F.Cu" "F.Mask" "F.Paste")
			(roundrect_rratio 0.25)
			(net 211 "/USB/VCC_PD")
			(pintype "passive")
		)
		(pad "2" smd roundrect
			(at 0.48 0 180)
			(size 0.59 0.64)
			(layers "F.Cu" "F.Mask" "F.Paste")
			(roundrect_rratio 0.25)
			(net 3 "GND")
			(pintype "passive")
		)
	)
	(footprint "antmicro-footprints:TP_SMD_0.75mm"
		(layer "F.Cu")
		(at 118.15 127.25 180)
		(property "Reference" "TP504"
			(at -3.85 -0.5 0)
			(layer "F.SilkS")
			(effects
				(font
					(size 0.7 0.7)
					(thickness 0.15)
				)
				(justify right bottom)
			)
		)
		(property "Value" "TP_0.75mm_SMD"
			(at 0 1.2 0)
			(layer "F.Fab")
			(effects
				(font
					(size 0.7 0.7)
					(thickness 0.15)
				)
				(justify right bottom)
			)
		)
		(property "MPN" ""
			(at 0 0 180)
			(unlocked yes)
			(layer "F.Fab")
			(hide yes)
			(effects
				(font
					(size 1 1)
					(thickness 0.15)
				)
			)
		)
		(property "Manufacturer" ""
			(at 0 0 180)
			(unlocked yes)
			(layer "F.Fab")
			(hide yes)
			(effects
				(font
					(size 1 1)
					(thickness 0.15)
				)
			)
		)
		(property "Author" "Antmicro"
			(at 0 0 180)
			(unlocked yes)
			(layer "F.Fab")
			(hide yes)
			(effects
				(font
					(size 1 1)
					(thickness 0.15)
				)
			)
		)
		(property "License" "Apache-2.0"
			(at 0 0 180)
			(unlocked yes)
			(layer "F.Fab")
			(hide yes)
			(effects
				(font
					(size 1 1)
					(thickness 0.15)
				)
			)
		)
		(sheetname "/NVMe & microSD/")
		(sheetfile "nvme-micro-sd.kicad_sch")
		(attr exclude_from_pos_files exclude_from_bom)
		(fp_circle
			(center 0 0)
			(end 0.475 0)
			(stroke
				(width 0.05)
				(type default)
			)
			(fill no)
			(layer "F.CrtYd")
		)
		(fp_text user "Author: Antmicro"
			(at -0.4 3.901 180)
			(layer "F.Fab")
			(effects
				(font
					(size 0.7 0.7)
					(thickness 0.15)
				)
				(justify left bottom)
			)
		)
		(fp_text user "${REFERENCE}"
			(at -0.4 2.7 180)
			(layer "F.Fab")
			(effects
				(font
					(size 0.7 0.7)
					(thickness 0.15)
				)
				(justify left bottom)
			)
		)
		(fp_text user "License: Apache-2.0"
			(at -0.4 5.101 180)
			(layer "F.Fab")
			(effects
				(font
					(size 0.7 0.7)
					(thickness 0.15)
				)
				(justify left bottom)
			)
		)
		(pad "1" smd circle
			(at 0 0 180)
			(size 0.75 0.75)
			(layers "F.Cu" "F.Mask")
			(net 193 "Net-(J501-SMB_CLK)")
			(pinfunction "1")
			(pintype "passive")
		)
	)
	(footprint "antmicro-footprints:R_0402_1005Metric"
		(layer "F.Cu")
		(at 123.805476 165.9665)
		(descr "Resistor SMD 0402")
		(tags "resistor SMD 0402")
		(property "Reference" "R508"
			(at -3.837514 0.39 0)
			(layer "F.SilkS")
			(effects
				(font
					(size 0.7 0.7)
					(thickness 0.15)
				)
				(justify left bottom)
			)
		)
		(property "Value" "R_10k_0402"
			(at -1.011843 1.772047 0)
			(layer "F.Fab")
			(effects
				(font
					(size 0.7 0.7)
					(thickness 0.15)
				)
				(justify left bottom)
			)
		)
		(property "Datasheet" "https://www.bourns.com/docs/product-datasheets/cr.pdf"
			(at 0 0 0)
			(layer "F.Fab")
			(hide yes)
			(effects
				(font
					(size 1.27 1.27)
					(thickness 0.15)
				)
			)
		)
		(property "Manufacturer" "Bourns"
			(at 0 0 0)
			(unlocked yes)
			(layer "F.Fab")
			(hide yes)
			(effects
				(font
					(size 1 1)
					(thickness 0.15)
				)
			)
		)
		(property "MPN" "CR0402-FX-1002GLF"
			(at 0 0 0)
			(unlocked yes)
			(layer "F.Fab")
			(hide yes)
			(effects
				(font
					(size 1 1)
					(thickness 0.15)
				)
			)
		)
		(property "Val" "10k"
			(at 0 0 0)
			(unlocked yes)
			(layer "F.Fab")
			(hide yes)
			(effects
				(font
					(size 1 1)
					(thickness 0.15)
				)
			)
		)
		(property "License" "Apache-2.0"
			(at 0 0 0)
			(unlocked yes)
			(layer "F.Fab")
			(hide yes)
			(effects
				(font
					(size 1 1)
					(thickness 0.15)
				)
			)
		)
		(property "Author" "Antmicro"
			(at 0 0 0)
			(unlocked yes)
			(layer "F.Fab")
			(hide yes)
			(effects
				(font
					(size 1 1)
					(thickness 0.15)
				)
			)
		)
		(property "Tolerance" "1%"
			(at 0 0 0)
			(unlocked yes)
			(layer "F.Fab")
			(hide yes)
			(effects
				(font
					(size 1 1)
					(thickness 0.15)
				)
			)
		)
		(sheetname "/NVMe & microSD/")
		(sheetfile "nvme-micro-sd.kicad_sch")
		(attr smd)
		(fp_rect
			(start -0.925 -0.47)
			(end 0.925 0.47)
			(stroke
				(width 0.05)
				(type default)
			)
			(fill no)
			(layer "F.CrtYd")
		)
		(fp_rect
			(start -0.5 -0.25)
			(end 0.5 0.25)
			(stroke
				(width 0.15)
				(type solid)
			)
			(fill no)
			(layer "F.Fab")
		)
		(fp_text user "License: Apache-2.0"
			(at -0.95 5.169 0)
			(layer "F.Fab")
			(effects
				(font
					(size 0.7 0.7)
					(thickness 0.15)
				)
				(justify left bottom)
			)
		)
		(fp_text user "${REFERENCE}"
			(at -0.95 3.168 0)
			(layer "F.Fab")
			(effects
				(font
					(size 0.7 0.7)
					(thickness 0.15)
				)
				(justify left bottom)
			)
		)
		(fp_text user "Author: Antmicro"
			(at -0.95 4.169 0)
			(layer "F.Fab")
			(effects
				(font
					(size 0.7 0.7)
					(thickness 0.15)
				)
				(justify left bottom)
			)
		)
		(pad "1" smd roundrect
			(at -0.48 0)
			(size 0.59 0.64)
			(layers "F.Cu" "F.Mask" "F.Paste")
			(roundrect_rratio 0.25)
			(net 9 "+3V3")
			(pintype "passive")
		)
		(pad "2" smd roundrect
			(at 0.48 0)
			(size 0.59 0.64)
			(layers "F.Cu" "F.Mask" "F.Paste")
			(roundrect_rratio 0.25)
			(net 8 "/Compute module/SDIO.CMD")
			(pintype "passive")
		)
	)
	(footprint "antmicro-footprints:R_0402_1005Metric"
		(layer "F.Cu")
		(at 72.867962 166.4365 180)
		(descr "Resistor SMD 0402")
		(tags "resistor SMD 0402")
		(property "Reference" "R805"
			(at -0.962038 1.43 0)
			(layer "F.SilkS")
			(effects
				(font
					(size 0.7 0.7)
					(thickness 0.15)
				)
				(justify right bottom)
			)
		)
		(property "Value" "R_10k_0402"
			(at -1.011843 1.772047 0)
			(layer "F.Fab")
			(effects
				(font
					(size 0.7 0.7)
					(thickness 0.15)
				)
				(justify right bottom)
			)
		)
		(property "Datasheet" "https://www.bourns.com/docs/product-datasheets/cr.pdf"
			(at 0 0 180)
			(layer "F.Fab")
			(hide yes)
			(effects
				(font
					(size 1.27 1.27)
					(thickness 0.15)
				)
			)
		)
		(property "MPN" "CR0402-FX-1002GLF"
			(at 0 0 180)
			(unlocked yes)
			(layer "F.Fab")
			(hide yes)
			(effects
				(font
					(size 1 1)
					(thickness 0.15)
				)
			)
		)
		(property "Manufacturer" "Bourns"
			(at 0 0 180)
			(unlocked yes)
			(layer "F.Fab")
			(hide yes)
			(effects
				(font
					(size 1 1)
					(thickness 0.15)
				)
			)
		)
		(property "License" "Apache-2.0"
			(at 0 0 180)
			(unlocked yes)
			(layer "F.Fab")
			(hide yes)
			(effects
				(font
					(size 1 1)
					(thickness 0.15)
				)
			)
		)
		(property "Author" "Antmicro"
			(at 0 0 180)
			(unlocked yes)
			(layer "F.Fab")
			(hide yes)
			(effects
				(font
					(size 1 1)
					(thickness 0.15)
				)
			)
		)
		(property "Val" "10k"
			(at 0 0 180)
			(unlocked yes)
			(layer "F.Fab")
			(hide yes)
			(effects
				(font
					(size 1 1)
					(thickness 0.15)
				)
			)
		)
		(property "Tolerance" "1%"
			(at 0 0 180)
			(unlocked yes)
			(layer "F.Fab")
			(hide yes)
			(effects
				(font
					(size 1 1)
					(thickness 0.15)
				)
			)
		)
		(sheetname "/Peripherals/")
		(sheetfile "peripherals.kicad_sch")
		(attr smd exclude_from_pos_files exclude_from_bom dnp)
		(fp_rect
			(start -0.925 -0.47)
			(end 0.925 0.47)
			(stroke
				(width 0.05)
				(type default)
			)
			(fill no)
			(layer "F.CrtYd")
		)
		(fp_rect
			(start -0.5 -0.25)
			(end 0.5 0.25)
			(stroke
				(width 0.15)
				(type solid)
			)
			(fill no)
			(layer "F.Fab")
		)
		(fp_text user "License: Apache-2.0"
			(at -0.95 5.169 180)
			(layer "F.Fab")
			(effects
				(font
					(size 0.7 0.7)
					(thickness 0.15)
				)
				(justify left bottom)
			)
		)
		(fp_text user "Author: Antmicro"
			(at -0.95 4.169 180)
			(layer "F.Fab")
			(effects
				(font
					(size 0.7 0.7)
					(thickness 0.15)
				)
				(justify left bottom)
			)
		)
		(fp_text user "${REFERENCE}"
			(at -0.95 3.168 180)
			(layer "F.Fab")
			(effects
				(font
					(size 0.7 0.7)
					(thickness 0.15)
				)
				(justify left bottom)
			)
		)
		(pad "1" smd roundrect
			(at -0.48 0 180)
			(size 0.59 0.64)
			(layers "F.Cu" "F.Mask" "F.Paste")
			(roundrect_rratio 0.25)
			(net 375 "Net-(U801-I2C_ADR1)")
			(pintype "passive")
		)
		(pad "2" smd roundrect
			(at 0.48 0 180)
			(size 0.59 0.64)
			(layers "F.Cu" "F.Mask" "F.Paste")
			(roundrect_rratio 0.25)
			(net 9 "+3V3")
			(pintype "passive")
		)
	)
	(footprint "antmicro-footprints:SW_KMR211NGLFS_SMD"
		(layer "F.Cu")
		(at 136.042962 122.6915 -90)
		(property "Reference" "S201"
			(at 3.4085 0.767962 0)
			(layer "F.SilkS")
			(effects
				(font
					(size 0.7 0.7)
					(thickness 0.15)
				)
				(justify left bottom)
			)
		)
		(property "Value" "SW_KMR211NGLFS_SMD"
			(at 0 2.8 90)
			(layer "F.Fab")
			(effects
				(font
					(size 0.7 0.7)
					(thickness 0.15)
				)
				(justify right bottom)
			)
		)
		(property "Datasheet" "http://www.farnell.com/datasheets/2631211.pdf"
			(at 0 0 270)
			(layer "F.Fab")
			(hide yes)
			(effects
				(font
					(size 1.27 1.27)
					(thickness 0.15)
				)
			)
		)
		(property "MPN" "KMR211NGLFS"
			(at 0 0 270)
			(unlocked yes)
			(layer "F.Fab")
			(hide yes)
			(effects
				(font
					(size 1 1)
					(thickness 0.15)
				)
			)
		)
		(property "Manufacturer" "C&K"
			(at 0 0 270)
			(unlocked yes)
			(layer "F.Fab")
			(hide yes)
			(effects
				(font
					(size 1 1)
					(thickness 0.15)
				)
			)
		)
		(property "Author" "Antmicro"
			(at 0 0 270)
			(unlocked yes)
			(layer "F.Fab")
			(hide yes)
			(effects
				(font
					(size 1 1)
					(thickness 0.15)
				)
			)
		)
		(property "License" "Apache-2.0"
			(at 0 0 270)
			(unlocked yes)
			(layer "F.Fab")
			(hide yes)
			(effects
				(font
					(size 1 1)
					(thickness 0.15)
				)
			)
		)
		(sheetname "/Compute module/")
		(sheetfile "compute-module.kicad_sch")
		(attr smd)
		(fp_line
			(start -2.1 1.601)
			(end -2.1 1.48)
			(stroke
				(width 0.15)
				(type solid)
			)
			(layer "F.SilkS")
		)
		(fp_line
			(start 2.101 1.601)
			(end -2.1 1.601)
			(stroke
				(width 0.15)
				(type solid)
			)
			(layer "F.SilkS")
		)
		(fp_line
			(start 2.101 1.601)
			(end 2.101 1.48)
			(stroke
				(width 0.15)
				(type solid)
			)
			(layer "F.SilkS")
		)
		(fp_line
			(start 2.101 -1.58)
			(end 2.101 -1.459)
			(stroke
				(width 0.15)
				(type solid)
			)
			(layer "F.SilkS")
		)
		(fp_line
			(start -2.1 -1.6)
			(end -2.1 -1.499)
			(stroke
				(width 0.15)
				(type solid)
			)
			(layer "F.SilkS")
		)
		(fp_line
			(start 2.101 -1.6)
			(end -2.1 -1.6)
			(stroke
				(width 0.15)
				(type solid)
			)
			(layer "F.SilkS")
		)
		(fp_rect
			(start 2.751 1.75)
			(end -2.748 -1.749)
			(stroke
				(width 0.05)
				(type solid)
			)
			(fill no)
			(layer "F.CrtYd")
		)
		(fp_line
			(start -2.1 1.601)
			(end 2.101 1.601)
			(stroke
				(width 0.15)
				(type solid)
			)
			(layer "F.Fab")
		)
		(fp_line
			(start 2.101 1.601)
			(end 2.101 -1.6)
			(stroke
				(width 0.15)
				(type solid)
			)
			(layer "F.Fab")
		)
		(fp_line
			(start 0.25 0.802)
			(end -0.248 0.802)
			(stroke
				(width 0.15)
				(type solid)
			)
			(layer "F.Fab")
		)
		(fp_line
			(start -0.248 -0.8)
			(end 0.25 -0.8)
			(stroke
				(width 0.15)
				(type solid)
			)
			(layer "F.Fab")
		)
		(fp_line
			(start -2.1 -1.6)
			(end -2.1 1.601)
			(stroke
				(width 0.15)
				(type solid)
			)
			(layer "F.Fab")
		)
		(fp_line
			(start 2.101 -1.6)
			(end -2.1 -1.6)
			(stroke
				(width 0.15)
				(type solid)
			)
			(layer "F.Fab")
		)
		(fp_arc
			(start -0.248 0.802)
			(mid -1.050001 0.001)
			(end -0.248 -0.8)
			(stroke
				(width 0.15)
				(type solid)
			)
			(layer "F.Fab")
		)
		(fp_arc
			(start 0.25 -0.8)
			(mid 1.051001 0.001)
			(end 0.25 0.802)
			(stroke
				(width 0.15)
				(type solid)
			)
			(layer "F.Fab")
		)
		(fp_text user "${REFERENCE}"
			(at -3 4.25 270)
			(layer "F.Fab")
			(effects
				(font
					(size 0.7 0.7)
					(thickness 0.15)
				)
				(justify left bottom)
			)
		)
		(fp_text user "Author: Antmicro"
			(at -3 5.5 270)
			(layer "F.Fab")
			(effects
				(font
					(size 0.7 0.7)
					(thickness 0.15)
				)
				(justify left bottom)
			)
		)
		(fp_text user "License: Apache-2.0"
			(at -3 6.75 270)
			(layer "F.Fab")
			(effects
				(font
					(size 0.7 0.7)
					(thickness 0.15)
				)
				(justify left bottom)
			)
		)
		(pad "1" smd rect
			(at -2.048 -0.8 90)
			(size 0.9 1)
			(layers "F.Cu" "F.Mask" "F.Paste")
			(net 9 "+3V3")
			(pinfunction "1")
			(pintype "passive")
		)
		(pad "2" smd rect
			(at 2.05 -0.8 90)
			(size 0.9 1)
			(layers "F.Cu" "F.Mask" "F.Paste")
			(net 9 "+3V3")
			(pinfunction "2")
			(pintype "passive")
		)
		(pad "3" smd rect
			(at -2.048 0.802 90)
			(size 0.9 1)
			(layers "F.Cu" "F.Mask" "F.Paste")
			(net 2 "Net-(D203-A)")
			(pinfunction "3")
			(pintype "passive")
		)
		(pad "4" smd rect
			(at 2.05 0.802 90)
			(size 0.9 1)
			(layers "F.Cu" "F.Mask" "F.Paste")
			(net 2 "Net-(D203-A)")
			(pinfunction "4")
			(pintype "passive")
		)
	)
	(footprint "antmicro-footprints:TP_SMD_0.75mm"
		(layer "F.Cu")
		(at 76.742962 164.6915 180)
		(property "Reference" "TP209"
			(at 8.975 0.575 0)
			(layer "F.SilkS")
			(effects
				(font
					(size 0.7 0.7)
					(thickness 0.15)
				)
				(justify right bottom)
			)
		)
		(property "Value" "TP_0.75mm_SMD"
			(at 0 1.2 0)
			(layer "F.Fab")
			(effects
				(font
					(size 0.7 0.7)
					(thickness 0.15)
				)
				(justify right bottom)
			)
		)
		(property "Author" "Antmicro"
			(at 0 0 180)
			(unlocked yes)
			(layer "F.Fab")
			(hide yes)
			(effects
				(font
					(size 1 1)
					(thickness 0.15)
				)
			)
		)
		(property "License" "Apache-2.0"
			(at 0 0 180)
			(unlocked yes)
			(layer "F.Fab")
			(hide yes)
			(effects
				(font
					(size 1 1)
					(thickness 0.15)
				)
			)
		)
		(property "MPN" ""
			(at 0 0 180)
			(unlocked yes)
			(layer "F.Fab")
			(hide yes)
			(effects
				(font
					(size 1 1)
					(thickness 0.15)
				)
			)
		)
		(property "Manufacturer" ""
			(at 0 0 180)
			(unlocked yes)
			(layer "F.Fab")
			(hide yes)
			(effects
				(font
					(size 1 1)
					(thickness 0.15)
				)
			)
		)
		(sheetname "/Compute module/")
		(sheetfile "compute-module.kicad_sch")
		(attr exclude_from_pos_files exclude_from_bom)
		(fp_circle
			(center 0 0)
			(end 0.475 0)
			(stroke
				(width 0.05)
				(type default)
			)
			(fill no)
			(layer "F.CrtYd")
		)
		(fp_text user "Author: Antmicro"
			(at -0.4 3.901 180)
			(layer "F.Fab")
			(effects
				(font
					(size 0.7 0.7)
					(thickness 0.15)
				)
				(justify left bottom)
			)
		)
		(fp_text user "${REFERENCE}"
			(at -0.4 2.7 180)
			(layer "F.Fab")
			(effects
				(font
					(size 0.7 0.7)
					(thickness 0.15)
				)
				(justify left bottom)
			)
		)
		(fp_text user "License: Apache-2.0"
			(at -0.4 5.101 180)
			(layer "F.Fab")
			(effects
				(font
					(size 0.7 0.7)
					(thickness 0.15)
				)
				(justify left bottom)
			)
		)
		(pad "1" smd circle
			(at 0 0 180)
			(size 0.75 0.75)
			(layers "F.Cu" "F.Mask")
			(net 254 "/Compute module/CAM_GPIO")
			(pinfunction "1")
			(pintype "passive")
		)
	)
	(footprint "antmicro-footprints:C_0402_1005Metric"
		(layer "F.Cu")
		(at 71.742962 176.5165 -90)
		(descr "Capacitor SMD 0402")
		(tags "capacitor SMD 0402")
		(property "Reference" "C805"
			(at -1.3165 0.492962 270)
			(layer "F.SilkS")
			(effects
				(font
					(size 0.7 0.7)
					(thickness 0.15)
				)
				(justify right bottom)
			)
		)
		(property "Value" "C_2u2_0402"
			(at -1.022927 2.155213 90)
			(layer "F.Fab")
			(effects
				(font
					(size 0.7 0.7)
					(thickness 0.15)
				)
				(justify right bottom)
			)
		)
		(property "Datasheet" "https://product.tdk.com/en/search/capacitor/ceramic/mlcc/info?part_no=C1005X5R1A225K050BC"
			(at 0 0 270)
			(layer "F.Fab")
			(hide yes)
			(effects
				(font
					(size 1.27 1.27)
					(thickness 0.15)
				)
			)
		)
		(property "MPN" "C1005X5R1A225K050BC"
			(at 0 0 270)
			(unlocked yes)
			(layer "F.Fab")
			(hide yes)
			(effects
				(font
					(size 1 1)
					(thickness 0.15)
				)
			)
		)
		(property "Manufacturer" "TDK"
			(at 0 0 270)
			(unlocked yes)
			(layer "F.Fab")
			(hide yes)
			(effects
				(font
					(size 1 1)
					(thickness 0.15)
				)
			)
		)
		(property "License" "Apache-2.0"
			(at 0 0 270)
			(unlocked yes)
			(layer "F.Fab")
			(hide yes)
			(effects
				(font
					(size 1 1)
					(thickness 0.15)
				)
			)
		)
		(property "Author" "Antmicro"
			(at 0 0 270)
			(unlocked yes)
			(layer "F.Fab")
			(hide yes)
			(effects
				(font
					(size 1 1)
					(thickness 0.15)
				)
			)
		)
		(property "Val" "2u2"
			(at 0 0 270)
			(unlocked yes)
			(layer "F.Fab")
			(hide yes)
			(effects
				(font
					(size 1 1)
					(thickness 0.15)
				)
			)
		)
		(property "Voltage" ""
			(at 0 0 270)
			(unlocked yes)
			(layer "F.Fab")
			(hide yes)
			(effects
				(font
					(size 1 1)
					(thickness 0.15)
				)
			)
		)
		(property "Dielectric" ""
			(at 0 0 270)
			(unlocked yes)
			(layer "F.Fab")
			(hide yes)
			(effects
				(font
					(size 1 1)
					(thickness 0.15)
				)
			)
		)
		(sheetname "/Peripherals/")
		(sheetfile "peripherals.kicad_sch")
		(attr smd)
		(fp_rect
			(start -0.925 -0.47)
			(end 0.925 0.47)
			(stroke
				(width 0.05)
				(type default)
			)
			(fill no)
			(layer "F.CrtYd")
		)
		(fp_line
			(start -0.494 0.248)
			(end -0.494 -0.25)
			(stroke
				(width 0.15)
				(type solid)
			)
			(layer "F.Fab")
		)
		(fp_line
			(start 0.504 0.248)
			(end -0.494 0.248)
			(stroke
				(width 0.15)
				(type solid)
			)
			(layer "F.Fab")
		)
		(fp_line
			(start -0.494 -0.25)
			(end 0.504 -0.25)
			(stroke
				(width 0.15)
				(type solid)
			)
			(layer "F.Fab")
		)
		(fp_line
			(start 0.504 -0.25)
			(end 0.504 0.248)
			(stroke
				(width 0.15)
				(type solid)
			)
			(layer "F.Fab")
		)
		(fp_text user "Author: Antmicro"
			(at -0.939 3.399 270)
			(layer "F.Fab")
			(effects
				(font
					(size 0.7 0.7)
					(thickness 0.15)
				)
				(justify left bottom)
			)
		)
		(fp_text user "${REFERENCE}"
			(at -0.939 4.599 270)
			(layer "F.Fab")
			(effects
				(font
					(size 0.7 0.7)
					(thickness 0.15)
				)
				(justify left bottom)
			)
		)
		(fp_text user "License: Apache-2.0"
			(at -0.939 5.799 270)
			(layer "F.Fab")
			(effects
				(font
					(size 0.7 0.7)
					(thickness 0.15)
				)
				(justify left bottom)
			)
		)
		(pad "1" smd roundrect
			(at -0.48 0 270)
			(size 0.59 0.64)
			(layers "F.Cu" "F.Mask" "F.Paste")
			(roundrect_rratio 0.25)
			(net 93 "Net-(U801-V_{DD(A)})")
			(pintype "passive")
		)
		(pad "2" smd roundrect
			(at 0.48 0 270)
			(size 0.59 0.64)
			(layers "F.Cu" "F.Mask" "F.Paste")
			(roundrect_rratio 0.25)
			(net 3 "GND")
			(pintype "passive")
		)
	)
	(footprint "antmicro-footprints:R_0402_1005Metric"
		(layer "F.Cu")
		(at 116.467962 134.9415 -90)
		(descr "Resistor SMD 0402")
		(tags "resistor SMD 0402")
		(property "Reference" "R510"
			(at -1.195 0.52 270)
			(layer "F.SilkS")
			(effects
				(font
					(size 0.7 0.7)
					(thickness 0.15)
				)
				(justify right bottom)
			)
		)
		(property "Value" "R_470R_0402"
			(at -1.011843 1.772047 90)
			(layer "F.Fab")
			(effects
				(font
					(size 0.7 0.7)
					(thickness 0.15)
				)
				(justify right bottom)
			)
		)
		(property "Datasheet" "https://www.bourns.com/docs/product-datasheets/cr.pdf"
			(at 0 0 270)
			(layer "F.Fab")
			(hide yes)
			(effects
				(font
					(size 1.27 1.27)
					(thickness 0.15)
				)
			)
		)
		(property "Manufacturer" "Bourns"
			(at 0 0 270)
			(unlocked yes)
			(layer "F.Fab")
			(hide yes)
			(effects
				(font
					(size 1 1)
					(thickness 0.15)
				)
			)
		)
		(property "MPN" "CR0402-FX-4700GLF"
			(at 0 0 270)
			(unlocked yes)
			(layer "F.Fab")
			(hide yes)
			(effects
				(font
					(size 1 1)
					(thickness 0.15)
				)
			)
		)
		(property "Val" "470R"
			(at 0 0 270)
			(unlocked yes)
			(layer "F.Fab")
			(hide yes)
			(effects
				(font
					(size 1 1)
					(thickness 0.15)
				)
			)
		)
		(property "License" "Apache-2.0"
			(at 0 0 270)
			(unlocked yes)
			(layer "F.Fab")
			(hide yes)
			(effects
				(font
					(size 1 1)
					(thickness 0.15)
				)
			)
		)
		(property "Author" "Antmicro"
			(at 0 0 270)
			(unlocked yes)
			(layer "F.Fab")
			(hide yes)
			(effects
				(font
					(size 1 1)
					(thickness 0.15)
				)
			)
		)
		(property "Tolerance" "1%"
			(at 0 0 270)
			(unlocked yes)
			(layer "F.Fab")
			(hide yes)
			(effects
				(font
					(size 1 1)
					(thickness 0.15)
				)
			)
		)
		(sheetname "/NVMe & microSD/")
		(sheetfile "nvme-micro-sd.kicad_sch")
		(attr smd)
		(fp_rect
			(start -0.925 -0.47)
			(end 0.925 0.47)
			(stroke
				(width 0.05)
				(type default)
			)
			(fill no)
			(layer "F.CrtYd")
		)
		(fp_rect
			(start -0.5 -0.25)
			(end 0.5 0.25)
			(stroke
				(width 0.15)
				(type solid)
			)
			(fill no)
			(layer "F.Fab")
		)
		(fp_text user "Author: Antmicro"
			(at -0.95 4.169 270)
			(layer "F.Fab")
			(effects
				(font
					(size 0.7 0.7)
					(thickness 0.15)
				)
				(justify left bottom)
			)
		)
		(fp_text user "License: Apache-2.0"
			(at -0.95 5.169 270)
			(layer "F.Fab")
			(effects
				(font
					(size 0.7 0.7)
					(thickness 0.15)
				)
				(justify left bottom)
			)
		)
		(fp_text user "${REFERENCE}"
			(at -0.95 3.168 270)
			(layer "F.Fab")
			(effects
				(font
					(size 0.7 0.7)
					(thickness 0.15)
				)
				(justify left bottom)
			)
		)
		(pad "1" smd roundrect
			(at -0.48 0 270)
			(size 0.59 0.64)
			(layers "F.Cu" "F.Mask" "F.Paste")
			(roundrect_rratio 0.25)
			(net 478 "Net-(D503-A)")
			(pintype "passive")
		)
		(pad "2" smd roundrect
			(at 0.48 0 270)
			(size 0.59 0.64)
			(layers "F.Cu" "F.Mask" "F.Paste")
			(roundrect_rratio 0.25)
			(net 65 "3V3_SSD")
			(pintype "passive")
		)
	)
	(footprint "antmicro-footprints:LED_0402_1005Metric_Y"
		(layer "F.Cu")
		(at 75.867962 136.0415 180)
		(property "Reference" "D911"
			(at 5.54752 -0.428183 0)
			(unlocked yes)
			(layer "F.SilkS")
			(effects
				(font
					(size 0.7 0.7)
					(thickness 0.15)
				)
				(justify left bottom)
			)
		)
		(property "Value" "LED_Y_0402_VLMY1500-GS08"
			(at 0.298 4.099 180)
			(unlocked yes)
			(layer "F.Fab")
			(effects
				(font
					(size 0.7 0.7)
					(thickness 0.15)
				)
				(justify left bottom)
			)
		)
		(property "Datasheet" "https://www.vishay.com/docs/82554/vlmo1500.pdf"
			(at 0 0 180)
			(layer "F.Fab")
			(hide yes)
			(effects
				(font
					(size 1.27 1.27)
					(thickness 0.15)
				)
			)
		)
		(property "MPN" "VLMY1500-GS08"
			(at 0 0 180)
			(unlocked yes)
			(layer "F.Fab")
			(hide yes)
			(effects
				(font
					(size 1 1)
					(thickness 0.15)
				)
			)
		)
		(property "Manufacturer" "Vishay"
			(at 0 0 180)
			(unlocked yes)
			(layer "F.Fab")
			(hide yes)
			(effects
				(font
					(size 1 1)
					(thickness 0.15)
				)
			)
		)
		(property "Author" "Antmicro"
			(at 0 0 180)
			(unlocked yes)
			(layer "F.Fab")
			(hide yes)
			(effects
				(font
					(size 1 1)
					(thickness 0.15)
				)
			)
		)
		(property "License" "Apache-2.0"
			(at 0 0 180)
			(unlocked yes)
			(layer "F.Fab")
			(hide yes)
			(effects
				(font
					(size 1 1)
					(thickness 0.15)
				)
			)
		)
		(property "Color" "Yellow"
			(at 0 0 180)
			(unlocked yes)
			(layer "F.Fab")
			(hide yes)
			(effects
				(font
					(size 1 1)
					(thickness 0.15)
				)
			)
		)
		(sheetname "/USB/")
		(sheetfile "usb.kicad_sch")
		(attr smd)
		(fp_line
			(start 0.175 0.4)
			(end -0.175 0.4)
			(stroke
				(width 0.15)
				(type solid)
			)
			(layer "F.SilkS")
		)
		(fp_line
			(start 0.175 -0.4)
			(end -0.175 -0.4)
			(stroke
				(width 0.15)
				(type solid)
			)
			(layer "F.SilkS")
		)
		(fp_line
			(start -0.9 0.4)
			(end -0.9 -0.4)
			(stroke
				(width 0.15)
				(type solid)
			)
			(layer "F.SilkS")
		)
		(fp_rect
			(start 0.925 0.47)
			(end -0.925 -0.47)
			(stroke
				(width 0.05)
				(type default)
			)
			(fill no)
			(layer "F.CrtYd")
		)
		(fp_line
			(start 0.501 0.26)
			(end 0.501 -0.248)
			(stroke
				(width 0.15)
				(type solid)
			)
			(layer "F.Fab")
		)
		(fp_line
			(start 0.501 0.26)
			(end 0.501 -0.248)
			(stroke
				(width 0.15)
				(type solid)
			)
			(layer "F.Fab")
		)
		(fp_line
			(start 0.501 -0.248)
			(end 0.172 -0.248)
			(stroke
				(width 0.15)
				(type solid)
			)
			(layer "F.Fab")
		)
		(fp_line
			(start 0.501 -0.248)
			(end -0.489 -0.248)
			(stroke
				(width 0.15)
				(type solid)
			)
			(layer "F.Fab")
		)
		(fp_line
			(start 0.228 0.202)
			(end 0.228 0)
			(stroke
				(width 0.15)
				(type solid)
			)
			(layer "F.Fab")
		)
		(fp_line
			(start 0.228 0)
			(end 0.228 -0.202)
			(stroke
				(width 0.15)
				(type solid)
			)
			(layer "F.Fab")
		)
		(fp_line
			(start 0.228 -0.202)
			(end -0.074 0)
			(stroke
				(width 0.15)
				(type solid)
			)
			(layer "F.Fab")
		)
		(fp_line
			(start 0.172 0.26)
			(end 0.501 0.26)
			(stroke
				(width 0.15)
				(type solid)
			)
			(layer "F.Fab")
		)
		(fp_line
			(start 0.172 -0.248)
			(end 0.172 0.26)
			(stroke
				(width 0.15)
				(type solid)
			)
			(layer "F.Fab")
		)
		(fp_line
			(start -0.074 0)
			(end 0.228 0.202)
			(stroke
				(width 0.15)
				(type solid)
			)
			(layer "F.Fab")
		)
		(fp_line
			(start -0.158 0.26)
			(end -0.158 -0.248)
			(stroke
				(width 0.15)
				(type solid)
			)
			(layer "F.Fab")
		)
		(fp_line
			(start -0.158 -0.248)
			(end -0.489 -0.248)
			(stroke
				(width 0.15)
				(type solid)
			)
			(layer "F.Fab")
		)
		(fp_line
			(start -0.173 0.202)
			(end -0.173 0.102)
			(stroke
				(width 0.15)
				(type solid)
			)
			(layer "F.Fab")
		)
		(fp_line
			(start -0.173 -0.202)
			(end -0.173 0.102)
			(stroke
				(width 0.15)
				(type solid)
			)
			(layer "F.Fab")
		)
		(fp_line
			(start -0.489 0.26)
			(end 0.501 0.26)
			(stroke
				(width 0.15)
				(type solid)
			)
			(layer "F.Fab")
		)
		(fp_line
			(start -0.489 0.26)
			(end -0.158 0.26)
			(stroke
				(width 0.15)
				(type solid)
			)
			(layer "F.Fab")
		)
		(fp_line
			(start -0.489 -0.248)
			(end -0.489 0.26)
			(stroke
				(width 0.15)
				(type solid)
			)
			(layer "F.Fab")
		)
		(fp_line
			(start -0.489 -0.248)
			(end -0.489 0.26)
			(stroke
				(width 0.15)
				(type solid)
			)
			(layer "F.Fab")
		)
		(fp_text user "License: Apache-2.0"
			(at -1.105 8.499 180)
			(layer "F.Fab")
			(effects
				(font
					(size 0.7 0.7)
					(thickness 0.15)
				)
				(justify left bottom)
			)
		)
		(fp_text user "Author: Antmicro"
			(at -1.105 7.299 180)
			(layer "F.Fab")
			(effects
				(font
					(size 0.7 0.7)
					(thickness 0.15)
				)
				(justify left bottom)
			)
		)
		(fp_text user "${REFERENCE}"
			(at -1.105 6.099 180)
			(unlocked yes)
			(layer "F.Fab")
			(effects
				(font
					(size 0.7 0.7)
					(thickness 0.15)
				)
				(justify left bottom)
			)
		)
		(pad "1" smd roundrect
			(at -0.48 0)
			(size 0.59 0.64)
			(layers "F.Cu" "F.Mask" "F.Paste")
			(roundrect_rratio 0.25)
			(net 486 "Net-(D911-C)")
			(pinfunction "C")
			(pintype "passive")
		)
		(pad "2" smd roundrect
			(at 0.48 0)
			(size 0.59 0.64)
			(layers "F.Cu" "F.Mask" "F.Paste")
			(roundrect_rratio 0.25)
			(net 487 "Net-(D911-A)")
			(pinfunction "A")
			(pintype "passive")
		)
	)
	(footprint "antmicro-footprints:R_0402_1005Metric"
		(layer "F.Cu")
		(at 73.507962 159.6765)
		(descr "Resistor SMD 0402")
		(tags "resistor SMD 0402")
		(property "Reference" "R325"
			(at -8.71 -0.61 0)
			(layer "F.SilkS")
			(effects
				(font
					(size 0.7 0.7)
					(thickness 0.15)
				)
				(justify left bottom)
			)
		)
		(property "Value" "R_1k_0402"
			(at -1.011843 1.772047 0)
			(layer "F.Fab")
			(effects
				(font
					(size 0.7 0.7)
					(thickness 0.15)
				)
				(justify left bottom)
			)
		)
		(property "Datasheet" "https://www.bourns.com/docs/product-datasheets/cr.pdf"
			(at 0 0 0)
			(layer "F.Fab")
			(hide yes)
			(effects
				(font
					(size 1.27 1.27)
					(thickness 0.15)
				)
			)
		)
		(property "MPN" "CR0402-FX-1001GLF"
			(at 0 0 0)
			(unlocked yes)
			(layer "F.Fab")
			(hide yes)
			(effects
				(font
					(size 1 1)
					(thickness 0.15)
				)
			)
		)
		(property "Manufacturer" "Bourns"
			(at 0 0 0)
			(unlocked yes)
			(layer "F.Fab")
			(hide yes)
			(effects
				(font
					(size 1 1)
					(thickness 0.15)
				)
			)
		)
		(property "License" "Apache-2.0"
			(at 0 0 0)
			(unlocked yes)
			(layer "F.Fab")
			(hide yes)
			(effects
				(font
					(size 1 1)
					(thickness 0.15)
				)
			)
		)
		(property "Author" "Antmicro"
			(at 0 0 0)
			(unlocked yes)
			(layer "F.Fab")
			(hide yes)
			(effects
				(font
					(size 1 1)
					(thickness 0.15)
				)
			)
		)
		(property "Val" "1k"
			(at 0 0 0)
			(unlocked yes)
			(layer "F.Fab")
			(hide yes)
			(effects
				(font
					(size 1 1)
					(thickness 0.15)
				)
			)
		)
		(property "Tolerance" "1%"
			(at 0 0 0)
			(unlocked yes)
			(layer "F.Fab")
			(hide yes)
			(effects
				(font
					(size 1 1)
					(thickness 0.15)
				)
			)
		)
		(sheetname "/Supply/")
		(sheetfile "supply.kicad_sch")
		(attr smd)
		(fp_rect
			(start -0.925 -0.47)
			(end 0.925 0.47)
			(stroke
				(width 0.05)
				(type default)
			)
			(fill no)
			(layer "F.CrtYd")
		)
		(fp_rect
			(start -0.5 -0.25)
			(end 0.5 0.25)
			(stroke
				(width 0.15)
				(type solid)
			)
			(fill no)
			(layer "F.Fab")
		)
		(fp_text user "${REFERENCE}"
			(at -0.95 3.168 0)
			(layer "F.Fab")
			(effects
				(font
					(size 0.7 0.7)
					(thickness 0.15)
				)
				(justify left bottom)
			)
		)
		(fp_text user "Author: Antmicro"
			(at -0.95 4.169 0)
			(layer "F.Fab")
			(effects
				(font
					(size 0.7 0.7)
					(thickness 0.15)
				)
				(justify left bottom)
			)
		)
		(fp_text user "License: Apache-2.0"
			(at -0.95 5.169 0)
			(layer "F.Fab")
			(effects
				(font
					(size 0.7 0.7)
					(thickness 0.15)
				)
				(justify left bottom)
			)
		)
		(pad "1" smd roundrect
			(at -0.48 0)
			(size 0.59 0.64)
			(layers "F.Cu" "F.Mask" "F.Paste")
			(roundrect_rratio 0.25)
			(net 474 "Net-(D304-A)")
			(pintype "passive")
		)
		(pad "2" smd roundrect
			(at 0.48 0)
			(size 0.59 0.64)
			(layers "F.Cu" "F.Mask" "F.Paste")
			(roundrect_rratio 0.25)
			(net 10 "+5V")
			(pintype "passive")
		)
	)
	(footprint "antmicro-footprints:R_0402_1005Metric"
		(layer "F.Cu")
		(at 76.167962 153.7915)
		(descr "Resistor SMD 0402")
		(tags "resistor SMD 0402")
		(property "Reference" "R229"
			(at 1.75 1.445 90)
			(layer "F.SilkS")
			(effects
				(font
					(size 0.7 0.7)
					(thickness 0.15)
				)
				(justify left bottom)
			)
		)
		(property "Value" "R_1k_0402"
			(at -1.011843 1.772047 0)
			(layer "F.Fab")
			(effects
				(font
					(size 0.7 0.7)
					(thickness 0.15)
				)
				(justify left bottom)
			)
		)
		(property "Datasheet" "https://www.bourns.com/docs/product-datasheets/cr.pdf"
			(at 0 0 0)
			(layer "F.Fab")
			(hide yes)
			(effects
				(font
					(size 1.27 1.27)
					(thickness 0.15)
				)
			)
		)
		(property "MPN" "CR0402-FX-1001GLF"
			(at 0 0 0)
			(unlocked yes)
			(layer "F.Fab")
			(hide yes)
			(effects
				(font
					(size 1 1)
					(thickness 0.15)
				)
			)
		)
		(property "Manufacturer" "Bourns"
			(at 0 0 0)
			(unlocked yes)
			(layer "F.Fab")
			(hide yes)
			(effects
				(font
					(size 1 1)
					(thickness 0.15)
				)
			)
		)
		(property "License" "Apache-2.0"
			(at 0 0 0)
			(unlocked yes)
			(layer "F.Fab")
			(hide yes)
			(effects
				(font
					(size 1 1)
					(thickness 0.15)
				)
			)
		)
		(property "Author" "Antmicro"
			(at 0 0 0)
			(unlocked yes)
			(layer "F.Fab")
			(hide yes)
			(effects
				(font
					(size 1 1)
					(thickness 0.15)
				)
			)
		)
		(property "Val" "1k"
			(at 0 0 0)
			(unlocked yes)
			(layer "F.Fab")
			(hide yes)
			(effects
				(font
					(size 1 1)
					(thickness 0.15)
				)
			)
		)
		(property "Tolerance" "1%"
			(at 0 0 0)
			(unlocked yes)
			(layer "F.Fab")
			(hide yes)
			(effects
				(font
					(size 1 1)
					(thickness 0.15)
				)
			)
		)
		(sheetname "/Compute module/")
		(sheetfile "compute-module.kicad_sch")
		(attr smd)
		(fp_rect
			(start -0.925 -0.47)
			(end 0.925 0.47)
			(stroke
				(width 0.05)
				(type default)
			)
			(fill no)
			(layer "F.CrtYd")
		)
		(fp_rect
			(start -0.5 -0.25)
			(end 0.5 0.25)
			(stroke
				(width 0.15)
				(type solid)
			)
			(fill no)
			(layer "F.Fab")
		)
		(fp_text user "${REFERENCE}"
			(at -0.95 3.168 0)
			(layer "F.Fab")
			(effects
				(font
					(size 0.7 0.7)
					(thickness 0.15)
				)
				(justify left bottom)
			)
		)
		(fp_text user "Author: Antmicro"
			(at -0.95 4.169 0)
			(layer "F.Fab")
			(effects
				(font
					(size 0.7 0.7)
					(thickness 0.15)
				)
				(justify left bottom)
			)
		)
		(fp_text user "License: Apache-2.0"
			(at -0.95 5.169 0)
			(layer "F.Fab")
			(effects
				(font
					(size 0.7 0.7)
					(thickness 0.15)
				)
				(justify left bottom)
			)
		)
		(pad "1" smd roundrect
			(at -0.48 0)
			(size 0.59 0.64)
			(layers "F.Cu" "F.Mask" "F.Paste")
			(roundrect_rratio 0.25)
			(net 500 "Net-(Q214-D)")
			(pintype "passive")
		)
		(pad "2" smd roundrect
			(at 0.48 0)
			(size 0.59 0.64)
			(layers "F.Cu" "F.Mask" "F.Paste")
			(roundrect_rratio 0.25)
			(net 466 "Net-(D206-C)")
			(pintype "passive")
		)
	)
	(footprint "antmicro-footprints:TP_SMD_0.75mm"
		(layer "F.Cu")
		(at 75.75 170.65 -90)
		(property "Reference" "TP801"
			(at -1.94 -8.305 0)
			(layer "F.SilkS")
			(effects
				(font
					(size 0.7 0.7)
					(thickness 0.15)
				)
				(justify left bottom)
			)
		)
		(property "Value" "TP_0.75mm_SMD"
			(at 0 1.2 270)
			(layer "F.Fab")
			(effects
				(font
					(size 0.7 0.7)
					(thickness 0.15)
				)
				(justify left bottom)
			)
		)
		(property "Author" "Antmicro"
			(at 0 0 270)
			(unlocked yes)
			(layer "F.Fab")
			(hide yes)
			(effects
				(font
					(size 1 1)
					(thickness 0.15)
				)
			)
		)
		(property "License" "Apache-2.0"
			(at 0 0 270)
			(unlocked yes)
			(layer "F.Fab")
			(hide yes)
			(effects
				(font
					(size 1 1)
					(thickness 0.15)
				)
			)
		)
		(property "MPN" ""
			(at 0 0 270)
			(unlocked yes)
			(layer "F.Fab")
			(hide yes)
			(effects
				(font
					(size 1 1)
					(thickness 0.15)
				)
			)
		)
		(property "Manufacturer" ""
			(at 0 0 270)
			(unlocked yes)
			(layer "F.Fab")
			(hide yes)
			(effects
				(font
					(size 1 1)
					(thickness 0.15)
				)
			)
		)
		(sheetname "/Peripherals/")
		(sheetfile "peripherals.kicad_sch")
		(attr exclude_from_pos_files exclude_from_bom)
		(fp_circle
			(center 0 0)
			(end 0.475 0)
			(stroke
				(width 0.05)
				(type default)
			)
			(fill no)
			(layer "F.CrtYd")
		)
		(fp_text user "${REFERENCE}"
			(at -0.4 2.7 270)
			(layer "F.Fab")
			(effects
				(font
					(size 0.7 0.7)
					(thickness 0.15)
				)
				(justify left bottom)
			)
		)
		(fp_text user "Author: Antmicro"
			(at -0.4 3.901 270)
			(layer "F.Fab")
			(effects
				(font
					(size 0.7 0.7)
					(thickness 0.15)
				)
				(justify left bottom)
			)
		)
		(fp_text user "License: Apache-2.0"
			(at -0.4 5.101 270)
			(layer "F.Fab")
			(effects
				(font
					(size 0.7 0.7)
					(thickness 0.15)
				)
				(justify left bottom)
			)
		)
		(pad "1" smd circle
			(at 0 0 270)
			(size 0.75 0.75)
			(layers "F.Cu" "F.Mask")
			(net 381 "Net-(U801-DCDC_EN)")
			(pinfunction "1")
			(pintype "passive")
		)
	)
	(footprint "antmicro-footprints:TP_SMD_0.75mm"
		(layer "F.Cu")
		(at 73.717962 133.1165)
		(property "Reference" "TP308"
			(at -9.217962 2.282028 0)
			(layer "F.SilkS")
			(effects
				(font
					(size 0.7 0.7)
					(thickness 0.15)
				)
				(justify left bottom)
			)
		)
		(property "Value" "TP_0.75mm_SMD"
			(at 0 1.2 0)
			(layer "F.Fab")
			(effects
				(font
					(size 0.7 0.7)
					(thickness 0.15)
				)
				(justify left bottom)
			)
		)
		(property "MPN" ""
			(at 0 0 0)
			(unlocked yes)
			(layer "F.Fab")
			(hide yes)
			(effects
				(font
					(size 1 1)
					(thickness 0.15)
				)
			)
		)
		(property "Manufacturer" ""
			(at 0 0 0)
			(unlocked yes)
			(layer "F.Fab")
			(hide yes)
			(effects
				(font
					(size 1 1)
					(thickness 0.15)
				)
			)
		)
		(property "Author" "Antmicro"
			(at 0 0 0)
			(unlocked yes)
			(layer "F.Fab")
			(hide yes)
			(effects
				(font
					(size 1 1)
					(thickness 0.15)
				)
			)
		)
		(property "License" "Apache-2.0"
			(at 0 0 0)
			(unlocked yes)
			(layer "F.Fab")
			(hide yes)
			(effects
				(font
					(size 1 1)
					(thickness 0.15)
				)
			)
		)
		(sheetname "/Supply/")
		(sheetfile "supply.kicad_sch")
		(attr exclude_from_pos_files exclude_from_bom)
		(fp_circle
			(center 0 0)
			(end 0.475 0)
			(stroke
				(width 0.05)
				(type default)
			)
			(fill no)
			(layer "F.CrtYd")
		)
		(fp_text user "${REFERENCE}"
			(at -0.4 2.7 0)
			(layer "F.Fab")
			(effects
				(font
					(size 0.7 0.7)
					(thickness 0.15)
				)
				(justify left bottom)
			)
		)
		(fp_text user "License: Apache-2.0"
			(at -0.4 5.101 0)
			(layer "F.Fab")
			(effects
				(font
					(size 0.7 0.7)
					(thickness 0.15)
				)
				(justify left bottom)
			)
		)
		(fp_text user "Author: Antmicro"
			(at -0.4 3.901 0)
			(layer "F.Fab")
			(effects
				(font
					(size 0.7 0.7)
					(thickness 0.15)
				)
				(justify left bottom)
			)
		)
		(pad "1" smd circle
			(at 0 0)
			(size 0.75 0.75)
			(layers "F.Cu" "F.Mask")
			(net 443 "/Supply/V_{BUS}")
			(pinfunction "1")
			(pintype "passive")
			(zone_connect 2)
		)
	)
	(footprint "antmicro-footprints:SOT-23-3"
		(layer "F.Cu")
		(at 107.467962 148.467)
		(property "Reference" "Q203"
			(at -1.8 -1.8 0)
			(layer "F.SilkS")
			(effects
				(font
					(size 0.7 0.7)
					(thickness 0.15)
				)
				(justify left bottom)
			)
		)
		(property "Value" "SSM3J332R"
			(at -1.9 2.7 0)
			(layer "F.Fab")
			(effects
				(font
					(size 0.7 0.7)
					(thickness 0.15)
				)
				(justify left bottom)
			)
		)
		(property "Datasheet" "https://www.mouser.com/datasheet/2/408/SSM3J332R_datasheet_en_20181015-1150575.pdf"
			(at 0 0 0)
			(layer "F.Fab")
			(hide yes)
			(effects
				(font
					(size 1.27 1.27)
					(thickness 0.15)
				)
			)
		)
		(property "MPN" "SSM3J332R,LF"
			(at 0 0 0)
			(unlocked yes)
			(layer "F.Fab")
			(hide yes)
			(effects
				(font
					(size 1 1)
					(thickness 0.15)
				)
			)
		)
		(property "Manufacturer" "Toshiba"
			(at 0 0 0)
			(unlocked yes)
			(layer "F.Fab")
			(hide yes)
			(effects
				(font
					(size 1 1)
					(thickness 0.15)
				)
			)
		)
		(property "Author" "Antmicro"
			(at 0 0 0)
			(unlocked yes)
			(layer "F.Fab")
			(hide yes)
			(effects
				(font
					(size 1 1)
					(thickness 0.15)
				)
			)
		)
		(property "License" "Apache-2.0"
			(at 0 0 0)
			(unlocked yes)
			(layer "F.Fab")
			(hide yes)
			(effects
				(font
					(size 1 1)
					(thickness 0.15)
				)
			)
		)
		(sheetname "/Compute module/")
		(sheetfile "compute-module.kicad_sch")
		(attr smd)
		(fp_line
			(start -1.45 -1.35)
			(end -0.85 -1.35)
			(stroke
				(width 0.15)
				(type solid)
			)
			(layer "F.SilkS")
		)
		(fp_line
			(start -0.85 -1.35)
			(end -0.7 -1.5)
			(stroke
				(width 0.15)
				(type solid)
			)
			(layer "F.SilkS")
		)
		(fp_line
			(start -0.7 1.5)
			(end -0.7 1.35)
			(stroke
				(width 0.15)
				(type solid)
			)
			(layer "F.SilkS")
		)
		(fp_line
			(start 0.7 -1.5)
			(end -0.7 -1.5)
			(stroke
				(width 0.15)
				(type solid)
			)
			(layer "F.SilkS")
		)
		(fp_line
			(start 0.7 -0.4)
			(end 0.7 -1.5)
			(stroke
				(width 0.15)
				(type solid)
			)
			(layer "F.SilkS")
		)
		(fp_line
			(start 0.7 0.4)
			(end 0.7 1.5)
			(stroke
				(width 0.15)
				(type solid)
			)
			(layer "F.SilkS")
		)
		(fp_line
			(start 0.7 1.5)
			(end -0.7 1.5)
			(stroke
				(width 0.15)
				(type solid)
			)
			(layer "F.SilkS")
		)
		(fp_line
			(start -1.75 -0.5)
			(end -1.75 -1.4)
			(stroke
				(width 0.05)
				(type solid)
			)
			(layer "F.CrtYd")
		)
		(fp_line
			(start -1.75 0.5)
			(end -0.85 0.5)
			(stroke
				(width 0.05)
				(type solid)
			)
			(layer "F.CrtYd")
		)
		(fp_line
			(start -1.75 1.4)
			(end -1.75 0.5)
			(stroke
				(width 0.05)
				(type solid)
			)
			(layer "F.CrtYd")
		)
		(fp_line
			(start -0.9 -1.6)
			(end -0.9 -1.4)
			(stroke
				(width 0.05)
				(type solid)
			)
			(layer "F.CrtYd")
		)
		(fp_line
			(start -0.9 -1.6)
			(end 0.825 -1.6)
			(stroke
				(width 0.05)
				(type solid)
			)
			(layer "F.CrtYd")
		)
		(fp_line
			(start -0.9 -1.4)
			(end -1.75 -1.4)
			(stroke
				(width 0.05)
				(type solid)
			)
			(layer "F.CrtYd")
		)
		(fp_line
			(start -0.85 -0.5)
			(end -1.75 -0.5)
			(stroke
				(width 0.05)
				(type solid)
			)
			(layer "F.CrtYd")
		)
		(fp_line
			(start -0.85 0.5)
			(end -0.85 -0.5)
			(stroke
				(width 0.05)
				(type solid)
			)
			(layer "F.CrtYd")
		)
		(fp_line
			(start -0.85 1.4)
			(end -1.75 1.4)
			(stroke
				(width 0.05)
				(type solid)
			)
			(layer "F.CrtYd")
		)
		(fp_line
			(start -0.85 1.65)
			(end -0.85 1.4)
			(stroke
				(width 0.05)
				(type solid)
			)
			(layer "F.CrtYd")
		)
		(fp_line
			(start 0.825 -1.6)
			(end 0.825 -0.45)
			(stroke
				(width 0.05)
				(type solid)
			)
			(layer "F.CrtYd")
		)
		(fp_line
			(start 0.825 -0.45)
			(end 1.75 -0.45)
			(stroke
				(width 0.05)
				(type solid)
			)
			(layer "F.CrtYd")
		)
		(fp_line
			(start 0.85 0.45)
			(end 0.85 1.65)
			(stroke
				(width 0.05)
				(type solid)
			)
			(layer "F.CrtYd")
		)
		(fp_line
			(start 0.85 1.65)
			(end -0.85 1.65)
			(stroke
				(width 0.05)
				(type solid)
			)
			(layer "F.CrtYd")
		)
		(fp_line
			(start 1.75 -0.45)
			(end 1.75 0.45)
			(stroke
				(width 0.05)
				(type solid)
			)
			(layer "F.CrtYd")
		)
		(fp_line
			(start 1.75 0.45)
			(end 0.85 0.45)
			(stroke
				(width 0.05)
				(type solid)
			)
			(layer "F.CrtYd")
		)
		(fp_line
			(start -0.712 -1.325)
			(end -0.712 1.523)
			(stroke
				(width 0.15)
				(type solid)
			)
			(layer "F.Fab")
		)
		(fp_line
			(start -0.712 1.519)
			(end 0.688 1.519)
			(stroke
				(width 0.15)
				(type solid)
			)
			(layer "F.Fab")
		)
		(fp_line
			(start -0.437 -1.526)
			(end -0.712 -1.325)
			(stroke
				(width 0.15)
				(type solid)
			)
			(layer "F.Fab")
		)
		(fp_line
			(start -0.437 -1.526)
			(end 0.688 -1.526)
			(stroke
				(width 0.15)
				(type solid)
			)
			(layer "F.Fab")
		)
		(fp_line
			(start 0.688 1.519)
			(end 0.688 -1.52)
			(stroke
				(width 0.15)
				(type solid)
			)
			(layer "F.Fab")
		)
		(fp_text user "${REFERENCE}"
			(at -1.837 4 0)
			(layer "F.Fab")
			(effects
				(font
					(size 0.7 0.7)
					(thickness 0.15)
				)
				(justify left bottom)
			)
		)
		(fp_text user "License: Apache-2.0"
			(at -1.8 6.8 0)
			(layer "F.Fab")
			(effects
				(font
					(size 0.7 0.7)
					(thickness 0.15)
				)
				(justify left bottom)
			)
		)
		(fp_text user "Author: Antmicro"
			(at -1.837 5.3 0)
			(layer "F.Fab")
			(effects
				(font
					(size 0.7 0.7)
					(thickness 0.15)
				)
				(justify left bottom)
			)
		)
		(pad "1" smd roundrect
			(at -1.1 -0.951)
			(size 1 0.6)
			(layers "F.Cu" "F.Mask" "F.Paste")
			(roundrect_rratio 0.15)
			(net 327 "Net-(Q201-D)")
			(pinfunction "G")
			(pintype "input")
		)
		(pad "2" smd roundrect
			(at -1.1 0.949)
			(size 1 0.6)
			(layers "F.Cu" "F.Mask" "F.Paste")
			(roundrect_rratio 0.15)
			(net 10 "+5V")
			(pinfunction "S")
			(pintype "passive")
		)
		(pad "3" smd roundrect
			(at 1.1 -0.0005)
			(size 1 0.6)
			(layers "F.Cu" "F.Mask" "F.Paste")
			(roundrect_rratio 0.15)
			(net 258 "/Compute module/Pf_5V.SDA")
			(pinfunction "D")
			(pintype "passive")
		)
	)
	(footprint "antmicro-footprints:C_0402_1005Metric"
		(layer "F.Cu")
		(at 66.092962 175.7005 -90)
		(descr "Capacitor SMD 0402")
		(tags "capacitor SMD 0402")
		(property "Reference" "C817"
			(at -3.504 13.925 90)
			(layer "F.SilkS")
			(effects
				(font
					(size 0.7 0.7)
					(thickness 0.15)
				)
				(justify right bottom)
			)
		)
		(property "Value" "C_template_name_0402"
			(at -1.022927 2.155213 90)
			(layer "F.Fab")
			(effects
				(font
					(size 0.7 0.7)
					(thickness 0.15)
				)
				(justify right bottom)
			)
		)
		(property "Datasheet" "template_datasheet"
			(at 0 0 270)
			(layer "F.Fab")
			(hide yes)
			(effects
				(font
					(size 1.27 1.27)
					(thickness 0.15)
				)
			)
		)
		(property "MPN" "template_MPN"
			(at 0 0 270)
			(unlocked yes)
			(layer "F.Fab")
			(hide yes)
			(effects
				(font
					(size 1 1)
					(thickness 0.15)
				)
			)
		)
		(property "Manufacturer" "template_manufacturer"
			(at 0 0 270)
			(unlocked yes)
			(layer "F.Fab")
			(hide yes)
			(effects
				(font
					(size 1 1)
					(thickness 0.15)
				)
			)
		)
		(property "License" "Apache-2.0"
			(at 0 0 270)
			(unlocked yes)
			(layer "F.Fab")
			(hide yes)
			(effects
				(font
					(size 1 1)
					(thickness 0.15)
				)
			)
		)
		(property "Author" "Antmicro"
			(at 0 0 270)
			(unlocked yes)
			(layer "F.Fab")
			(hide yes)
			(effects
				(font
					(size 1 1)
					(thickness 0.15)
				)
			)
		)
		(property "Val" "template_value"
			(at 0 0 270)
			(unlocked yes)
			(layer "F.Fab")
			(hide yes)
			(effects
				(font
					(size 1 1)
					(thickness 0.15)
				)
			)
		)
		(property "Voltage" "template_voltage"
			(at 0 0 270)
			(unlocked yes)
			(layer "F.Fab")
			(hide yes)
			(effects
				(font
					(size 1 1)
					(thickness 0.15)
				)
			)
		)
		(property "Dielectric" "template_dielectric"
			(at 0 0 270)
			(unlocked yes)
			(layer "F.Fab")
			(hide yes)
			(effects
				(font
					(size 1 1)
					(thickness 0.15)
				)
			)
		)
		(sheetname "/Peripherals/")
		(sheetfile "peripherals.kicad_sch")
		(attr smd exclude_from_pos_files exclude_from_bom dnp)
		(fp_rect
			(start -0.925 -0.47)
			(end 0.925 0.47)
			(stroke
				(width 0.05)
				(type default)
			)
			(fill no)
			(layer "F.CrtYd")
		)
		(fp_line
			(start -0.494 0.248)
			(end -0.494 -0.25)
			(stroke
				(width 0.15)
				(type solid)
			)
			(layer "F.Fab")
		)
		(fp_line
			(start 0.504 0.248)
			(end -0.494 0.248)
			(stroke
				(width 0.15)
				(type solid)
			)
			(layer "F.Fab")
		)
		(fp_line
			(start -0.494 -0.25)
			(end 0.504 -0.25)
			(stroke
				(width 0.15)
				(type solid)
			)
			(layer "F.Fab")
		)
		(fp_line
			(start 0.504 -0.25)
			(end 0.504 0.248)
			(stroke
				(width 0.15)
				(type solid)
			)
			(layer "F.Fab")
		)
		(fp_text user "${REFERENCE}"
			(at -0.939 4.599 270)
			(layer "F.Fab")
			(effects
				(font
					(size 0.7 0.7)
					(thickness 0.15)
				)
				(justify left bottom)
			)
		)
		(fp_text user "License: Apache-2.0"
			(at -0.939 5.799 270)
			(layer "F.Fab")
			(effects
				(font
					(size 0.7 0.7)
					(thickness 0.15)
				)
				(justify left bottom)
			)
		)
		(fp_text user "Author: Antmicro"
			(at -0.939 3.399 270)
			(layer "F.Fab")
			(effects
				(font
					(size 0.7 0.7)
					(thickness 0.15)
				)
				(justify left bottom)
			)
		)
		(pad "1" smd roundrect
			(at -0.48 0 270)
			(size 0.59 0.64)
			(layers "F.Cu" "F.Mask" "F.Paste")
			(roundrect_rratio 0.25)
			(net 110 "Net-(C817-Pad1)")
			(pintype "passive")
		)
		(pad "2" smd roundrect
			(at 0.48 0 270)
			(size 0.59 0.64)
			(layers "F.Cu" "F.Mask" "F.Paste")
			(roundrect_rratio 0.25)
			(net 3 "GND")
			(pintype "passive")
		)
	)
	(footprint "antmicro-footprints:LED_0603_1608Metric_G"
		(layer "F.Cu")
		(at 76.517962 173.2065 180)
		(descr "LED SMD 0603 Green")
		(tags "LED SMD 0603 Green")
		(property "Reference" "D207"
			(at -7.822038 0.7365 0)
			(layer "F.SilkS")
			(effects
				(font
					(size 0.7 0.7)
					(thickness 0.15)
				)
				(justify right bottom)
			)
		)
		(property "Value" "LED_G_0603_KP-1608CGCK"
			(at -0.001 1.599 0)
			(layer "F.Fab")
			(effects
				(font
					(size 0.7 0.7)
					(thickness 0.15)
				)
				(justify right bottom)
			)
		)
		(property "Datasheet" "http://www.kingbright.com/attachments/file/psearch//000/00/00/KP-1608CGCK(Ver.23B).pdf"
			(at 0 0 180)
			(layer "F.Fab")
			(hide yes)
			(effects
				(font
					(size 1.27 1.27)
					(thickness 0.15)
				)
			)
		)
		(property "MPN" "KP-1608CGCK"
			(at 0 0 180)
			(unlocked yes)
			(layer "F.Fab")
			(hide yes)
			(effects
				(font
					(size 1 1)
					(thickness 0.15)
				)
			)
		)
		(property "Manufacturer" "Kingbright"
			(at 0 0 180)
			(unlocked yes)
			(layer "F.Fab")
			(hide yes)
			(effects
				(font
					(size 1 1)
					(thickness 0.15)
				)
			)
		)
		(property "Color" "Green"
			(at 0 0 180)
			(unlocked yes)
			(layer "F.Fab")
			(hide yes)
			(effects
				(font
					(size 1 1)
					(thickness 0.15)
				)
			)
		)
		(property "Author" "Antmicro"
			(at 0 0 180)
			(unlocked yes)
			(layer "F.Fab")
			(hide yes)
			(effects
				(font
					(size 1 1)
					(thickness 0.15)
				)
			)
		)
		(property "License" "Apache-2.0"
			(at 0 0 180)
			(unlocked yes)
			(layer "F.Fab")
			(hide yes)
			(effects
				(font
					(size 1 1)
					(thickness 0.15)
				)
			)
		)
		(sheetname "/Compute module/")
		(sheetfile "compute-module.kicad_sch")
		(attr smd exclude_from_bom dnp)
		(fp_line
			(start 0.22 0.35)
			(end -0.22 0.35)
			(stroke
				(width 0.15)
				(type solid)
			)
			(layer "F.SilkS")
		)
		(fp_line
			(start 0.22 -0.35)
			(end -0.22 -0.35)
			(stroke
				(width 0.15)
				(type solid)
			)
			(layer "F.SilkS")
		)
		(fp_line
			(start 0.105328 0.201008)
			(end 0.105328 -0.198992)
			(stroke
				(width 0.1)
				(type solid)
			)
			(layer "F.SilkS")
		)
		(fp_line
			(start 0.105328 0.201008)
			(end -0.094672 0.001008)
			(stroke
				(width 0.1)
				(type solid)
			)
			(layer "F.SilkS")
		)
		(fp_line
			(start 0.105328 0.001008)
			(end 0.24 0.001)
			(stroke
				(width 0.1)
				(type solid)
			)
			(layer "F.SilkS")
		)
		(fp_line
			(start -0.094672 0.201008)
			(end -0.094672 -0.198992)
			(stroke
				(width 0.1)
				(type solid)
			)
			(layer "F.SilkS")
		)
		(fp_line
			(start -0.094672 0.001008)
			(end 0.105328 -0.198992)
			(stroke
				(width 0.1)
				(type solid)
			)
			(layer "F.SilkS")
		)
		(fp_line
			(start -0.094672 0.001008)
			(end -0.24 0.001008)
			(stroke
				(width 0.1)
				(type solid)
			)
			(layer "F.SilkS")
		)
		(fp_line
			(start -1.18 -0.319)
			(end -1.18 0.321)
			(stroke
				(width 0.15)
				(type solid)
			)
			(layer "F.SilkS")
		)
		(fp_rect
			(start 1.25 0.65)
			(end -1.25 -0.65)
			(stroke
				(width 0.05)
				(type solid)
			)
			(fill no)
			(layer "F.CrtYd")
		)
		(fp_line
			(start 0.599 0)
			(end 0.201 0)
			(stroke
				(width 0.15)
				(type solid)
			)
			(layer "F.Fab")
		)
		(fp_line
			(start 0.201 0.2)
			(end 0.201 0)
			(stroke
				(width 0.15)
				(type solid)
			)
			(layer "F.Fab")
		)
		(fp_line
			(start 0.201 0)
			(end 0.201 -0.202)
			(stroke
				(width 0.15)
				(type solid)
			)
			(layer "F.Fab")
		)
		(fp_line
			(start 0.201 -0.202)
			(end -0.101 0)
			(stroke
				(width 0.15)
				(type solid)
			)
			(layer "F.Fab")
		)
		(fp_line
			(start -0.101 0)
			(end 0.201 0.2)
			(stroke
				(width 0.15)
				(type solid)
			)
			(layer "F.Fab")
		)
		(fp_line
			(start -0.199 0.2)
			(end -0.199 0.1)
			(stroke
				(width 0.15)
				(type solid)
			)
			(layer "F.Fab")
		)
		(fp_line
			(start -0.199 0)
			(end -0.597 0)
			(stroke
				(width 0.15)
				(type solid)
			)
			(layer "F.Fab")
		)
		(fp_line
			(start -0.199 -0.202)
			(end -0.199 0.1)
			(stroke
				(width 0.15)
				(type solid)
			)
			(layer "F.Fab")
		)
		(fp_rect
			(start 0.848 0.4)
			(end -0.85 -0.402)
			(stroke
				(width 0.15)
				(type solid)
			)
			(fill no)
			(layer "F.Fab")
		)
		(fp_text user "${REFERENCE}"
			(at -1.4224 5.999 180)
			(layer "F.Fab")
			(effects
				(font
					(size 0.7 0.7)
					(thickness 0.15)
				)
				(justify left bottom)
			)
		)
		(fp_text user "Author: Antmicro"
			(at -1.4224 4.799 180)
			(layer "F.Fab")
			(effects
				(font
					(size 0.7 0.7)
					(thickness 0.15)
				)
				(justify left bottom)
			)
		)
		(fp_text user "License: Apache-2.0"
			(at -1.4224 3.599 180)
			(layer "F.Fab")
			(effects
				(font
					(size 0.7 0.7)
					(thickness 0.15)
				)
				(justify left bottom)
			)
		)
		(pad "1" smd roundrect
			(at -0.7 0)
			(size 0.8 1)
			(layers "F.Cu" "F.Mask" "F.Paste")
			(roundrect_rratio 0.2)
			(net 469 "Net-(D207-C)")
			(pinfunction "C")
			(pintype "passive")
		)
		(pad "2" smd roundrect
			(at 0.7 0)
			(size 0.8 1)
			(layers "F.Cu" "F.Mask" "F.Paste")
			(roundrect_rratio 0.2)
			(net 9 "+3V3")
			(pinfunction "A")
			(pintype "passive")
		)
	)
	(footprint "antmicro-footprints:R_0402_1005Metric"
		(layer "F.Cu")
		(at 108.1 156.7915 180)
		(descr "Resistor SMD 0402")
		(tags "resistor SMD 0402")
		(property "Reference" "R226"
			(at 1.91 -2.495 180)
			(layer "F.SilkS")
			(effects
				(font
					(size 0.7 0.7)
					(thickness 0.15)
				)
				(justify left bottom)
			)
		)
		(property "Value" "R_0R_0402"
			(at -1.011843 1.772047 180)
			(layer "F.Fab")
			(effects
				(font
					(size 0.7 0.7)
					(thickness 0.15)
				)
				(justify left bottom)
			)
		)
		(property "Datasheet" "https://industrial.panasonic.com/cdbs/www-data/pdf/RDA0000/AOA0000C301.pdf"
			(at 0 0 180)
			(layer "F.Fab")
			(hide yes)
			(effects
				(font
					(size 1.27 1.27)
					(thickness 0.15)
				)
			)
		)
		(property "Manufacturer" "Panasonic"
			(at 0 0 180)
			(unlocked yes)
			(layer "F.Fab")
			(hide yes)
			(effects
				(font
					(size 1 1)
					(thickness 0.15)
				)
			)
		)
		(property "MPN" "ERJ2GE0R00X"
			(at 0 0 180)
			(unlocked yes)
			(layer "F.Fab")
			(hide yes)
			(effects
				(font
					(size 1 1)
					(thickness 0.15)
				)
			)
		)
		(property "Val" "0R"
			(at 0 0 180)
			(unlocked yes)
			(layer "F.Fab")
			(hide yes)
			(effects
				(font
					(size 1 1)
					(thickness 0.15)
				)
			)
		)
		(property "License" "Apache-2.0"
			(at 0 0 180)
			(unlocked yes)
			(layer "F.Fab")
			(hide yes)
			(effects
				(font
					(size 1 1)
					(thickness 0.15)
				)
			)
		)
		(property "Author" "Antmicro"
			(at 0 0 180)
			(unlocked yes)
			(layer "F.Fab")
			(hide yes)
			(effects
				(font
					(size 1 1)
					(thickness 0.15)
				)
			)
		)
		(property "Tolerance" "~"
			(at 0 0 180)
			(unlocked yes)
			(layer "F.Fab")
			(hide yes)
			(effects
				(font
					(size 1 1)
					(thickness 0.15)
				)
			)
		)
		(property "Current" "1A"
			(at 0 0 180)
			(unlocked yes)
			(layer "F.Fab")
			(hide yes)
			(effects
				(font
					(size 1 1)
					(thickness 0.15)
				)
			)
		)
		(sheetname "/Compute module/")
		(sheetfile "compute-module.kicad_sch")
		(attr smd)
		(fp_rect
			(start -0.925 -0.47)
			(end 0.925 0.47)
			(stroke
				(width 0.05)
				(type default)
			)
			(fill no)
			(layer "F.CrtYd")
		)
		(fp_rect
			(start -0.5 -0.25)
			(end 0.5 0.25)
			(stroke
				(width 0.15)
				(type solid)
			)
			(fill no)
			(layer "F.Fab")
		)
		(fp_text user "${REFERENCE}"
			(at -0.95 3.168 180)
			(layer "F.Fab")
			(effects
				(font
					(size 0.7 0.7)
					(thickness 0.15)
				)
				(justify left bottom)
			)
		)
		(fp_text user "License: Apache-2.0"
			(at -0.95 5.169 180)
			(layer "F.Fab")
			(effects
				(font
					(size 0.7 0.7)
					(thickness 0.15)
				)
				(justify left bottom)
			)
		)
		(fp_text user "Author: Antmicro"
			(at -0.95 4.169 180)
			(layer "F.Fab")
			(effects
				(font
					(size 0.7 0.7)
					(thickness 0.15)
				)
				(justify left bottom)
			)
		)
		(pad "1" smd roundrect
			(at -0.48 0 180)
			(size 0.59 0.64)
			(layers "F.Cu" "F.Mask" "F.Paste")
			(roundrect_rratio 0.25)
			(net 151 "/Compute module/R2_P")
			(pintype "passive")
		)
		(pad "2" smd roundrect
			(at 0.48 0 180)
			(size 0.59 0.64)
			(layers "F.Cu" "F.Mask" "F.Paste")
			(roundrect_rratio 0.25)
			(net 163 "/Compute module/NVMe.RX2_P")
			(pintype "passive")
		)
	)
	(footprint "antmicro-footprints:SOT-523"
		(layer "F.Cu")
		(at 98.217962 130.0415 -90)
		(property "Reference" "Q901"
			(at 1.265 0.85 180)
			(layer "F.SilkS")
			(effects
				(font
					(size 0.7 0.7)
					(thickness 0.15)
				)
				(justify right bottom)
			)
		)
		(property "Value" "PJE138K"
			(at 0.1 1.824 90)
			(layer "F.Fab")
			(effects
				(font
					(size 0.7 0.7)
					(thickness 0.15)
				)
				(justify right bottom)
			)
		)
		(property "Datasheet" "https://www.mouser.com/datasheet/2/1057/PJE138K-1876698.pdf"
			(at 0 0 270)
			(layer "F.Fab")
			(hide yes)
			(effects
				(font
					(size 1.27 1.27)
					(thickness 0.15)
				)
			)
		)
		(property "MPN" "PJE138K_R1_00001"
			(at 0 0 270)
			(unlocked yes)
			(layer "F.Fab")
			(hide yes)
			(effects
				(font
					(size 1 1)
					(thickness 0.15)
				)
			)
		)
		(property "Manufacturer" "PANJIT"
			(at 0 0 270)
			(unlocked yes)
			(layer "F.Fab")
			(hide yes)
			(effects
				(font
					(size 1 1)
					(thickness 0.15)
				)
			)
		)
		(property "Author" "Antmicro"
			(at 0 0 270)
			(unlocked yes)
			(layer "F.Fab")
			(hide yes)
			(effects
				(font
					(size 1 1)
					(thickness 0.15)
				)
			)
		)
		(property "License" "Apache-2.0"
			(at 0 0 270)
			(unlocked yes)
			(layer "F.Fab")
			(hide yes)
			(effects
				(font
					(size 1 1)
					(thickness 0.15)
				)
			)
		)
		(sheetname "/USB/")
		(sheetfile "usb.kicad_sch")
		(attr smd)
		(fp_line
			(start -0.927 -0.051)
			(end -0.927 -0.351)
			(stroke
				(width 0.15)
				(type solid)
			)
			(layer "F.SilkS")
		)
		(fp_line
			(start -0.927 -0.351)
			(end -0.725 -0.551)
			(stroke
				(width 0.15)
				(type solid)
			)
			(layer "F.SilkS")
		)
		(fp_line
			(start -0.725 -0.551)
			(end -0.277 -0.551)
			(stroke
				(width 0.15)
				(type solid)
			)
			(layer "F.SilkS")
		)
		(fp_line
			(start -0.277 -0.551)
			(end -0.277 -0.75)
			(stroke
				(width 0.15)
				(type solid)
			)
			(layer "F.SilkS")
		)
		(fp_circle
			(center -0.9652 0.9652)
			(end -0.9152 0.9652)
			(stroke
				(width 0.15)
				(type solid)
			)
			(fill yes)
			(layer "F.SilkS")
		)
		(fp_line
			(start -1.12 1.15)
			(end 1.1 1.15)
			(stroke
				(width 0.05)
				(type solid)
			)
			(layer "F.CrtYd")
		)
		(fp_line
			(start -1.12 -1.16)
			(end -1.12 1.15)
			(stroke
				(width 0.05)
				(type solid)
			)
			(layer "F.CrtYd")
		)
		(fp_line
			(start -1.12 -1.16)
			(end 1.1 -1.16)
			(stroke
				(width 0.05)
				(type solid)
			)
			(layer "F.CrtYd")
		)
		(fp_line
			(start 1.1 -1.16)
			(end 1.1 1.15)
			(stroke
				(width 0.05)
				(type solid)
			)
			(layer "F.CrtYd")
		)
		(fp_line
			(start 0.8 0.424)
			(end -0.802 0.424)
			(stroke
				(width 0.15)
				(type solid)
			)
			(layer "F.Fab")
		)
		(fp_line
			(start -0.802 -0.276)
			(end -0.802 0.424)
			(stroke
				(width 0.15)
				(type solid)
			)
			(layer "F.Fab")
		)
		(fp_line
			(start -0.652 -0.425)
			(end -0.802 -0.276)
			(stroke
				(width 0.15)
				(type solid)
			)
			(layer "F.Fab")
		)
		(fp_line
			(start 0.8 -0.425)
			(end 0.8 0.424)
			(stroke
				(width 0.15)
				(type solid)
			)
			(layer "F.Fab")
		)
		(fp_line
			(start 0.8 -0.425)
			(end -0.652 -0.425)
			(stroke
				(width 0.15)
				(type solid)
			)
			(layer "F.Fab")
		)
		(fp_circle
			(center -0.9652 0.9652)
			(end -0.9144 0.9652)
			(stroke
				(width 0.15)
				(type solid)
			)
			(fill no)
			(layer "F.Fab")
		)
		(fp_text user "${REFERENCE}"
			(at -1.12 3.824 270)
			(layer "F.Fab")
			(effects
				(font
					(size 0.7 0.7)
					(thickness 0.15)
				)
				(justify left bottom)
			)
		)
		(fp_text user "License: Apache-2.0"
			(at -1.12 5.024 270)
			(layer "F.Fab")
			(effects
				(font
					(size 0.7 0.7)
					(thickness 0.15)
				)
				(justify left bottom)
			)
		)
		(fp_text user "Author: Antmicro"
			(at -1.12 6.224 270)
			(layer "F.Fab")
			(effects
				(font
					(size 0.7 0.7)
					(thickness 0.15)
				)
				(justify left bottom)
			)
		)
		(pad "1" smd rect
			(at -0.5 0.65 270)
			(size 0.4 0.51)
			(layers "F.Cu" "F.Mask" "F.Paste")
			(net 279 "/Compute module/USB.OTGID")
			(pinfunction "G")
			(pintype "input")
		)
		(pad "2" smd rect
			(at 0.498 0.65 270)
			(size 0.4 0.51)
			(layers "F.Cu" "F.Mask" "F.Paste")
			(net 3 "GND")
			(pinfunction "S")
			(pintype "passive")
		)
		(pad "3" smd rect
			(at 0 -0.652 270)
			(size 0.4 0.51)
			(layers "F.Cu" "F.Mask" "F.Paste")
			(net 288 "/USB/USBA_OUT_EN")
			(pinfunction "D")
			(pintype "passive")
		)
	)
	(footprint "antmicro-footprints:LED_0603_1608Metric_G"
		(layer "F.Cu")
		(at 75.567962 148.2665 180)
		(descr "LED SMD 0603 Green")
		(tags "LED SMD 0603 Green")
		(property "Reference" "D201"
			(at -1.35 5.1 0)
			(layer "F.SilkS")
			(effects
				(font
					(size 0.7 0.7)
					(thickness 0.15)
				)
				(justify right bottom)
			)
		)
		(property "Value" "LED_G_0603_KP-1608CGCK"
			(at -0.001 1.599 0)
			(layer "F.Fab")
			(effects
				(font
					(size 0.7 0.7)
					(thickness 0.15)
				)
				(justify right bottom)
			)
		)
		(property "Datasheet" "http://www.kingbright.com/attachments/file/psearch//000/00/00/KP-1608CGCK(Ver.23B).pdf"
			(at 0 0 180)
			(layer "F.Fab")
			(hide yes)
			(effects
				(font
					(size 1.27 1.27)
					(thickness 0.15)
				)
			)
		)
		(property "MPN" "KP-1608CGCK"
			(at 0 0 180)
			(unlocked yes)
			(layer "F.Fab")
			(hide yes)
			(effects
				(font
					(size 1 1)
					(thickness 0.15)
				)
			)
		)
		(property "Manufacturer" "Kingbright"
			(at 0 0 180)
			(unlocked yes)
			(layer "F.Fab")
			(hide yes)
			(effects
				(font
					(size 1 1)
					(thickness 0.15)
				)
			)
		)
		(property "Color" "Green"
			(at 0 0 180)
			(unlocked yes)
			(layer "F.Fab")
			(hide yes)
			(effects
				(font
					(size 1 1)
					(thickness 0.15)
				)
			)
		)
		(property "Author" "Antmicro"
			(at 0 0 180)
			(unlocked yes)
			(layer "F.Fab")
			(hide yes)
			(effects
				(font
					(size 1 1)
					(thickness 0.15)
				)
			)
		)
		(property "License" "Apache-2.0"
			(at 0 0 180)
			(unlocked yes)
			(layer "F.Fab")
			(hide yes)
			(effects
				(font
					(size 1 1)
					(thickness 0.15)
				)
			)
		)
		(sheetname "/Compute module/")
		(sheetfile "compute-module.kicad_sch")
		(attr smd)
		(fp_line
			(start 0.22 0.35)
			(end -0.22 0.35)
			(stroke
				(width 0.15)
				(type solid)
			)
			(layer "F.SilkS")
		)
		(fp_line
			(start 0.22 -0.35)
			(end -0.22 -0.35)
			(stroke
				(width 0.15)
				(type solid)
			)
			(layer "F.SilkS")
		)
		(fp_line
			(start 0.105328 0.201008)
			(end 0.105328 -0.198992)
			(stroke
				(width 0.1)
				(type solid)
			)
			(layer "F.SilkS")
		)
		(fp_line
			(start 0.105328 0.201008)
			(end -0.094672 0.001008)
			(stroke
				(width 0.1)
				(type solid)
			)
			(layer "F.SilkS")
		)
		(fp_line
			(start 0.105328 0.001008)
			(end 0.24 0.001)
			(stroke
				(width 0.1)
				(type solid)
			)
			(layer "F.SilkS")
		)
		(fp_line
			(start -0.094672 0.201008)
			(end -0.094672 -0.198992)
			(stroke
				(width 0.1)
				(type solid)
			)
			(layer "F.SilkS")
		)
		(fp_line
			(start -0.094672 0.001008)
			(end 0.105328 -0.198992)
			(stroke
				(width 0.1)
				(type solid)
			)
			(layer "F.SilkS")
		)
		(fp_line
			(start -0.094672 0.001008)
			(end -0.24 0.001008)
			(stroke
				(width 0.1)
				(type solid)
			)
			(layer "F.SilkS")
		)
		(fp_line
			(start -1.18 -0.319)
			(end -1.18 0.321)
			(stroke
				(width 0.15)
				(type solid)
			)
			(layer "F.SilkS")
		)
		(fp_rect
			(start 1.25 0.65)
			(end -1.25 -0.65)
			(stroke
				(width 0.05)
				(type solid)
			)
			(fill no)
			(layer "F.CrtYd")
		)
		(fp_line
			(start 0.599 0)
			(end 0.201 0)
			(stroke
				(width 0.15)
				(type solid)
			)
			(layer "F.Fab")
		)
		(fp_line
			(start 0.201 0.2)
			(end 0.201 0)
			(stroke
				(width 0.15)
				(type solid)
			)
			(layer "F.Fab")
		)
		(fp_line
			(start 0.201 0)
			(end 0.201 -0.202)
			(stroke
				(width 0.15)
				(type solid)
			)
			(layer "F.Fab")
		)
		(fp_line
			(start 0.201 -0.202)
			(end -0.101 0)
			(stroke
				(width 0.15)
				(type solid)
			)
			(layer "F.Fab")
		)
		(fp_line
			(start -0.101 0)
			(end 0.201 0.2)
			(stroke
				(width 0.15)
				(type solid)
			)
			(layer "F.Fab")
		)
		(fp_line
			(start -0.199 0.2)
			(end -0.199 0.1)
			(stroke
				(width 0.15)
				(type solid)
			)
			(layer "F.Fab")
		)
		(fp_line
			(start -0.199 0)
			(end -0.597 0)
			(stroke
				(width 0.15)
				(type solid)
			)
			(layer "F.Fab")
		)
		(fp_line
			(start -0.199 -0.202)
			(end -0.199 0.1)
			(stroke
				(width 0.15)
				(type solid)
			)
			(layer "F.Fab")
		)
		(fp_rect
			(start 0.848 0.4)
			(end -0.85 -0.402)
			(stroke
				(width 0.15)
				(type solid)
			)
			(fill no)
			(layer "F.Fab")
		)
		(fp_text user "${REFERENCE}"
			(at -1.4224 5.999 180)
			(layer "F.Fab")
			(effects
				(font
					(size 0.7 0.7)
					(thickness 0.15)
				)
				(justify left bottom)
			)
		)
		(fp_text user "Author: Antmicro"
			(at -1.4224 4.799 180)
			(layer "F.Fab")
			(effects
				(font
					(size 0.7 0.7)
					(thickness 0.15)
				)
				(justify left bottom)
			)
		)
		(fp_text user "License: Apache-2.0"
			(at -1.4224 3.599 180)
			(layer "F.Fab")
			(effects
				(font
					(size 0.7 0.7)
					(thickness 0.15)
				)
				(justify left bottom)
			)
		)
		(pad "1" smd roundrect
			(at -0.7 0)
			(size 0.8 1)
			(layers "F.Cu" "F.Mask" "F.Paste")
			(roundrect_rratio 0.2)
			(net 445 "Net-(D201-C)")
			(pinfunction "C")
			(pintype "passive")
		)
		(pad "2" smd roundrect
			(at 0.7 0)
			(size 0.8 1)
			(layers "F.Cu" "F.Mask" "F.Paste")
			(roundrect_rratio 0.2)
			(net 10 "+5V")
			(pinfunction "A")
			(pintype "passive")
		)
	)
	(footprint "antmicro-footprints:Conn_JST_SH_1x4_SM04B-SRSS-TB-LF-SN"
		(layer "F.Cu")
		(at 132.317962 114.6165 180)
		(property "Reference" "J803"
			(at -4.56 2.73 90)
			(layer "F.SilkS")
			(effects
				(font
					(size 0.7 0.7)
					(thickness 0.15)
				)
				(justify right bottom)
			)
		)
		(property "Value" "JST_SH_1x4_SM04B-SRSS-TB-LF-SN"
			(at 0 3.9 0)
			(layer "F.Fab")
			(effects
				(font
					(size 0.7 0.7)
					(thickness 0.15)
				)
				(justify right bottom)
			)
		)
		(property "Datasheet" "https://www.jst-mfg.com/product/pdf/eng/eSH.pdf"
			(at 0 0 180)
			(layer "F.Fab")
			(hide yes)
			(effects
				(font
					(size 1.27 1.27)
					(thickness 0.15)
				)
			)
		)
		(property "MPN" "SM04B-SRSS-TB(LF)(SN)"
			(at 0 0 180)
			(unlocked yes)
			(layer "F.Fab")
			(hide yes)
			(effects
				(font
					(size 1 1)
					(thickness 0.15)
				)
			)
		)
		(property "Manufacturer" "JST Automotive Connectors"
			(at 0 0 180)
			(unlocked yes)
			(layer "F.Fab")
			(hide yes)
			(effects
				(font
					(size 1 1)
					(thickness 0.15)
				)
			)
		)
		(property "Author" "Antmicro"
			(at 0 0 180)
			(unlocked yes)
			(layer "F.Fab")
			(hide yes)
			(effects
				(font
					(size 1 1)
					(thickness 0.15)
				)
			)
		)
		(property "License" "Apache-2.0"
			(at 0 0 180)
			(unlocked yes)
			(layer "F.Fab")
			(hide yes)
			(effects
				(font
					(size 1 1)
					(thickness 0.15)
				)
			)
		)
		(sheetname "/Peripherals/")
		(sheetfile "peripherals.kicad_sch")
		(attr smd)
		(fp_line
			(start 3.2 -2)
			(end 3.2 0.6)
			(stroke
				(width 0.15)
				(type solid)
			)
			(layer "F.SilkS")
		)
		(fp_line
			(start 2 -2)
			(end 3.2 -2)
			(stroke
				(width 0.15)
				(type solid)
			)
			(layer "F.SilkS")
		)
		(fp_line
			(start -2 2.6)
			(end 2 2.6)
			(stroke
				(width 0.15)
				(type solid)
			)
			(layer "F.SilkS")
		)
		(fp_line
			(start -2 -2)
			(end -3.2 -2)
			(stroke
				(width 0.15)
				(type solid)
			)
			(layer "F.SilkS")
		)
		(fp_line
			(start -3.2 -2)
			(end -3.2 0.6)
			(stroke
				(width 0.15)
				(type solid)
			)
			(layer "F.SilkS")
		)
		(fp_circle
			(center -2.1 -2.5)
			(end -2.05 -2.5)
			(stroke
				(width 0.15)
				(type solid)
			)
			(fill yes)
			(layer "F.SilkS")
		)
		(fp_rect
			(start -3.65 -3.14)
			(end 3.65 2.9)
			(stroke
				(width 0.05)
				(type solid)
			)
			(fill no)
			(layer "F.CrtYd")
		)
		(fp_rect
			(start -3 -2.475)
			(end 3 2.475)
			(stroke
				(width 0.15)
				(type solid)
			)
			(fill no)
			(layer "F.Fab")
		)
		(fp_text user "License: Apache-2.0"
			(at -4 5.88 180)
			(layer "F.Fab")
			(effects
				(font
					(size 0.7 0.7)
					(thickness 0.15)
				)
				(justify left bottom)
			)
		)
		(fp_text user "${REFERENCE}"
			(at -4 8.28 180)
			(layer "F.Fab")
			(effects
				(font
					(size 0.7 0.7)
					(thickness 0.15)
				)
				(justify left bottom)
			)
		)
		(fp_text user "Author: Antmicro"
			(at -4 7.08 180)
			(layer "F.Fab")
			(effects
				(font
					(size 0.7 0.7)
					(thickness 0.15)
				)
				(justify left bottom)
			)
		)
		(pad "1" smd roundrect
			(at -1.5 -2.12)
			(size 0.6 1.55)
			(layers "F.Cu" "F.Mask" "F.Paste")
			(roundrect_rratio 0.25)
			(net 3 "GND")
			(pintype "passive")
		)
		(pad "2" smd roundrect
			(at -0.5 -2.12)
			(size 0.6 1.55)
			(layers "F.Cu" "F.Mask" "F.Paste")
			(roundrect_rratio 0.25)
			(net 317 "/Peripherals/VLED")
			(pintype "passive")
		)
		(pad "3" smd roundrect
			(at 0.5 -2.12)
			(size 0.6 1.55)
			(layers "F.Cu" "F.Mask" "F.Paste")
			(roundrect_rratio 0.25)
			(net 143 "/CSI/I_{2}C1.SDA")
			(pintype "passive")
		)
		(pad "4" smd roundrect
			(at 1.5 -2.12)
			(size 0.6 1.55)
			(layers "F.Cu" "F.Mask" "F.Paste")
			(roundrect_rratio 0.25)
			(net 142 "/CSI/I_{2}C1.SCL")
			(pintype "passive")
		)
		(pad "MP" smd roundrect
			(at -2.8 1.755 180)
			(size 1.2 1.8)
			(layers "F.Cu" "F.Mask" "F.Paste")
			(roundrect_rratio 0.25)
			(net 3 "GND")
			(pintype "passive")
		)
		(pad "MP" smd roundrect
			(at 2.8 1.755 180)
			(size 1.2 1.8)
			(layers "F.Cu" "F.Mask" "F.Paste")
			(roundrect_rratio 0.25)
			(net 3 "GND")
			(pintype "passive")
		)
	)
	(footprint "antmicro-footprints:TP_SMD_0.75mm"
		(layer "F.Cu")
		(at 99.777962 119.539)
		(property "Reference" "TP909"
			(at 27.995 26.2225 90)
			(layer "F.SilkS")
			(effects
				(font
					(size 0.7 0.7)
					(thickness 0.15)
				)
				(justify left bottom)
			)
		)
		(property "Value" "TP_0.75mm_SMD"
			(at 0 1.2 0)
			(layer "F.Fab")
			(effects
				(font
					(size 0.7 0.7)
					(thickness 0.15)
				)
				(justify left bottom)
			)
		)
		(property "MPN" ""
			(at 0 0 0)
			(unlocked yes)
			(layer "F.Fab")
			(hide yes)
			(effects
				(font
					(size 1 1)
					(thickness 0.15)
				)
			)
		)
		(property "Manufacturer" ""
			(at 0 0 0)
			(unlocked yes)
			(layer "F.Fab")
			(hide yes)
			(effects
				(font
					(size 1 1)
					(thickness 0.15)
				)
			)
		)
		(property "Author" "Antmicro"
			(at 0 0 0)
			(unlocked yes)
			(layer "F.Fab")
			(hide yes)
			(effects
				(font
					(size 1 1)
					(thickness 0.15)
				)
			)
		)
		(property "License" "Apache-2.0"
			(at 0 0 0)
			(unlocked yes)
			(layer "F.Fab")
			(hide yes)
			(effects
				(font
					(size 1 1)
					(thickness 0.15)
				)
			)
		)
		(sheetname "/USB/")
		(sheetfile "usb.kicad_sch")
		(attr exclude_from_pos_files exclude_from_bom)
		(fp_circle
			(center 0 0)
			(end 0.475 0)
			(stroke
				(width 0.05)
				(type default)
			)
			(fill no)
			(layer "F.CrtYd")
		)
		(fp_text user "License: Apache-2.0"
			(at -0.4 5.101 0)
			(layer "F.Fab")
			(effects
				(font
					(size 0.7 0.7)
					(thickness 0.15)
				)
				(justify left bottom)
			)
		)
		(fp_text user "Author: Antmicro"
			(at -0.4 3.901 0)
			(layer "F.Fab")
			(effects
				(font
					(size 0.7 0.7)
					(thickness 0.15)
				)
				(justify left bottom)
			)
		)
		(fp_text user "${REFERENCE}"
			(at -0.4 2.7 0)
			(layer "F.Fab")
			(effects
				(font
					(size 0.7 0.7)
					(thickness 0.15)
				)
				(justify left bottom)
			)
		)
		(pad "1" smd circle
			(at 0 0)
			(size 0.75 0.75)
			(layers "F.Cu" "F.Mask")
			(net 434 "Net-(U906-PORT)")
			(pinfunction "1")
			(pintype "passive")
		)
	)
	(footprint "antmicro-footprints:TP_SMD_0.75mm"
		(layer "F.Cu")
		(at 108 154.825)
		(property "Reference" "TP217"
			(at 0.45 0.475 0)
			(layer "F.SilkS")
			(effects
				(font
					(size 0.7 0.7)
					(thickness 0.15)
				)
				(justify left bottom)
			)
		)
		(property "Value" "TP_0.75mm_SMD"
			(at 0 1.2 0)
			(layer "F.Fab")
			(effects
				(font
					(size 0.7 0.7)
					(thickness 0.15)
				)
				(justify left bottom)
			)
		)
		(property "MPN" ""
			(at 0 0 0)
			(unlocked yes)
			(layer "F.Fab")
			(hide yes)
			(effects
				(font
					(size 1 1)
					(thickness 0.15)
				)
			)
		)
		(property "Manufacturer" ""
			(at 0 0 0)
			(unlocked yes)
			(layer "F.Fab")
			(hide yes)
			(effects
				(font
					(size 1 1)
					(thickness 0.15)
				)
			)
		)
		(property "Author" "Antmicro"
			(at 0 0 0)
			(unlocked yes)
			(layer "F.Fab")
			(hide yes)
			(effects
				(font
					(size 1 1)
					(thickness 0.15)
				)
			)
		)
		(property "License" "Apache-2.0"
			(at 0 0 0)
			(unlocked yes)
			(layer "F.Fab")
			(hide yes)
			(effects
				(font
					(size 1 1)
					(thickness 0.15)
				)
			)
		)
		(sheetname "/Compute module/")
		(sheetfile "compute-module.kicad_sch")
		(attr exclude_from_pos_files exclude_from_bom)
		(fp_circle
			(center 0 0)
			(end 0.475 0)
			(stroke
				(width 0.05)
				(type default)
			)
			(fill no)
			(layer "F.CrtYd")
		)
		(fp_text user "Author: Antmicro"
			(at -0.4 3.901 0)
			(layer "F.Fab")
			(effects
				(font
					(size 0.7 0.7)
					(thickness 0.15)
				)
				(justify left bottom)
			)
		)
		(fp_text user "${REFERENCE}"
			(at -0.4 2.7 0)
			(layer "F.Fab")
			(effects
				(font
					(size 0.7 0.7)
					(thickness 0.15)
				)
				(justify left bottom)
			)
		)
		(fp_text user "License: Apache-2.0"
			(at -0.4 5.101 0)
			(layer "F.Fab")
			(effects
				(font
					(size 0.7 0.7)
					(thickness 0.15)
				)
				(justify left bottom)
			)
		)
		(pad "1" smd circle
			(at 0 0)
			(size 0.75 0.75)
			(layers "F.Cu" "F.Mask")
			(net 260 "/Compute module/Pf_5V.CEC")
			(pinfunction "1")
			(pintype "passive")
		)
	)
	(footprint "antmicro-footprints:C_0402_1005Metric"
		(layer "F.Cu")
		(at 87.392962 151.3665 90)
		(descr "Capacitor SMD 0402")
		(tags "capacitor SMD 0402")
		(property "Reference" "C206"
			(at 0.025 -0.425 90)
			(layer "F.SilkS")
			(effects
				(font
					(size 0.7 0.7)
					(thickness 0.15)
				)
				(justify left bottom)
			)
		)
		(property "Value" "C_100n_0402"
			(at -1.022927 2.155213 90)
			(layer "F.Fab")
			(effects
				(font
					(size 0.7 0.7)
					(thickness 0.15)
				)
				(justify left bottom)
			)
		)
		(property "Datasheet" "https://www.murata.com/products/productdetail?partno=GRM155R61H104KE14%23"
			(at 0 0 90)
			(layer "F.Fab")
			(hide yes)
			(effects
				(font
					(size 1.27 1.27)
					(thickness 0.15)
				)
			)
		)
		(property "MPN" "GRM155R61H104KE14D"
			(at 0 0 90)
			(unlocked yes)
			(layer "F.Fab")
			(hide yes)
			(effects
				(font
					(size 1 1)
					(thickness 0.15)
				)
			)
		)
		(property "Manufacturer" "Murata"
			(at 0 0 90)
			(unlocked yes)
			(layer "F.Fab")
			(hide yes)
			(effects
				(font
					(size 1 1)
					(thickness 0.15)
				)
			)
		)
		(property "License" "Apache-2.0"
			(at 0 0 90)
			(unlocked yes)
			(layer "F.Fab")
			(hide yes)
			(effects
				(font
					(size 1 1)
					(thickness 0.15)
				)
			)
		)
		(property "Author" "Antmicro"
			(at 0 0 90)
			(unlocked yes)
			(layer "F.Fab")
			(hide yes)
			(effects
				(font
					(size 1 1)
					(thickness 0.15)
				)
			)
		)
		(property "Val" "100n"
			(at 0 0 90)
			(unlocked yes)
			(layer "F.Fab")
			(hide yes)
			(effects
				(font
					(size 1 1)
					(thickness 0.15)
				)
			)
		)
		(property "Voltage" "50V"
			(at 0 0 90)
			(unlocked yes)
			(layer "F.Fab")
			(hide yes)
			(effects
				(font
					(size 1 1)
					(thickness 0.15)
				)
			)
		)
		(property "Dielectric" "X5R"
			(at 0 0 90)
			(unlocked yes)
			(layer "F.Fab")
			(hide yes)
			(effects
				(font
					(size 1 1)
					(thickness 0.15)
				)
			)
		)
		(sheetname "/Compute module/")
		(sheetfile "compute-module.kicad_sch")
		(attr smd)
		(fp_rect
			(start -0.925 -0.47)
			(end 0.925 0.47)
			(stroke
				(width 0.05)
				(type default)
			)
			(fill no)
			(layer "F.CrtYd")
		)
		(fp_line
			(start 0.504 -0.25)
			(end 0.504 0.248)
			(stroke
				(width 0.15)
				(type solid)
			)
			(layer "F.Fab")
		)
		(fp_line
			(start -0.494 -0.25)
			(end 0.504 -0.25)
			(stroke
				(width 0.15)
				(type solid)
			)
			(layer "F.Fab")
		)
		(fp_line
			(start 0.504 0.248)
			(end -0.494 0.248)
			(stroke
				(width 0.15)
				(type solid)
			)
			(layer "F.Fab")
		)
		(fp_line
			(start -0.494 0.248)
			(end -0.494 -0.25)
			(stroke
				(width 0.15)
				(type solid)
			)
			(layer "F.Fab")
		)
		(fp_text user "License: Apache-2.0"
			(at -0.939 5.799 90)
			(layer "F.Fab")
			(effects
				(font
					(size 0.7 0.7)
					(thickness 0.15)
				)
				(justify left bottom)
			)
		)
		(fp_text user "Author: Antmicro"
			(at -0.939 3.399 90)
			(layer "F.Fab")
			(effects
				(font
					(size 0.7 0.7)
					(thickness 0.15)
				)
				(justify left bottom)
			)
		)
		(fp_text user "${REFERENCE}"
			(at -0.939 4.599 90)
			(layer "F.Fab")
			(effects
				(font
					(size 0.7 0.7)
					(thickness 0.15)
				)
				(justify left bottom)
			)
		)
		(pad "1" smd roundrect
			(at -0.48 0 90)
			(size 0.59 0.64)
			(layers "F.Cu" "F.Mask" "F.Paste")
			(roundrect_rratio 0.25)
			(net 3 "GND")
			(pintype "passive")
		)
		(pad "2" smd roundrect
			(at 0.48 0 90)
			(size 0.59 0.64)
			(layers "F.Cu" "F.Mask" "F.Paste")
			(roundrect_rratio 0.25)
			(net 9 "+3V3")
			(pintype "passive")
		)
	)
	(footprint "antmicro-footprints:TP_SMD_0.75mm"
		(layer "F.Cu")
		(at 139.55 157.3)
		(property "Reference" "TP603"
			(at 0.95 -0.55 180)
			(layer "F.SilkS")
			(effects
				(font
					(size 0.7 0.7)
					(thickness 0.15)
				)
				(justify left bottom)
			)
		)
		(property "Value" "TP_0.75mm_SMD"
			(at 0 1.2 0)
			(layer "F.Fab")
			(effects
				(font
					(size 0.7 0.7)
					(thickness 0.15)
				)
				(justify left bottom)
			)
		)
		(property "MPN" ""
			(at 0 0 0)
			(unlocked yes)
			(layer "F.Fab")
			(hide yes)
			(effects
				(font
					(size 1 1)
					(thickness 0.15)
				)
			)
		)
		(property "Manufacturer" ""
			(at 0 0 0)
			(unlocked yes)
			(layer "F.Fab")
			(hide yes)
			(effects
				(font
					(size 1 1)
					(thickness 0.15)
				)
			)
		)
		(property "Author" "Antmicro"
			(at 0 0 0)
			(unlocked yes)
			(layer "F.Fab")
			(hide yes)
			(effects
				(font
					(size 1 1)
					(thickness 0.15)
				)
			)
		)
		(property "License" "Apache-2.0"
			(at 0 0 0)
			(unlocked yes)
			(layer "F.Fab")
			(hide yes)
			(effects
				(font
					(size 1 1)
					(thickness 0.15)
				)
			)
		)
		(sheetname "/CSI/")
		(sheetfile "csi.kicad_sch")
		(attr exclude_from_pos_files exclude_from_bom)
		(fp_circle
			(center 0 0)
			(end 0.475 0)
			(stroke
				(width 0.05)
				(type default)
			)
			(fill no)
			(layer "F.CrtYd")
		)
		(fp_text user "Author: Antmicro"
			(at -0.4 3.901 0)
			(layer "F.Fab")
			(effects
				(font
					(size 0.7 0.7)
					(thickness 0.15)
				)
				(justify left bottom)
			)
		)
		(fp_text user "${REFERENCE}"
			(at -0.4 2.7 0)
			(layer "F.Fab")
			(effects
				(font
					(size 0.7 0.7)
					(thickness 0.15)
				)
				(justify left bottom)
			)
		)
		(fp_text user "License: Apache-2.0"
			(at -0.4 5.101 0)
			(layer "F.Fab")
			(effects
				(font
					(size 0.7 0.7)
					(thickness 0.15)
				)
				(justify left bottom)
			)
		)
		(pad "1" smd circle
			(at 0 0)
			(size 0.75 0.75)
			(layers "F.Cu" "F.Mask")
			(net 20 "/CSI/CSI_5V")
			(pinfunction "1")
			(pintype "passive")
		)
	)
	(footprint "antmicro-footprints:R_0402_1005Metric"
		(layer "F.Cu")
		(at 133.342962 124.7415)
		(descr "Resistor SMD 0402")
		(tags "resistor SMD 0402")
		(property "Reference" "R212"
			(at -1.195 8.075 0)
			(layer "F.SilkS")
			(effects
				(font
					(size 0.7 0.7)
					(thickness 0.15)
				)
				(justify left bottom)
			)
		)
		(property "Value" "R_100k_0402"
			(at -1.011843 1.772047 0)
			(layer "F.Fab")
			(effects
				(font
					(size 0.7 0.7)
					(thickness 0.15)
				)
				(justify left bottom)
			)
		)
		(property "Datasheet" "https://www.bourns.com/docs/product-datasheets/cr.pdf"
			(at 0 0 0)
			(layer "F.Fab")
			(hide yes)
			(effects
				(font
					(size 1.27 1.27)
					(thickness 0.15)
				)
			)
		)
		(property "Manufacturer" "Bourns"
			(at 0 0 0)
			(unlocked yes)
			(layer "F.Fab")
			(hide yes)
			(effects
				(font
					(size 1 1)
					(thickness 0.15)
				)
			)
		)
		(property "MPN" "CR0402-FX-1003GLF"
			(at 0 0 0)
			(unlocked yes)
			(layer "F.Fab")
			(hide yes)
			(effects
				(font
					(size 1 1)
					(thickness 0.15)
				)
			)
		)
		(property "Val" "100k"
			(at 0 0 0)
			(unlocked yes)
			(layer "F.Fab")
			(hide yes)
			(effects
				(font
					(size 1 1)
					(thickness 0.15)
				)
			)
		)
		(property "License" "Apache-2.0"
			(at 0 0 0)
			(unlocked yes)
			(layer "F.Fab")
			(hide yes)
			(effects
				(font
					(size 1 1)
					(thickness 0.15)
				)
			)
		)
		(property "Author" "Antmicro"
			(at 0 0 0)
			(unlocked yes)
			(layer "F.Fab")
			(hide yes)
			(effects
				(font
					(size 1 1)
					(thickness 0.15)
				)
			)
		)
		(property "Tolerance" "1%"
			(at 0 0 0)
			(unlocked yes)
			(layer "F.Fab")
			(hide yes)
			(effects
				(font
					(size 1 1)
					(thickness 0.15)
				)
			)
		)
		(sheetname "/Compute module/")
		(sheetfile "compute-module.kicad_sch")
		(attr smd)
		(fp_rect
			(start -0.925 -0.47)
			(end 0.925 0.47)
			(stroke
				(width 0.05)
				(type default)
			)
			(fill no)
			(layer "F.CrtYd")
		)
		(fp_rect
			(start -0.5 -0.25)
			(end 0.5 0.25)
			(stroke
				(width 0.15)
				(type solid)
			)
			(fill no)
			(layer "F.Fab")
		)
		(fp_text user "License: Apache-2.0"
			(at -0.95 5.169 0)
			(layer "F.Fab")
			(effects
				(font
					(size 0.7 0.7)
					(thickness 0.15)
				)
				(justify left bottom)
			)
		)
		(fp_text user "Author: Antmicro"
			(at -0.95 4.169 0)
			(layer "F.Fab")
			(effects
				(font
					(size 0.7 0.7)
					(thickness 0.15)
				)
				(justify left bottom)
			)
		)
		(fp_text user "${REFERENCE}"
			(at -0.95 3.168 0)
			(layer "F.Fab")
			(effects
				(font
					(size 0.7 0.7)
					(thickness 0.15)
				)
				(justify left bottom)
			)
		)
		(pad "1" smd roundrect
			(at -0.48 0)
			(size 0.59 0.64)
			(layers "F.Cu" "F.Mask" "F.Paste")
			(roundrect_rratio 0.25)
			(net 3 "GND")
			(pintype "passive")
		)
		(pad "2" smd roundrect
			(at 0.48 0)
			(size 0.59 0.64)
			(layers "F.Cu" "F.Mask" "F.Paste")
			(roundrect_rratio 0.25)
			(net 2 "Net-(D203-A)")
			(pintype "passive")
		)
	)
	(footprint "antmicro-footprints:TP_SMD_0.75mm"
		(layer "F.Cu")
		(at 39.3 160.4)
		(property "Reference" "TP310"
			(at 0.45 3.8 90)
			(layer "F.SilkS")
			(effects
				(font
					(size 0.7 0.7)
					(thickness 0.15)
				)
				(justify left bottom)
			)
		)
		(property "Value" "TP_0.75mm_SMD"
			(at 0 1.2 0)
			(layer "F.Fab")
			(effects
				(font
					(size 0.7 0.7)
					(thickness 0.15)
				)
				(justify left bottom)
			)
		)
		(property "MPN" ""
			(at 0 0 0)
			(unlocked yes)
			(layer "F.Fab")
			(hide yes)
			(effects
				(font
					(size 1 1)
					(thickness 0.15)
				)
			)
		)
		(property "Manufacturer" ""
			(at 0 0 0)
			(unlocked yes)
			(layer "F.Fab")
			(hide yes)
			(effects
				(font
					(size 1 1)
					(thickness 0.15)
				)
			)
		)
		(property "Author" "Antmicro"
			(at 0 0 0)
			(unlocked yes)
			(layer "F.Fab")
			(hide yes)
			(effects
				(font
					(size 1 1)
					(thickness 0.15)
				)
			)
		)
		(property "License" "Apache-2.0"
			(at 0 0 0)
			(unlocked yes)
			(layer "F.Fab")
			(hide yes)
			(effects
				(font
					(size 1 1)
					(thickness 0.15)
				)
			)
		)
		(sheetname "/Supply/")
		(sheetfile "supply.kicad_sch")
		(attr exclude_from_pos_files exclude_from_bom)
		(fp_circle
			(center 0 0)
			(end 0.475 0)
			(stroke
				(width 0.05)
				(type default)
			)
			(fill no)
			(layer "F.CrtYd")
		)
		(fp_text user "License: Apache-2.0"
			(at -0.4 5.101 0)
			(layer "F.Fab")
			(effects
				(font
					(size 0.7 0.7)
					(thickness 0.15)
				)
				(justify left bottom)
			)
		)
		(fp_text user "${REFERENCE}"
			(at -0.4 2.7 0)
			(layer "F.Fab")
			(effects
				(font
					(size 0.7 0.7)
					(thickness 0.15)
				)
				(justify left bottom)
			)
		)
		(fp_text user "Author: Antmicro"
			(at -0.4 3.901 0)
			(layer "F.Fab")
			(effects
				(font
					(size 0.7 0.7)
					(thickness 0.15)
				)
				(justify left bottom)
			)
		)
		(pad "1" smd circle
			(at 0 0)
			(size 0.75 0.75)
			(layers "F.Cu" "F.Mask")
			(net 21 "/Supply/VCC_IN")
			(pinfunction "1")
			(pintype "passive")
		)
	)
	(footprint "antmicro-footprints:R_0402_1005Metric"
		(layer "F.Cu")
		(at 74.007962 136.0465 180)
		(descr "Resistor SMD 0402")
		(tags "resistor SMD 0402")
		(property "Reference" "R920"
			(at 3.613659 -0.447803 0)
			(layer "F.SilkS")
			(effects
				(font
					(size 0.7 0.7)
					(thickness 0.15)
				)
				(justify right bottom)
			)
		)
		(property "Value" "R_470R_0402"
			(at -1.011843 1.772047 0)
			(layer "F.Fab")
			(effects
				(font
					(size 0.7 0.7)
					(thickness 0.15)
				)
				(justify right bottom)
			)
		)
		(property "Datasheet" "https://www.bourns.com/docs/product-datasheets/cr.pdf"
			(at 0 0 180)
			(layer "F.Fab")
			(hide yes)
			(effects
				(font
					(size 1.27 1.27)
					(thickness 0.15)
				)
			)
		)
		(property "Manufacturer" "Bourns"
			(at 0 0 180)
			(unlocked yes)
			(layer "F.Fab")
			(hide yes)
			(effects
				(font
					(size 1 1)
					(thickness 0.15)
				)
			)
		)
		(property "MPN" "CR0402-FX-4700GLF"
			(at 0 0 180)
			(unlocked yes)
			(layer "F.Fab")
			(hide yes)
			(effects
				(font
					(size 1 1)
					(thickness 0.15)
				)
			)
		)
		(property "Val" "470R"
			(at 0 0 180)
			(unlocked yes)
			(layer "F.Fab")
			(hide yes)
			(effects
				(font
					(size 1 1)
					(thickness 0.15)
				)
			)
		)
		(property "License" "Apache-2.0"
			(at 0 0 180)
			(unlocked yes)
			(layer "F.Fab")
			(hide yes)
			(effects
				(font
					(size 1 1)
					(thickness 0.15)
				)
			)
		)
		(property "Author" "Antmicro"
			(at 0 0 180)
			(unlocked yes)
			(layer "F.Fab")
			(hide yes)
			(effects
				(font
					(size 1 1)
					(thickness 0.15)
				)
			)
		)
		(property "Tolerance" "1%"
			(at 0 0 180)
			(unlocked yes)
			(layer "F.Fab")
			(hide yes)
			(effects
				(font
					(size 1 1)
					(thickness 0.15)
				)
			)
		)
		(sheetname "/USB/")
		(sheetfile "usb.kicad_sch")
		(attr smd)
		(fp_rect
			(start -0.925 -0.47)
			(end 0.925 0.47)
			(stroke
				(width 0.05)
				(type default)
			)
			(fill no)
			(layer "F.CrtYd")
		)
		(fp_rect
			(start -0.5 -0.25)
			(end 0.5 0.25)
			(stroke
				(width 0.15)
				(type solid)
			)
			(fill no)
			(layer "F.Fab")
		)
		(fp_text user "${REFERENCE}"
			(at -0.95 3.168 180)
			(layer "F.Fab")
			(effects
				(font
					(size 0.7 0.7)
					(thickness 0.15)
				)
				(justify left bottom)
			)
		)
		(fp_text user "License: Apache-2.0"
			(at -0.95 5.169 180)
			(layer "F.Fab")
			(effects
				(font
					(size 0.7 0.7)
					(thickness 0.15)
				)
				(justify left bottom)
			)
		)
		(fp_text user "Author: Antmicro"
			(at -0.95 4.169 180)
			(layer "F.Fab")
			(effects
				(font
					(size 0.7 0.7)
					(thickness 0.15)
				)
				(justify left bottom)
			)
		)
		(pad "1" smd roundrect
			(at -0.48 0 180)
			(size 0.59 0.64)
			(layers "F.Cu" "F.Mask" "F.Paste")
			(roundrect_rratio 0.25)
			(net 487 "Net-(D911-A)")
			(pintype "passive")
		)
		(pad "2" smd roundrect
			(at 0.48 0 180)
			(size 0.59 0.64)
			(layers "F.Cu" "F.Mask" "F.Paste")
			(roundrect_rratio 0.25)
			(net 27 "/USB/USB_3V3")
			(pintype "passive")
		)
	)
	(footprint "antmicro-footprints:R_0402_1005Metric"
		(layer "F.Cu")
		(at 120.3 157.9915 180)
		(descr "Resistor SMD 0402")
		(tags "resistor SMD 0402")
		(property "Reference" "R223"
			(at -4.3 -0.175 180)
			(layer "F.SilkS")
			(effects
				(font
					(size 0.7 0.7)
					(thickness 0.15)
				)
				(justify left bottom)
			)
		)
		(property "Value" "R_0R_0402"
			(at -1.011843 1.772047 180)
			(layer "F.Fab")
			(effects
				(font
					(size 0.7 0.7)
					(thickness 0.15)
				)
				(justify left bottom)
			)
		)
		(property "Datasheet" "https://industrial.panasonic.com/cdbs/www-data/pdf/RDA0000/AOA0000C301.pdf"
			(at 0 0 180)
			(layer "F.Fab")
			(hide yes)
			(effects
				(font
					(size 1.27 1.27)
					(thickness 0.15)
				)
			)
		)
		(property "Manufacturer" "Panasonic"
			(at 0 0 180)
			(unlocked yes)
			(layer "F.Fab")
			(hide yes)
			(effects
				(font
					(size 1 1)
					(thickness 0.15)
				)
			)
		)
		(property "MPN" "ERJ2GE0R00X"
			(at 0 0 180)
			(unlocked yes)
			(layer "F.Fab")
			(hide yes)
			(effects
				(font
					(size 1 1)
					(thickness 0.15)
				)
			)
		)
		(property "Val" "0R"
			(at 0 0 180)
			(unlocked yes)
			(layer "F.Fab")
			(hide yes)
			(effects
				(font
					(size 1 1)
					(thickness 0.15)
				)
			)
		)
		(property "License" "Apache-2.0"
			(at 0 0 180)
			(unlocked yes)
			(layer "F.Fab")
			(hide yes)
			(effects
				(font
					(size 1 1)
					(thickness 0.15)
				)
			)
		)
		(property "Author" "Antmicro"
			(at 0 0 180)
			(unlocked yes)
			(layer "F.Fab")
			(hide yes)
			(effects
				(font
					(size 1 1)
					(thickness 0.15)
				)
			)
		)
		(property "Tolerance" "~"
			(at 0 0 180)
			(unlocked yes)
			(layer "F.Fab")
			(hide yes)
			(effects
				(font
					(size 1 1)
					(thickness 0.15)
				)
			)
		)
		(property "Current" "1A"
			(at 0 0 180)
			(unlocked yes)
			(layer "F.Fab")
			(hide yes)
			(effects
				(font
					(size 1 1)
					(thickness 0.15)
				)
			)
		)
		(sheetname "/Compute module/")
		(sheetfile "compute-module.kicad_sch")
		(attr smd)
		(fp_rect
			(start -0.925 -0.47)
			(end 0.925 0.47)
			(stroke
				(width 0.05)
				(type default)
			)
			(fill no)
			(layer "F.CrtYd")
		)
		(fp_rect
			(start -0.5 -0.25)
			(end 0.5 0.25)
			(stroke
				(width 0.15)
				(type solid)
			)
			(fill no)
			(layer "F.Fab")
		)
		(fp_text user "License: Apache-2.0"
			(at -0.95 5.169 180)
			(layer "F.Fab")
			(effects
				(font
					(size 0.7 0.7)
					(thickness 0.15)
				)
				(justify left bottom)
			)
		)
		(fp_text user "Author: Antmicro"
			(at -0.95 4.169 180)
			(layer "F.Fab")
			(effects
				(font
					(size 0.7 0.7)
					(thickness 0.15)
				)
				(justify left bottom)
			)
		)
		(fp_text user "${REFERENCE}"
			(at -0.95 3.168 180)
			(layer "F.Fab")
			(effects
				(font
					(size 0.7 0.7)
					(thickness 0.15)
				)
				(justify left bottom)
			)
		)
		(pad "1" smd roundrect
			(at -0.48 0 180)
			(size 0.59 0.64)
			(layers "F.Cu" "F.Mask" "F.Paste")
			(roundrect_rratio 0.25)
			(net 158 "/Compute module/NVMe.RX3_N")
			(pintype "passive")
		)
		(pad "2" smd roundrect
			(at 0.48 0 180)
			(size 0.59 0.64)
			(layers "F.Cu" "F.Mask" "F.Paste")
			(roundrect_rratio 0.25)
			(net 156 "/Compute module/R3_N")
			(pintype "passive")
		)
	)
	(footprint "antmicro-footprints:R_0402_1005Metric"
		(layer "F.Cu")
		(at 66.925 168.3 180)
		(descr "Resistor SMD 0402")
		(tags "resistor SMD 0402")
		(property "Reference" "R4"
			(at 0.8 0.425 0)
			(layer "F.SilkS")
			(effects
				(font
					(size 0.7 0.7)
					(thickness 0.15)
				)
				(justify right top)
			)
		)
		(property "Value" "R_0R_0402"
			(at -1.011843 1.772047 0)
			(layer "F.Fab")
			(effects
				(font
					(size 0.7 0.7)
					(thickness 0.15)
				)
				(justify right top)
			)
		)
		(property "Datasheet" "https://industrial.panasonic.com/cdbs/www-data/pdf/RDA0000/AOA0000C301.pdf"
			(at 0 0 0)
			(layer "F.Fab")
			(hide yes)
			(effects
				(font
					(size 1.27 1.27)
					(thickness 0.15)
				)
			)
		)
		(property "Description" "SMD Chip Resistor, Jumper, 0 ohm, 100 mW, 0402 [1005 Metric], Thick Film, General Purpose"
			(at 0 0 0)
			(layer "F.Fab")
			(hide yes)
			(effects
				(font
					(size 1.27 1.27)
					(thickness 0.15)
				)
			)
		)
		(property "MPN" "ERJ2GE0R00X"
			(at 0 0 180)
			(unlocked yes)
			(layer "F.Fab")
			(hide yes)
			(effects
				(font
					(size 1 1)
					(thickness 0.15)
				)
			)
		)
		(property "Manufacturer" "Panasonic"
			(at 0 0 180)
			(unlocked yes)
			(layer "F.Fab")
			(hide yes)
			(effects
				(font
					(size 1 1)
					(thickness 0.15)
				)
			)
		)
		(property "License" "Apache-2.0"
			(at 0 0 180)
			(unlocked yes)
			(layer "F.Fab")
			(hide yes)
			(effects
				(font
					(size 1 1)
					(thickness 0.15)
				)
			)
		)
		(property "Author" "Antmicro"
			(at 0 0 180)
			(unlocked yes)
			(layer "F.Fab")
			(hide yes)
			(effects
				(font
					(size 1 1)
					(thickness 0.15)
				)
			)
		)
		(property "Val" "0R"
			(at 0 0 180)
			(unlocked yes)
			(layer "F.Fab")
			(hide yes)
			(effects
				(font
					(size 1 1)
					(thickness 0.15)
				)
			)
		)
		(property "Tolerance" "~"
			(at 0 0 180)
			(unlocked yes)
			(layer "F.Fab")
			(hide yes)
			(effects
				(font
					(size 1 1)
					(thickness 0.15)
				)
			)
		)
		(property "Current" "1A"
			(at 0 0 180)
			(unlocked yes)
			(layer "F.Fab")
			(hide yes)
			(effects
				(font
					(size 1 1)
					(thickness 0.15)
				)
			)
		)
		(sheetname "/Peripherals/")
		(sheetfile "peripherals.kicad_sch")
		(attr smd exclude_from_pos_files exclude_from_bom dnp)
		(fp_rect
			(start -0.925 -0.47)
			(end 0.925 0.47)
			(stroke
				(width 0.05)
				(type default)
			)
			(fill no)
			(layer "F.CrtYd")
		)
		(fp_rect
			(start -0.5 -0.25)
			(end 0.5 0.25)
			(stroke
				(width 0.15)
				(type solid)
			)
			(fill no)
			(layer "F.Fab")
		)
		(fp_text user "Author: Antmicro"
			(at -0.95 4.169 0)
			(layer "F.Fab")
			(effects
				(font
					(size 0.7 0.7)
					(thickness 0.15)
				)
				(justify right top)
			)
		)
		(fp_text user "License: Apache-2.0"
			(at -0.95 5.169 0)
			(layer "F.Fab")
			(effects
				(font
					(size 0.7 0.7)
					(thickness 0.15)
				)
				(justify right top)
			)
		)
		(fp_text user "${REFERENCE}"
			(at -0.95 3.168 0)
			(layer "F.Fab")
			(effects
				(font
					(size 0.7 0.7)
					(thickness 0.15)
				)
				(justify right top)
			)
		)
		(pad "1" smd roundrect
			(at -0.48 0 180)
			(size 0.59 0.64)
			(layers "F.Cu" "F.Mask" "F.Paste")
			(roundrect_rratio 0.25)
			(net 501 "Net-(U801-V_{DD(UP)})")
			(pintype "passive")
		)
		(pad "2" smd roundrect
			(at 0.48 0 180)
			(size 0.59 0.64)
			(layers "F.Cu" "F.Mask" "F.Paste")
			(roundrect_rratio 0.25)
			(net 9 "+3V3")
			(pintype "passive")
		)
	)
	(footprint "antmicro-footprints:FB_0402_1005Metric"
		(layer "F.Cu")
		(at 90.192962 130.0515 -90)
		(descr "Ferrite Bead SMD 0402")
		(tags "ferrite bead SMD 0402")
		(property "Reference" "FB903"
			(at -0.99 -1.315 90)
			(layer "F.SilkS")
			(effects
				(font
					(size 0.7 0.7)
					(thickness 0.15)
				)
				(justify right bottom)
			)
		)
		(property "Value" "FB_120Z_1.3A_Murata-BLM15PD_0402"
			(at 0 1.4 90)
			(layer "F.Fab")
			(effects
				(font
					(size 0.7 0.7)
					(thickness 0.15)
				)
				(justify right bottom)
			)
		)
		(property "Datasheet" "https://www.murata.com/en-us/products/productdata/8796740059166/ENFA0018.pdf"
			(at 0 0 270)
			(layer "F.Fab")
			(hide yes)
			(effects
				(font
					(size 1.27 1.27)
					(thickness 0.15)
				)
			)
		)
		(property "MPN" "BLM15PD121SN1D"
			(at 0 0 270)
			(unlocked yes)
			(layer "F.Fab")
			(hide yes)
			(effects
				(font
					(size 1 1)
					(thickness 0.15)
				)
			)
		)
		(property "Manufacturer" "Murata"
			(at 0 0 270)
			(unlocked yes)
			(layer "F.Fab")
			(hide yes)
			(effects
				(font
					(size 1 1)
					(thickness 0.15)
				)
			)
		)
		(property "Author" "Antmicro"
			(at 0 0 270)
			(unlocked yes)
			(layer "F.Fab")
			(hide yes)
			(effects
				(font
					(size 1 1)
					(thickness 0.15)
				)
			)
		)
		(property "License" "Apache-2.0"
			(at 0 0 270)
			(unlocked yes)
			(layer "F.Fab")
			(hide yes)
			(effects
				(font
					(size 1 1)
					(thickness 0.15)
				)
			)
		)
		(property "Val" "120Z/1.3A"
			(at 0 0 270)
			(unlocked yes)
			(layer "F.Fab")
			(hide yes)
			(effects
				(font
					(size 1 1)
					(thickness 0.15)
				)
			)
		)
		(property "Current" ""
			(at 0 0 270)
			(unlocked yes)
			(layer "F.Fab")
			(hide yes)
			(effects
				(font
					(size 1 1)
					(thickness 0.15)
				)
			)
		)
		(sheetname "/USB/")
		(sheetfile "usb.kicad_sch")
		(attr smd)
		(fp_rect
			(start -0.925 -0.47)
			(end 0.925 0.47)
			(stroke
				(width 0.05)
				(type default)
			)
			(fill no)
			(layer "F.CrtYd")
		)
		(fp_rect
			(start -0.5 -0.25)
			(end 0.5 0.25)
			(stroke
				(width 0.15)
				(type solid)
			)
			(fill no)
			(layer "F.Fab")
		)
		(fp_text user "License: Apache-2.0"
			(at -0.95 5.169 270)
			(layer "F.Fab")
			(effects
				(font
					(size 0.7 0.7)
					(thickness 0.15)
				)
				(justify left bottom)
			)
		)
		(fp_text user "${REFERENCE}"
			(at -0.95 3.168 270)
			(layer "F.Fab")
			(effects
				(font
					(size 0.7 0.7)
					(thickness 0.15)
				)
				(justify left bottom)
			)
		)
		(fp_text user "Author: Antmicro"
			(at -0.95 4.169 270)
			(layer "F.Fab")
			(effects
				(font
					(size 0.7 0.7)
					(thickness 0.15)
				)
				(justify left bottom)
			)
		)
		(pad "1" smd roundrect
			(at -0.48 0 270)
			(size 0.59 0.64)
			(layers "F.Cu" "F.Mask" "F.Paste")
			(roundrect_rratio 0.25)
			(net 471 "Net-(D910-C)")
			(pintype "passive")
		)
		(pad "2" smd roundrect
			(at 0.48 0 270)
			(size 0.59 0.64)
			(layers "F.Cu" "F.Mask" "F.Paste")
			(roundrect_rratio 0.25)
			(net 211 "/USB/VCC_PD")
			(pintype "passive")
		)
	)
	(footprint "antmicro-footprints:TP_SMD_0.75mm"
		(layer "F.Cu")
		(at 94.45 131.55)
		(property "Reference" "TP918"
			(at 2.45 2.96 0)
			(layer "F.SilkS")
			(effects
				(font
					(size 0.7 0.7)
					(thickness 0.15)
				)
				(justify left bottom)
			)
		)
		(property "Value" "TP_0.75mm_SMD"
			(at 0 1.2 0)
			(layer "F.Fab")
			(effects
				(font
					(size 0.7 0.7)
					(thickness 0.15)
				)
				(justify left bottom)
			)
		)
		(property "MPN" ""
			(at 0 0 0)
			(unlocked yes)
			(layer "F.Fab")
			(hide yes)
			(effects
				(font
					(size 1 1)
					(thickness 0.15)
				)
			)
		)
		(property "Manufacturer" ""
			(at 0 0 0)
			(unlocked yes)
			(layer "F.Fab")
			(hide yes)
			(effects
				(font
					(size 1 1)
					(thickness 0.15)
				)
			)
		)
		(property "Author" "Antmicro"
			(at 0 0 0)
			(unlocked yes)
			(layer "F.Fab")
			(hide yes)
			(effects
				(font
					(size 1 1)
					(thickness 0.15)
				)
			)
		)
		(property "License" "Apache-2.0"
			(at 0 0 0)
			(unlocked yes)
			(layer "F.Fab")
			(hide yes)
			(effects
				(font
					(size 1 1)
					(thickness 0.15)
				)
			)
		)
		(sheetname "/USB/")
		(sheetfile "usb.kicad_sch")
		(attr exclude_from_pos_files exclude_from_bom)
		(fp_circle
			(center 0 0)
			(end 0.475 0)
			(stroke
				(width 0.05)
				(type default)
			)
			(fill no)
			(layer "F.CrtYd")
		)
		(fp_text user "${REFERENCE}"
			(at -0.4 2.7 0)
			(layer "F.Fab")
			(effects
				(font
					(size 0.7 0.7)
					(thickness 0.15)
				)
				(justify left bottom)
			)
		)
		(fp_text user "Author: Antmicro"
			(at -0.4 3.901 0)
			(layer "F.Fab")
			(effects
				(font
					(size 0.7 0.7)
					(thickness 0.15)
				)
				(justify left bottom)
			)
		)
		(fp_text user "License: Apache-2.0"
			(at -0.4 5.101 0)
			(layer "F.Fab")
			(effects
				(font
					(size 0.7 0.7)
					(thickness 0.15)
				)
				(justify left bottom)
			)
		)
		(pad "1" smd circle
			(at 0 0)
			(size 0.75 0.75)
			(layers "F.Cu" "F.Mask")
			(net 449 "Net-(U905-GPIO1)")
			(pinfunction "1")
			(pintype "passive")
		)
	)
	(footprint "antmicro-footprints:C_Pol_EIA-B"
		(layer "F.Cu")
		(at 101.777962 126.063)
		(property "Reference" "C929"
			(at 1.94 1.8135 0)
			(layer "F.SilkS")
			(effects
				(font
					(size 0.7 0.7)
					(thickness 0.15)
				)
				(justify left bottom)
			)
		)
		(property "Value" "C_Pol_330u_6.3V_KEMET-T520-B"
			(at 0 2.85 0)
			(layer "F.Fab")
			(effects
				(font
					(size 0.7 0.7)
					(thickness 0.15)
				)
				(justify left bottom)
			)
		)
		(property "Datasheet" "https://www.kemet.com/en/us/capacitors/product/T520B337M006ATE040.html"
			(at 0 0 0)
			(layer "F.Fab")
			(hide yes)
			(effects
				(font
					(size 1.27 1.27)
					(thickness 0.15)
				)
			)
		)
		(property "Val" "330u"
			(at 0 0 0)
			(unlocked yes)
			(layer "F.Fab")
			(hide yes)
			(effects
				(font
					(size 1 1)
					(thickness 0.15)
				)
			)
		)
		(property "MPN" "T520B337M006ATE040"
			(at 0 0 0)
			(unlocked yes)
			(layer "F.Fab")
			(hide yes)
			(effects
				(font
					(size 1 1)
					(thickness 0.15)
				)
			)
		)
		(property "Manufacturer" "KEMET"
			(at 0 0 0)
			(unlocked yes)
			(layer "F.Fab")
			(hide yes)
			(effects
				(font
					(size 1 1)
					(thickness 0.15)
				)
			)
		)
		(property "License" "Apache-2.0"
			(at 0 0 0)
			(unlocked yes)
			(layer "F.Fab")
			(hide yes)
			(effects
				(font
					(size 1 1)
					(thickness 0.15)
				)
			)
		)
		(property "Author" "Antmicro"
			(at 0 0 0)
			(unlocked yes)
			(layer "F.Fab")
			(hide yes)
			(effects
				(font
					(size 1 1)
					(thickness 0.15)
				)
			)
		)
		(property "Voltage" "6.3V"
			(at 0 0 0)
			(unlocked yes)
			(layer "F.Fab")
			(hide yes)
			(effects
				(font
					(size 1 1)
					(thickness 0.15)
				)
			)
		)
		(property "Dielectric" "template_dielectric"
			(at 0 0 0)
			(unlocked yes)
			(layer "F.Fab")
			(hide yes)
			(effects
				(font
					(size 1 1)
					(thickness 0.15)
				)
			)
		)
		(sheetname "/USB/")
		(sheetfile "usb.kicad_sch")
		(attr smd)
		(fp_line
			(start -2.521 -1.676)
			(end -2.123 -1.676)
			(stroke
				(width 0.15)
				(type solid)
			)
			(layer "F.SilkS")
		)
		(fp_line
			(start -2.325 -1.475)
			(end -2.325 -1.878)
			(stroke
				(width 0.15)
				(type solid)
			)
			(layer "F.SilkS")
		)
		(fp_line
			(start -1.8 -1.6)
			(end 1.8 -1.6)
			(stroke
				(width 0.15)
				(type solid)
			)
			(layer "F.SilkS")
		)
		(fp_line
			(start -1.8 -1.3)
			(end -1.8 -1.6)
			(stroke
				(width 0.15)
				(type solid)
			)
			(layer "F.SilkS")
		)
		(fp_line
			(start -1.8 1.3)
			(end -1.8 1.6)
			(stroke
				(width 0.15)
				(type solid)
			)
			(layer "F.SilkS")
		)
		(fp_line
			(start 1.8 -1.3)
			(end 1.8 -1.6)
			(stroke
				(width 0.15)
				(type solid)
			)
			(layer "F.SilkS")
		)
		(fp_line
			(start 1.8 1.3)
			(end 1.8 1.6)
			(stroke
				(width 0.15)
				(type solid)
			)
			(layer "F.SilkS")
		)
		(fp_line
			(start 1.8 1.6)
			(end -1.8 1.6)
			(stroke
				(width 0.15)
				(type solid)
			)
			(layer "F.SilkS")
		)
		(fp_line
			(start -2.411 -1.35)
			(end -2.41 1.35)
			(stroke
				(width 0.05)
				(type solid)
			)
			(layer "F.CrtYd")
		)
		(fp_line
			(start -1.97 -1.75)
			(end -1.97 -1.35)
			(stroke
				(width 0.05)
				(type solid)
			)
			(layer "F.CrtYd")
		)
		(fp_line
			(start -1.97 -1.35)
			(end -2.41 -1.35)
			(stroke
				(width 0.05)
				(type solid)
			)
			(layer "F.CrtYd")
		)
		(fp_line
			(start -1.97 1.35)
			(end -2.41 1.35)
			(stroke
				(width 0.05)
				(type solid)
			)
			(layer "F.CrtYd")
		)
		(fp_line
			(start -1.97 1.35)
			(end -1.97 1.75)
			(stroke
				(width 0.05)
				(type solid)
			)
			(layer "F.CrtYd")
		)
		(fp_line
			(start 1.959 -1.75)
			(end -1.97 -1.75)
			(stroke
				(width 0.05)
				(type solid)
			)
			(layer "F.CrtYd")
		)
		(fp_line
			(start 1.959 -1.75)
			(end 1.959 -1.35)
			(stroke
				(width 0.05)
				(type solid)
			)
			(layer "F.CrtYd")
		)
		(fp_line
			(start 1.96 1.35)
			(end 1.96 1.75)
			(stroke
				(width 0.05)
				(type solid)
			)
			(layer "F.CrtYd")
		)
		(fp_line
			(start 1.96 1.75)
			(end -1.97 1.75)
			(stroke
				(width 0.05)
				(type solid)
			)
			(layer "F.CrtYd")
		)
		(fp_line
			(start 2.399 -1.35)
			(end 1.959 -1.35)
			(stroke
				(width 0.05)
				(type solid)
			)
			(layer "F.CrtYd")
		)
		(fp_line
			(start 2.399 -1.35)
			(end 2.4 1.35)
			(stroke
				(width 0.05)
				(type solid)
			)
			(layer "F.CrtYd")
		)
		(fp_line
			(start 2.4 1.35)
			(end 1.96 1.35)
			(stroke
				(width 0.05)
				(type solid)
			)
			(layer "F.CrtYd")
		)
		(fp_line
			(start -1.7 1.324)
			(end -1.551 1.475)
			(stroke
				(width 0.15)
				(type solid)
			)
			(layer "F.Fab")
		)
		(fp_rect
			(start -1.72 -1.5)
			(end 1.719 1.499)
			(stroke
				(width 0.15)
				(type solid)
			)
			(fill no)
			(layer "F.Fab")
		)
		(fp_text user "License: Apache-2.0"
			(at -2.665 5.65 0)
			(layer "F.Fab")
			(effects
				(font
					(size 0.7 0.7)
					(thickness 0.15)
				)
				(justify left bottom)
			)
		)
		(fp_text user "Author: Antmicro"
			(at -2.665 6.85 0)
			(layer "F.Fab")
			(effects
				(font
					(size 0.7 0.7)
					(thickness 0.15)
				)
				(justify left bottom)
			)
		)
		(fp_text user "${REFERENCE}"
			(at -2.665 4.45 0)
			(layer "F.Fab")
			(effects
				(font
					(size 0.7 0.7)
					(thickness 0.15)
				)
				(justify left bottom)
			)
		)
		(pad "1" smd roundrect
			(at -1.551 0)
			(size 1.2 2.2)
			(layers "F.Cu" "F.Mask" "F.Paste")
			(roundrect_rratio 0.1)
			(net 28 "/USB/+5V_{CAP}")
			(pintype "passive")
		)
		(pad "2" smd roundrect
			(at 1.55 0)
			(size 1.2 2.2)
			(layers "F.Cu" "F.Mask" "F.Paste")
			(roundrect_rratio 0.1)
			(net 3 "GND")
			(pintype "passive")
		)
	)
	(footprint "antmicro-footprints:SOD-523"
		(layer "F.Cu")
		(at 96.107962 120.6165)
		(property "Reference" "D903"
			(at 24.645 26.035 0)
			(layer "F.SilkS")
			(effects
				(font
					(size 0.7 0.7)
					(thickness 0.15)
				)
				(justify left bottom)
			)
		)
		(property "Value" "PESD5Z5_0F"
			(at 0 1.499 0)
			(layer "F.Fab")
			(effects
				(font
					(size 0.7 0.7)
					(thickness 0.15)
				)
				(justify left bottom)
			)
		)
		(property "Datasheet" "https://assets.nexperia.com/documents/data-sheet/PESD5Z5_0.pdf"
			(at 0 0 0)
			(layer "F.Fab")
			(hide yes)
			(effects
				(font
					(size 1.27 1.27)
					(thickness 0.15)
				)
			)
		)
		(property "Manufacturer" "Nexperia"
			(at 0 0 0)
			(unlocked yes)
			(layer "F.Fab")
			(hide yes)
			(effects
				(font
					(size 1 1)
					(thickness 0.15)
				)
			)
		)
		(property "MPN" "PESD5Z5.0F"
			(at 0 0 0)
			(unlocked yes)
			(layer "F.Fab")
			(hide yes)
			(effects
				(font
					(size 1 1)
					(thickness 0.15)
				)
			)
		)
		(property "Author" "Antmicro"
			(at 0 0 0)
			(unlocked yes)
			(layer "F.Fab")
			(hide yes)
			(effects
				(font
					(size 1 1)
					(thickness 0.15)
				)
			)
		)
		(property "License" "Apache-2.0"
			(at 0 0 0)
			(unlocked yes)
			(layer "F.Fab")
			(hide yes)
			(effects
				(font
					(size 1 1)
					(thickness 0.15)
				)
			)
		)
		(sheetname "/USB/")
		(sheetfile "usb.kicad_sch")
		(attr smd)
		(fp_line
			(start -0.35 -0.5)
			(end -0.35 0.5)
			(stroke
				(width 0.15)
				(type solid)
			)
			(layer "F.SilkS")
		)
		(fp_rect
			(start -1 -0.6)
			(end 1 0.6)
			(stroke
				(width 0.05)
				(type solid)
			)
			(fill no)
			(layer "F.CrtYd")
		)
		(fp_line
			(start -0.652 -0.425)
			(end 0.65 -0.425)
			(stroke
				(width 0.15)
				(type solid)
			)
			(layer "F.Fab")
		)
		(fp_line
			(start -0.652 0.423)
			(end -0.652 -0.425)
			(stroke
				(width 0.15)
				(type solid)
			)
			(layer "F.Fab")
		)
		(fp_line
			(start -0.652 0.423)
			(end 0.65 0.423)
			(stroke
				(width 0.15)
				(type solid)
			)
			(layer "F.Fab")
		)
		(fp_line
			(start -0.35 -0.4)
			(end -0.35 0.4)
			(stroke
				(width 0.15)
				(type solid)
			)
			(layer "F.Fab")
		)
		(fp_line
			(start 0.65 -0.425)
			(end 0.65 0.423)
			(stroke
				(width 0.15)
				(type solid)
			)
			(layer "F.Fab")
		)
		(fp_text user "Author: Antmicro"
			(at -1.276 4.7 0)
			(layer "F.Fab")
			(effects
				(font
					(size 0.7 0.7)
					(thickness 0.15)
				)
				(justify left bottom)
			)
		)
		(fp_text user "License: Apache-2.0"
			(at -1.276 5.9 0)
			(layer "F.Fab")
			(effects
				(font
					(size 0.7 0.7)
					(thickness 0.15)
				)
				(justify left bottom)
			)
		)
		(fp_text user "${REFERENCE}"
			(at -1.276 3.499 0)
			(layer "F.Fab")
			(effects
				(font
					(size 0.7 0.7)
					(thickness 0.15)
				)
				(justify left bottom)
			)
		)
		(pad "1" smd roundrect
			(at -0.701 0)
			(size 0.5 0.6)
			(layers "F.Cu" "F.Mask" "F.Paste")
			(roundrect_rratio 0.25)
			(net 24 "/Compute module/USBA_VBUS")
			(pinfunction "C")
			(pintype "passive")
		)
		(pad "2" smd roundrect
			(at 0.699 0)
			(size 0.5 0.6)
			(layers "F.Cu" "F.Mask" "F.Paste")
			(roundrect_rratio 0.25)
			(net 3 "GND")
			(pinfunction "A")
			(pintype "passive")
		)
	)
	(footprint "antmicro-footprints:SOT-523"
		(layer "F.Cu")
		(at 90.692962 157.6915 90)
		(property "Reference" "Q213"
			(at -2.075 -1.005 180)
			(layer "F.SilkS")
			(effects
				(font
					(size 0.7 0.7)
					(thickness 0.15)
				)
				(justify left bottom)
			)
		)
		(property "Value" "PJE138K"
			(at 0.1 1.824 90)
			(layer "F.Fab")
			(effects
				(font
					(size 0.7 0.7)
					(thickness 0.15)
				)
				(justify left bottom)
			)
		)
		(property "Datasheet" "https://www.mouser.com/datasheet/2/1057/PJE138K-1876698.pdf"
			(at 0 0 90)
			(layer "F.Fab")
			(hide yes)
			(effects
				(font
					(size 1.27 1.27)
					(thickness 0.15)
				)
			)
		)
		(property "MPN" "PJE138K_R1_00001"
			(at 0 0 90)
			(unlocked yes)
			(layer "F.Fab")
			(hide yes)
			(effects
				(font
					(size 1 1)
					(thickness 0.15)
				)
			)
		)
		(property "Manufacturer" "PANJIT"
			(at 0 0 90)
			(unlocked yes)
			(layer "F.Fab")
			(hide yes)
			(effects
				(font
					(size 1 1)
					(thickness 0.15)
				)
			)
		)
		(property "Author" "Antmicro"
			(at 0 0 90)
			(unlocked yes)
			(layer "F.Fab")
			(hide yes)
			(effects
				(font
					(size 1 1)
					(thickness 0.15)
				)
			)
		)
		(property "License" "Apache-2.0"
			(at 0 0 90)
			(unlocked yes)
			(layer "F.Fab")
			(hide yes)
			(effects
				(font
					(size 1 1)
					(thickness 0.15)
				)
			)
		)
		(sheetname "/Compute module/")
		(sheetfile "compute-module.kicad_sch")
		(attr smd)
		(fp_line
			(start -0.277 -0.551)
			(end -0.277 -0.75)
			(stroke
				(width 0.15)
				(type solid)
			)
			(layer "F.SilkS")
		)
		(fp_line
			(start -0.725 -0.551)
			(end -0.277 -0.551)
			(stroke
				(width 0.15)
				(type solid)
			)
			(layer "F.SilkS")
		)
		(fp_line
			(start -0.927 -0.351)
			(end -0.725 -0.551)
			(stroke
				(width 0.15)
				(type solid)
			)
			(layer "F.SilkS")
		)
		(fp_line
			(start -0.927 -0.051)
			(end -0.927 -0.351)
			(stroke
				(width 0.15)
				(type solid)
			)
			(layer "F.SilkS")
		)
		(fp_circle
			(center -0.9652 0.9652)
			(end -0.9152 0.9652)
			(stroke
				(width 0.15)
				(type solid)
			)
			(fill yes)
			(layer "F.SilkS")
		)
		(fp_line
			(start 1.1 -1.16)
			(end 1.1 1.15)
			(stroke
				(width 0.05)
				(type solid)
			)
			(layer "F.CrtYd")
		)
		(fp_line
			(start -1.12 -1.16)
			(end 1.1 -1.16)
			(stroke
				(width 0.05)
				(type solid)
			)
			(layer "F.CrtYd")
		)
		(fp_line
			(start -1.12 -1.16)
			(end -1.12 1.15)
			(stroke
				(width 0.05)
				(type solid)
			)
			(layer "F.CrtYd")
		)
		(fp_line
			(start -1.12 1.15)
			(end 1.1 1.15)
			(stroke
				(width 0.05)
				(type solid)
			)
			(layer "F.CrtYd")
		)
		(fp_line
			(start 0.8 -0.425)
			(end -0.652 -0.425)
			(stroke
				(width 0.15)
				(type solid)
			)
			(layer "F.Fab")
		)
		(fp_line
			(start 0.8 -0.425)
			(end 0.8 0.424)
			(stroke
				(width 0.15)
				(type solid)
			)
			(layer "F.Fab")
		)
		(fp_line
			(start -0.652 -0.425)
			(end -0.802 -0.276)
			(stroke
				(width 0.15)
				(type solid)
			)
			(layer "F.Fab")
		)
		(fp_line
			(start -0.802 -0.276)
			(end -0.802 0.424)
			(stroke
				(width 0.15)
				(type solid)
			)
			(layer "F.Fab")
		)
		(fp_line
			(start 0.8 0.424)
			(end -0.802 0.424)
			(stroke
				(width 0.15)
				(type solid)
			)
			(layer "F.Fab")
		)
		(fp_circle
			(center -0.9652 0.9652)
			(end -0.9144 0.9652)
			(stroke
				(width 0.15)
				(type solid)
			)
			(fill no)
			(layer "F.Fab")
		)
		(fp_text user "License: Apache-2.0"
			(at -1.12 5.024 90)
			(layer "F.Fab")
			(effects
				(font
					(size 0.7 0.7)
					(thickness 0.15)
				)
				(justify left bottom)
			)
		)
		(fp_text user "Author: Antmicro"
			(at -1.12 6.224 90)
			(layer "F.Fab")
			(effects
				(font
					(size 0.7 0.7)
					(thickness 0.15)
				)
				(justify left bottom)
			)
		)
		(fp_text user "${REFERENCE}"
			(at -1.12 3.824 90)
			(layer "F.Fab")
			(effects
				(font
					(size 0.7 0.7)
					(thickness 0.15)
				)
				(justify left bottom)
			)
		)
		(pad "1" smd rect
			(at -0.5 0.65 90)
			(size 0.4 0.51)
			(layers "F.Cu" "F.Mask" "F.Paste")
			(net 347 "/Compute module/ExpanderINT")
			(pinfunction "G")
			(pintype "input")
		)
		(pad "2" smd rect
			(at 0.498 0.65 90)
			(size 0.4 0.51)
			(layers "F.Cu" "F.Mask" "F.Paste")
			(net 3 "GND")
			(pinfunction "S")
			(pintype "passive")
		)
		(pad "3" smd rect
			(at 0 -0.652 90)
			(size 0.4 0.51)
			(layers "F.Cu" "F.Mask" "F.Paste")
			(net 235 "/Compute module/GPIO.23")
			(pinfunction "D")
			(pintype "passive")
		)
	)
	(footprint "antmicro-footprints:Resonator_SMD_Murata_XRCGB_2x1.6x0.65mm"
		(layer "F.Cu")
		(at 74.867962 176.7165 90)
		(property "Reference" "Y801"
			(at -1.9035 0.512038 0)
			(layer "F.SilkS")
			(effects
				(font
					(size 0.7 0.7)
					(thickness 0.15)
				)
				(justify left bottom)
			)
		)
		(property "Value" "Resonator_27.12MHz_XRCGB"
			(at 0 2.2 90)
			(layer "F.Fab")
			(effects
				(font
					(size 0.7 0.7)
					(thickness 0.15)
				)
				(justify left bottom)
			)
		)
		(property "Datasheet" "https://www.murata.com/products/productdata/8801078247454/SPEC-XRCGB27M120F3M13R0.pdf?1541043011000"
			(at 0 0 90)
			(layer "F.Fab")
			(hide yes)
			(effects
				(font
					(size 1.27 1.27)
					(thickness 0.15)
				)
			)
		)
		(property "MPN" "XRCGB27M120F3M13R0"
			(at 0 0 90)
			(unlocked yes)
			(layer "F.Fab")
			(hide yes)
			(effects
				(font
					(size 1 1)
					(thickness 0.15)
				)
			)
		)
		(property "Manufacturer" "Murata"
			(at 0 0 90)
			(unlocked yes)
			(layer "F.Fab")
			(hide yes)
			(effects
				(font
					(size 1 1)
					(thickness 0.15)
				)
			)
		)
		(property "Author" "Antmicro"
			(at 0 0 90)
			(unlocked yes)
			(layer "F.Fab")
			(hide yes)
			(effects
				(font
					(size 1 1)
					(thickness 0.15)
				)
			)
		)
		(property "License" "Apache-2.0"
			(at 0 0 90)
			(unlocked yes)
			(layer "F.Fab")
			(hide yes)
			(effects
				(font
					(size 1 1)
					(thickness 0.15)
				)
			)
		)
		(property "Val" "27.12MHz"
			(at 0 0 90)
			(unlocked yes)
			(layer "F.Fab")
			(hide yes)
			(effects
				(font
					(size 1 1)
					(thickness 0.15)
				)
			)
		)
		(property "CLoad" "10pF"
			(at 0 0 90)
			(unlocked yes)
			(layer "F.Fab")
			(hide yes)
			(effects
				(font
					(size 1 1)
					(thickness 0.15)
				)
			)
		)
		(sheetname "/Peripherals/")
		(sheetfile "peripherals.kicad_sch")
		(attr smd)
		(fp_line
			(start -0.4 -1.15)
			(end 0.4 -1.15)
			(stroke
				(width 0.15)
				(type solid)
			)
			(layer "F.SilkS")
		)
		(fp_line
			(start 0.95 0.4)
			(end 0.95 -0.4)
			(stroke
				(width 0.15)
				(type solid)
			)
			(layer "F.SilkS")
		)
		(fp_line
			(start -0.95 0.4)
			(end -0.95 -0.4)
			(stroke
				(width 0.15)
				(type solid)
			)
			(layer "F.SilkS")
		)
		(fp_line
			(start -0.4 1.15)
			(end 0.4 1.15)
			(stroke
				(width 0.15)
				(type solid)
			)
			(layer "F.SilkS")
		)
		(fp_circle
			(center -0.95 -1.15)
			(end -0.9 -1.15)
			(stroke
				(width 0.15)
				(type solid)
			)
			(fill yes)
			(layer "F.SilkS")
		)
		(fp_rect
			(start -1.05 -1.25)
			(end 1.05 1.24)
			(stroke
				(width 0.05)
				(type solid)
			)
			(fill no)
			(layer "F.CrtYd")
		)
		(fp_rect
			(start -0.85 -1.054)
			(end 0.852 1.054)
			(stroke
				(width 0.15)
				(type solid)
			)
			(fill no)
			(layer "F.Fab")
		)
		(fp_text user "License: Apache-2.0"
			(at -1.05 5.8 90)
			(layer "F.Fab")
			(effects
				(font
					(size 0.7 0.7)
					(thickness 0.15)
				)
				(justify left bottom)
			)
		)
		(fp_text user "${REFERENCE}"
			(at -1.05 3.4 90)
			(layer "F.Fab")
			(effects
				(font
					(size 0.7 0.7)
					(thickness 0.15)
				)
				(justify left bottom)
			)
		)
		(fp_text user "Author: Antmicro"
			(at -1.05 4.6 90)
			(layer "F.Fab")
			(effects
				(font
					(size 0.7 0.7)
					(thickness 0.15)
				)
				(justify left bottom)
			)
		)
		(pad "1" smd rect
			(at -0.5 -0.675 90)
			(size 0.7 0.75)
			(layers "F.Cu" "F.Mask" "F.Paste")
			(net 99 "Net-(U801-XTAL2)")
			(pintype "passive")
		)
		(pad "2" smd rect
			(at -0.5 0.675 90)
			(size 0.7 0.75)
			(layers "F.Cu" "F.Mask" "F.Paste")
			(net 3 "GND")
			(pinfunction "SH")
			(pintype "passive")
		)
		(pad "3" smd rect
			(at 0.5 0.675 90)
			(size 0.7 0.75)
			(layers "F.Cu" "F.Mask" "F.Paste")
			(net 108 "Net-(U801-CLK_XTAL1)")
			(pintype "passive")
		)
		(pad "4" smd rect
			(at 0.5 -0.675 90)
			(size 0.7 0.75)
			(layers "F.Cu" "F.Mask" "F.Paste")
			(net 3 "GND")
			(pinfunction "SH")
			(pintype "passive")
		)
	)
	(footprint "antmicro-footprints:R_0402_1005Metric"
		(layer "F.Cu")
		(at 117.88 153.4415 180)
		(descr "Resistor SMD 0402")
		(tags "resistor SMD 0402")
		(property "Reference" "R216"
			(at -3.525 -0.325 180)
			(layer "F.SilkS")
			(effects
				(font
					(size 0.7 0.7)
					(thickness 0.15)
				)
				(justify left bottom)
			)
		)
		(property "Value" "R_0R_0402"
			(at -1.011843 1.772047 180)
			(layer "F.Fab")
			(effects
				(font
					(size 0.7 0.7)
					(thickness 0.15)
				)
				(justify left bottom)
			)
		)
		(property "Datasheet" "https://industrial.panasonic.com/cdbs/www-data/pdf/RDA0000/AOA0000C301.pdf"
			(at 0 0 180)
			(layer "F.Fab")
			(hide yes)
			(effects
				(font
					(size 1.27 1.27)
					(thickness 0.15)
				)
			)
		)
		(property "Manufacturer" "Panasonic"
			(at 0 0 180)
			(unlocked yes)
			(layer "F.Fab")
			(hide yes)
			(effects
				(font
					(size 1 1)
					(thickness 0.15)
				)
			)
		)
		(property "MPN" "ERJ2GE0R00X"
			(at 0 0 180)
			(unlocked yes)
			(layer "F.Fab")
			(hide yes)
			(effects
				(font
					(size 1 1)
					(thickness 0.15)
				)
			)
		)
		(property "Val" "0R"
			(at 0 0 180)
			(unlocked yes)
			(layer "F.Fab")
			(hide yes)
			(effects
				(font
					(size 1 1)
					(thickness 0.15)
				)
			)
		)
		(property "License" "Apache-2.0"
			(at 0 0 180)
			(unlocked yes)
			(layer "F.Fab")
			(hide yes)
			(effects
				(font
					(size 1 1)
					(thickness 0.15)
				)
			)
		)
		(property "Author" "Antmicro"
			(at 0 0 180)
			(unlocked yes)
			(layer "F.Fab")
			(hide yes)
			(effects
				(font
					(size 1 1)
					(thickness 0.15)
				)
			)
		)
		(property "Tolerance" "~"
			(at 0 0 180)
			(unlocked yes)
			(layer "F.Fab")
			(hide yes)
			(effects
				(font
					(size 1 1)
					(thickness 0.15)
				)
			)
		)
		(property "Current" "1A"
			(at 0 0 180)
			(unlocked yes)
			(layer "F.Fab")
			(hide yes)
			(effects
				(font
					(size 1 1)
					(thickness 0.15)
				)
			)
		)
		(sheetname "/Compute module/")
		(sheetfile "compute-module.kicad_sch")
		(attr smd)
		(fp_rect
			(start -0.925 -0.47)
			(end 0.925 0.47)
			(stroke
				(width 0.05)
				(type default)
			)
			(fill no)
			(layer "F.CrtYd")
		)
		(fp_rect
			(start -0.5 -0.25)
			(end 0.5 0.25)
			(stroke
				(width 0.15)
				(type solid)
			)
			(fill no)
			(layer "F.Fab")
		)
		(fp_text user "Author: Antmicro"
			(at -0.95 4.169 180)
			(layer "F.Fab")
			(effects
				(font
					(size 0.7 0.7)
					(thickness 0.15)
				)
				(justify left bottom)
			)
		)
		(fp_text user "License: Apache-2.0"
			(at -0.95 5.169 180)
			(layer "F.Fab")
			(effects
				(font
					(size 0.7 0.7)
					(thickness 0.15)
				)
				(justify left bottom)
			)
		)
		(fp_text user "${REFERENCE}"
			(at -0.95 3.168 180)
			(layer "F.Fab")
			(effects
				(font
					(size 0.7 0.7)
					(thickness 0.15)
				)
				(justify left bottom)
			)
		)
		(pad "1" smd roundrect
			(at -0.48 0 180)
			(size 0.59 0.64)
			(layers "F.Cu" "F.Mask" "F.Paste")
			(roundrect_rratio 0.25)
			(net 169 "/Compute module/NVMe.TX1_P")
			(pintype "passive")
		)
		(pad "2" smd roundrect
			(at 0.48 0 180)
			(size 0.59 0.64)
			(layers "F.Cu" "F.Mask" "F.Paste")
			(roundrect_rratio 0.25)
			(net 139 "/Compute module/T1_P")
			(pintype "passive")
		)
	)
	(footprint "antmicro-footprints:VFQFN-40-1EP_6x6mm"
		(layer "F.Cu")
		(at 71.567962 171.8165 -90)
		(property "Reference" "U801"
			(at -3.7665 -3.422038 0)
			(layer "F.SilkS")
			(effects
				(font
					(size 0.7 0.7)
					(thickness 0.15)
				)
				(justify left top)
			)
		)
		(property "Value" "PN7160A1_VFQFN"
			(at 0 4.6 90)
			(layer "F.Fab")
			(effects
				(font
					(size 0.7 0.7)
					(thickness 0.15)
				)
				(justify right bottom)
			)
		)
		(property "Datasheet" "https://www.nxp.com/docs/en/data-sheet/PN7160_PN7161.pdf"
			(at 0 0 90)
			(layer "F.Fab")
			(hide yes)
			(effects
				(font
					(size 1.27 1.27)
					(thickness 0.15)
				)
			)
		)
		(property "MPN" "PN7160A1HN/C100E"
			(at 0 0 270)
			(unlocked yes)
			(layer "F.Fab")
			(hide yes)
			(effects
				(font
					(size 1 1)
					(thickness 0.15)
				)
			)
		)
		(property "Manufacturer" "NXP"
			(at 0 0 270)
			(unlocked yes)
			(layer "F.Fab")
			(hide yes)
			(effects
				(font
					(size 1 1)
					(thickness 0.15)
				)
			)
		)
		(property "Author" "Antmicro"
			(at 0 0 270)
			(unlocked yes)
			(layer "F.Fab")
			(hide yes)
			(effects
				(font
					(size 1 1)
					(thickness 0.15)
				)
			)
		)
		(property "License" "Apache-2.0"
			(at 0 0 270)
			(unlocked yes)
			(layer "F.Fab")
			(hide yes)
			(effects
				(font
					(size 1 1)
					(thickness 0.15)
				)
			)
		)
		(property ki_fp_filters "QFN40_PN7160_NXP QFN40_PN7160_NXP-M QFN40_PN7160_NXP-L")
		(sheetname "/Peripherals/")
		(sheetfile "peripherals.kicad_sch")
		(attr smd)
		(fp_line
			(start -3.125 3.125)
			(end -3.125 2.675)
			(stroke
				(width 0.15)
				(type solid)
			)
			(layer "F.SilkS")
		)
		(fp_line
			(start -2.725 3.125)
			(end -3.125 3.125)
			(stroke
				(width 0.15)
				(type solid)
			)
			(layer "F.SilkS")
		)
		(fp_line
			(start 3.125 3.125)
			(end 2.575 3.125)
			(stroke
				(width 0.15)
				(type solid)
			)
			(layer "F.SilkS")
		)
		(fp_line
			(start 3.125 2.575)
			(end 3.125 3.125)
			(stroke
				(width 0.15)
				(type solid)
			)
			(layer "F.SilkS")
		)
		(fp_line
			(start -3.125 -2.625)
			(end -3.125 -2.5)
			(stroke
				(width 0.15)
				(type solid)
			)
			(layer "F.SilkS")
		)
		(fp_line
			(start 3.125 -2.625)
			(end 3.125 -3.125)
			(stroke
				(width 0.15)
				(type solid)
			)
			(layer "F.SilkS")
		)
		(fp_line
			(start -2.725 -3.125)
			(end -3.125 -2.625)
			(stroke
				(width 0.15)
				(type solid)
			)
			(layer "F.SilkS")
		)
		(fp_line
			(start -2.525 -3.125)
			(end -2.725 -3.125)
			(stroke
				(width 0.15)
				(type solid)
			)
			(layer "F.SilkS")
		)
		(fp_line
			(start 3.125 -3.125)
			(end 2.575 -3.125)
			(stroke
				(width 0.15)
				(type solid)
			)
			(layer "F.SilkS")
		)
		(fp_circle
			(center -3.4 -2.6)
			(end -3.35 -2.6)
			(stroke
				(width 0.15)
				(type solid)
			)
			(fill yes)
			(layer "F.SilkS")
		)
		(fp_line
			(start -3.68 3.68)
			(end 3.68 3.68)
			(stroke
				(width 0.05)
				(type solid)
			)
			(layer "F.CrtYd")
		)
		(fp_line
			(start -3.68 -3.68)
			(end -3.68 3.68)
			(stroke
				(width 0.05)
				(type solid)
			)
			(layer "F.CrtYd")
		)
		(fp_line
			(start 3.68 -3.68)
			(end 3.68 3.68)
			(stroke
				(width 0.05)
				(type solid)
			)
			(layer "F.CrtYd")
		)
		(fp_line
			(start 3.68 -3.68)
			(end -3.68 -3.68)
			(stroke
				(width 0.05)
				(type solid)
			)
			(layer "F.CrtYd")
		)
		(fp_line
			(start -3.025 3.025)
			(end 3.025 3.025)
			(stroke
				(width 0.15)
				(type solid)
			)
			(layer "F.Fab")
		)
		(fp_line
			(start -3.025 -2.525)
			(end -3.025 3.025)
			(stroke
				(width 0.15)
				(type solid)
			)
			(layer "F.Fab")
		)
		(fp_line
			(start -2.625 -3.025)
			(end -3.025 -2.525)
			(stroke
				(width 0.15)
				(type solid)
			)
			(layer "F.Fab")
		)
		(fp_line
			(start -2.625 -3.025)
			(end 3.025 -3.025)
			(stroke
				(width 0.15)
				(type solid)
			)
			(layer "F.Fab")
		)
		(fp_line
			(start 3.025 -3.025)
			(end 3.025 3.025)
			(stroke
				(width 0.15)
				(type solid)
			)
			(layer "F.Fab")
		)
		(fp_text user "${REFERENCE}"
			(at -4.03 6.6 90)
			(layer "F.Fab")
			(effects
				(font
					(size 0.7 0.7)
					(thickness 0.15)
					(italic yes)
				)
				(justify right top)
			)
		)
		(fp_text user "Author: Antmicro"
			(at 0 5.75 90)
			(layer "F.Fab")
			(effects
				(font
					(size 0.7 0.7)
					(thickness 0.15)
				)
				(justify right bottom)
			)
		)
		(fp_text user "License: Apache-2.0"
			(at 0 6.95 90)
			(layer "F.Fab")
			(effects
				(font
					(size 0.7 0.7)
					(thickness 0.15)
				)
				(justify right bottom)
			)
		)
		(pad "1" smd rect
			(at -2.975 -2.25 270)
			(size 0.85 0.28)
			(layers "F.Cu" "F.Mask" "F.Paste")
			(net 374 "Net-(U801-I2C_ADR0)")
			(pinfunction "I2C_ADR0")
			(pintype "bidirectional")
			(solder_mask_margin 0.07)
		)
		(pad "2" smd rect
			(at -2.975 -1.75 270)
			(size 0.85 0.28)
			(layers "F.Cu" "F.Mask" "F.Paste")
			(net 287 "/Compute module/NFC.DWL_REQ")
			(pinfunction "DWL_REQ")
			(pintype "input")
			(solder_mask_margin 0.07)
		)
		(pad "3" smd rect
			(at -2.975 -1.25 270)
			(size 0.85 0.28)
			(layers "F.Cu" "F.Mask" "F.Paste")
			(net 375 "Net-(U801-I2C_ADR1)")
			(pinfunction "I2C_ADR1")
			(pintype "bidirectional")
			(solder_mask_margin 0.07)
		)
		(pad "4" smd rect
			(at -2.975 -0.75 270)
			(size 0.85 0.28)
			(layers "F.Cu" "F.Mask" "F.Paste")
			(net 3 "GND")
			(pinfunction "VSS")
			(pintype "power_out")
			(solder_mask_margin 0.07)
		)
		(pad "5" smd rect
			(at -2.975 -0.25 270)
			(size 0.85 0.28)
			(layers "F.Cu" "F.Mask" "F.Paste")
			(net 143 "/CSI/I_{2}C1.SDA")
			(pinfunction "I2C_SDA")
			(pintype "bidirectional")
			(solder_mask_margin 0.07)
		)
		(pad "6" smd rect
			(at -2.975 0.25 270)
			(size 0.85 0.28)
			(layers "F.Cu" "F.Mask" "F.Paste")
			(net 9 "+3V3")
			(pinfunction "V_{DD(PAD)}")
			(pintype "power_in")
			(solder_mask_margin 0.07)
		)
		(pad "7" smd rect
			(at -2.975 0.75 270)
			(size 0.85 0.28)
			(layers "F.Cu" "F.Mask" "F.Paste")
			(net 142 "/CSI/I_{2}C1.SCL")
			(pinfunction "I2C_SCL")
			(pintype "bidirectional")
			(solder_mask_margin 0.07)
		)
		(pad "8" smd rect
			(at -2.975 1.25 270)
			(size 0.85 0.28)
			(layers "F.Cu" "F.Mask" "F.Paste")
			(net 286 "/Compute module/NFC.IRQ")
			(pinfunction "IRQ")
			(pintype "output")
			(solder_mask_margin 0.07)
		)
		(pad "9" smd rect
			(at -2.975 1.75 270)
			(size 0.85 0.28)
			(layers "F.Cu" "F.Mask" "F.Paste")
			(net 3 "GND")
			(pinfunction "VSS")
			(pintype "power_out")
			(solder_mask_margin 0.07)
		)
		(pad "10" smd rect
			(at -2.975 2.25 270)
			(size 0.85 0.28)
			(layers "F.Cu" "F.Mask" "F.Paste")
			(net 285 "/Compute module/NFC.EN")
			(pinfunction "VEN/~{RST}")
			(pintype "input")
			(solder_mask_margin 0.07)
		)
		(pad "11" smd rect
			(at -2.25 2.975 270)
			(size 0.28 0.85)
			(layers "F.Cu" "F.Mask" "F.Paste")
			(net 398 "unconnected-(U801-IC-Pad11)")
			(pinfunction "IC")
			(pintype "no_connect")
			(solder_mask_margin 0.07)
		)
		(pad "12" smd rect
			(at -1.75 2.975 270)
			(size 0.28 0.85)
			(layers "F.Cu" "F.Mask" "F.Paste")
			(net 501 "Net-(U801-V_{DD(UP)})")
			(pinfunction "V_{BAT}")
			(pintype "passive")
			(solder_mask_margin 0.07)
		)
		(pad "13" smd rect
			(at -1.25 2.975 270)
			(size 0.28 0.85)
			(layers "F.Cu" "F.Mask" "F.Paste")
			(net 501 "Net-(U801-V_{DD(UP)})")
			(pinfunction "V_{DD(UP)}")
			(pintype "power_in")
			(solder_mask_margin 0.07)
		)
		(pad "14" smd rect
			(at -0.75 2.975 270)
			(size 0.28 0.85)
			(layers "F.Cu" "F.Mask" "F.Paste")
			(net 94 "Net-(U801-TVDD_IN)")
			(pinfunction "V_{DD(TX)}")
			(pintype "power_in")
			(solder_mask_margin 0.07)
		)
		(pad "15" smd rect
			(at -0.25 2.975 270)
			(size 0.28 0.85)
			(layers "F.Cu" "F.Mask" "F.Paste")
			(net 105 "Net-(U801-RXN)")
			(pinfunction "RXN")
			(pintype "input")
			(solder_mask_margin 0.07)
		)
		(pad "16" smd rect
			(at 0.25 2.975 270)
			(size 0.28 0.85)
			(layers "F.Cu" "F.Mask" "F.Paste")
			(net 103 "Net-(U801-RXP)")
			(pinfunction "RXP")
			(pintype "input")
			(solder_mask_margin 0.07)
		)
		(pad "17" smd rect
			(at 0.75 2.975 270)
			(size 0.28 0.85)
			(layers "F.Cu" "F.Mask" "F.Paste")
			(net 95 "Net-(U801-V_{DD(VMID)})")
			(pinfunction "V_{DD(VMID)}")
			(pintype "power_in")
			(solder_mask_margin 0.07)
		)
		(pad "18" smd rect
			(at 1.25 2.975 270)
			(size 0.28 0.85)
			(layers "F.Cu" "F.Mask" "F.Paste")
			(net 94 "Net-(U801-TVDD_IN)")
			(pinfunction "TVDD_IN")
			(pintype "power_in")
			(solder_mask_margin 0.07)
		)
		(pad "19" smd rect
			(at 1.75 2.975 270)
			(size 0.28 0.85)
			(layers "F.Cu" "F.Mask" "F.Paste")
			(net 326 "Net-(U801-TX2)")
			(pinfunction "TX2")
			(pintype "output")
			(solder_mask_margin 0.07)
		)
		(pad "20" smd rect
			(at 2.25 2.975 270)
			(size 0.28 0.85)
			(layers "F.Cu" "F.Mask" "F.Paste")
			(net 3 "GND")
			(pinfunction "VSS")
			(pintype "power_out")
			(solder_mask_margin 0.07)
		)
		(pad "21" smd rect
			(at 2.975 2.25 270)
			(size 0.85 0.28)
			(layers "F.Cu" "F.Mask" "F.Paste")
			(net 325 "Net-(U801-TX1)")
			(pinfunction "TX1")
			(pintype "output")
			(solder_mask_margin 0.07)
		)
		(pad "22" smd rect
			(at 2.975 1.75 270)
			(size 0.85 0.28)
			(layers "F.Cu" "F.Mask" "F.Paste")
			(net 94 "Net-(U801-TVDD_IN)")
			(pinfunction "TVDD_IN2")
			(pintype "power_in")
			(solder_mask_margin 0.07)
		)
		(pad "23" smd rect
			(at 2.975 1.25 270)
			(size 0.85 0.28)
			(layers "F.Cu" "F.Mask" "F.Paste")
			(net 101 "Net-(U801-ANT1)")
			(pinfunction "ANT1")
			(pintype "bidirectional")
			(solder_mask_margin 0.07)
		)
		(pad "24" smd rect
			(at 2.975 0.75 270)
			(size 0.85 0.28)
			(layers "F.Cu" "F.Mask" "F.Paste")
			(net 107 "Net-(U801-ANT2)")
			(pinfunction "ANT2")
			(pintype "bidirectional")
			(solder_mask_margin 0.07)
		)
		(pad "25" smd rect
			(at 2.975 0.25 270)
			(size 0.85 0.28)
			(layers "F.Cu" "F.Mask" "F.Paste")
			(net 383 "Net-(U801-V_{DD(HF)})")
			(pinfunction "V_{DD(HF)}")
			(pintype "power_in")
			(solder_mask_margin 0.07)
		)
		(pad "26" smd rect
			(at 2.975 -0.25 270)
			(size 0.85 0.28)
			(layers "F.Cu" "F.Mask" "F.Paste")
			(net 93 "Net-(U801-V_{DD(A)})")
			(pinfunction "V_{DD(A)}")
			(pintype "power_in")
			(solder_mask_margin 0.07)
		)
		(pad "27" smd rect
			(at 2.975 -0.75 270)
			(size 0.96 0.28)
			(layers "F.Cu" "F.Mask" "F.Paste")
			(net 93 "Net-(U801-V_{DD(A)})")
			(pinfunction "V_{DD}")
			(pintype "power_in")
			(solder_mask_margin 0.07)
		)
		(pad "28" smd rect
			(at 2.975 -1.25 270)
			(size 0.85 0.28)
			(layers "F.Cu" "F.Mask" "F.Paste")
			(net 501 "Net-(U801-V_{DD(UP)})")
			(pinfunction "V_{BAT}")
			(pintype "power_in")
			(solder_mask_margin 0.07)
		)
		(pad "29" smd rect
			(at 2.975 -1.75 270)
			(size 0.85 0.28)
			(layers "F.Cu" "F.Mask" "F.Paste")
			(net 99 "Net-(U801-XTAL2)")
			(pinfunction "XTAL2")
			(pintype "output")
			(solder_mask_margin 0.07)
		)
		(pad "30" smd rect
			(at 2.975 -2.25 270)
			(size 0.85 0.28)
			(layers "F.Cu" "F.Mask" "F.Paste")
			(net 108 "Net-(U801-CLK_XTAL1)")
			(pinfunction "CLK_XTAL1")
			(pintype "input")
			(solder_mask_margin 0.07)
		)
		(pad "31" smd rect
			(at 2.25 -2.975 270)
			(size 0.28 0.85)
			(layers "F.Cu" "F.Mask" "F.Paste")
			(net 93 "Net-(U801-V_{DD(A)})")
			(pinfunction "V_{DD(D)}")
			(pintype "power_in")
			(solder_mask_margin 0.07)
		)
		(pad "32" smd rect
			(at 1.75 -2.975 270)
			(size 0.28 0.85)
			(layers "F.Cu" "F.Mask" "F.Paste")
			(net 399 "unconnected-(U801-NC-Pad32)")
			(pinfunction "NC")
			(pintype "no_connect")
			(solder_mask_margin 0.07)
		)
		(pad "33" smd rect
			(at 1.25 -2.975 270)
			(size 0.28 0.85)
			(layers "F.Cu" "F.Mask" "F.Paste")
			(net 400 "unconnected-(U801-NC-Pad33)")
			(pinfunction "NC")
			(pintype "no_connect")
			(solder_mask_margin 0.07)
		)
		(pad "34" smd rect
			(at 0.75 -2.975 270)
			(size 0.28 0.85)
			(layers "F.Cu" "F.Mask" "F.Paste")
			(net 401 "unconnected-(U801-NC-Pad34)")
			(pinfunction "NC")
			(pintype "no_connect")
			(solder_mask_margin 0.07)
		)
		(pad "35" smd rect
			(at 0.25 -2.975 270)
			(size 0.28 0.85)
			(layers "F.Cu" "F.Mask" "F.Paste")
			(net 402 "unconnected-(U801-NC-Pad35)")
			(pinfunction "NC")
			(pintype "no_connect")
			(solder_mask_margin 0.07)
		)
		(pad "36" smd rect
			(at -0.25 -2.975 270)
			(size 0.28 0.85)
			(layers "F.Cu" "F.Mask" "F.Paste")
			(net 403 "unconnected-(U801-NC-Pad36)")
			(pinfunction "NC")
			(pintype "no_connect")
			(solder_mask_margin 0.07)
		)
		(pad "37" smd rect
			(at -0.75 -2.975 270)
			(size 0.28 0.85)
			(layers "F.Cu" "F.Mask" "F.Paste")
			(net 381 "Net-(U801-DCDC_EN)")
			(pinfunction "DCDC_EN")
			(pintype "output")
			(solder_mask_margin 0.07)
		)
		(pad "38" smd rect
			(at -1.25 -2.975 270)
			(size 0.28 0.85)
			(layers "F.Cu" "F.Mask" "F.Paste")
			(net 404 "unconnected-(U801-IC-Pad38)")
			(pinfunction "IC")
			(pintype "no_connect")
			(solder_mask_margin 0.07)
		)
		(pad "39" smd rect
			(at -1.75 -2.975 270)
			(size 0.28 0.85)
			(layers "F.Cu" "F.Mask" "F.Paste")
			(net 328 "/Compute module/NFC.WKUP_REQ")
			(pinfunction "WKUP_REQ")
			(pintype "input")
			(solder_mask_margin 0.07)
		)
		(pad "40" smd rect
			(at -2.25 -2.975 270)
			(size 0.28 0.85)
			(layers "F.Cu" "F.Mask" "F.Paste")
			(net 382 "Net-(U801-CLK_REQ)")
			(pinfunction "CLK_REQ")
			(pintype "output")
			(solder_mask_margin 0.07)
		)
		(pad "41" smd rect
			(at 0 0 270)
			(size 4.5 4.5)
			(layers "F.Cu" "F.Mask" "F.Paste")
			(net 3 "GND")
			(pinfunction "VSS")
			(pintype "passive")
		)
	)
	(footprint "antmicro-footprints:TSOT23-6"
		(layer "F.Cu")
		(at 132.917962 158.6165 -90)
		(property "Reference" "U602"
			(at 1.12 1.65 0)
			(layer "F.SilkS")
			(effects
				(font
					(size 0.7 0.7)
					(thickness 0.15)
				)
				(justify right bottom)
			)
		)
		(property "Value" "AP22615A_TSOT26"
			(at 0 2.6 90)
			(layer "F.Fab")
			(effects
				(font
					(size 0.7 0.7)
					(thickness 0.15)
				)
				(justify right bottom)
			)
		)
		(property "Datasheet" "https://www.mouser.com/datasheet/2/115/DIOD_S_A0008958405_1-2543193.pdf"
			(at 0 0 270)
			(layer "F.Fab")
			(hide yes)
			(effects
				(font
					(size 1.27 1.27)
					(thickness 0.15)
				)
			)
		)
		(property "MPN" "AP22615AWU-7"
			(at 0 0 270)
			(unlocked yes)
			(layer "F.Fab")
			(hide yes)
			(effects
				(font
					(size 1 1)
					(thickness 0.15)
				)
			)
		)
		(property "Manufacturer" "Diodes Incorporated"
			(at 0 0 270)
			(unlocked yes)
			(layer "F.Fab")
			(hide yes)
			(effects
				(font
					(size 1 1)
					(thickness 0.15)
				)
			)
		)
		(property "Author" "Antmicro"
			(at 0 0 270)
			(unlocked yes)
			(layer "F.Fab")
			(hide yes)
			(effects
				(font
					(size 1 1)
					(thickness 0.15)
				)
			)
		)
		(property "License" "Apache-2.0"
			(at 0 0 270)
			(unlocked yes)
			(layer "F.Fab")
			(hide yes)
			(effects
				(font
					(size 1 1)
					(thickness 0.15)
				)
			)
		)
		(sheetname "/CSI/")
		(sheetfile "csi.kicad_sch")
		(attr smd)
		(fp_line
			(start -1 1.55)
			(end -1 1.4)
			(stroke
				(width 0.15)
				(type solid)
			)
			(layer "F.SilkS")
		)
		(fp_line
			(start 1 1.55)
			(end -1 1.55)
			(stroke
				(width 0.15)
				(type solid)
			)
			(layer "F.SilkS")
		)
		(fp_line
			(start 1 1.55)
			(end 1 1.4)
			(stroke
				(width 0.15)
				(type solid)
			)
			(layer "F.SilkS")
		)
		(fp_line
			(start 1 -1.497)
			(end 1 -1.375)
			(stroke
				(width 0.15)
				(type solid)
			)
			(layer "F.SilkS")
		)
		(fp_line
			(start 1 -1.497)
			(end -1 -1.5)
			(stroke
				(width 0.15)
				(type solid)
			)
			(layer "F.SilkS")
		)
		(fp_line
			(start -1 -1.5)
			(end -1 -1.375)
			(stroke
				(width 0.15)
				(type solid)
			)
			(layer "F.SilkS")
		)
		(fp_circle
			(center -1.44 -1.5)
			(end -1.39 -1.5)
			(stroke
				(width 0.15)
				(type solid)
			)
			(fill yes)
			(layer "F.SilkS")
		)
		(fp_rect
			(start 1.93 -1.7)
			(end -1.93 1.7)
			(stroke
				(width 0.05)
				(type solid)
			)
			(fill no)
			(layer "F.CrtYd")
		)
		(fp_line
			(start -0.45 -1.521)
			(end -0.876 -1.096)
			(stroke
				(width 0.15)
				(type solid)
			)
			(layer "F.Fab")
		)
		(fp_rect
			(start 0.875 1.528)
			(end -0.875 -1.525)
			(stroke
				(width 0.15)
				(type solid)
			)
			(fill no)
			(layer "F.Fab")
		)
		(fp_text user "License: Apache-2.0"
			(at -1.93 6.199 270)
			(layer "F.Fab")
			(effects
				(font
					(size 0.7 0.7)
					(thickness 0.15)
				)
				(justify left bottom)
			)
		)
		(fp_text user "${REFERENCE}"
			(at -1.93 3.8 270)
			(layer "F.Fab")
			(effects
				(font
					(size 0.7 0.7)
					(thickness 0.15)
				)
				(justify left bottom)
			)
		)
		(fp_text user "Author: Antmicro"
			(at -1.93 5 270)
			(layer "F.Fab")
			(effects
				(font
					(size 0.7 0.7)
					(thickness 0.15)
				)
				(justify left bottom)
			)
		)
		(pad "1" smd rect
			(at -1.301 -0.947 180)
			(size 0.7 1.2)
			(layers "F.Cu" "F.Mask" "F.Paste")
			(net 19 "/CSI/CSI_3V3")
			(pinfunction "OUT")
			(pintype "power_out")
		)
		(pad "2" smd rect
			(at -1.301 0.004 180)
			(size 0.7 1.2)
			(layers "F.Cu" "F.Mask" "F.Paste")
			(net 3 "GND")
			(pinfunction "GND")
			(pintype "power_in")
		)
		(pad "3" smd rect
			(at -1.301 0.954 180)
			(size 0.7 1.2)
			(layers "F.Cu" "F.Mask" "F.Paste")
			(net 371 "Net-(U602-FLG)")
			(pinfunction "FLG")
			(pintype "output")
		)
		(pad "4" smd rect
			(at 1.299 0.954 180)
			(size 0.7 1.2)
			(layers "F.Cu" "F.Mask" "F.Paste")
			(net 369 "/CSI/CamCtrl.EN")
			(pinfunction "EN")
			(pintype "input")
		)
		(pad "5" smd rect
			(at 1.299 0.004 180)
			(size 0.7 1.2)
			(layers "F.Cu" "F.Mask" "F.Paste")
			(net 373 "Net-(U602-ISET)")
			(pinfunction "ISET")
			(pintype "passive")
		)
		(pad "6" smd rect
			(at 1.299 -0.947 180)
			(size 0.7 1.2)
			(layers "F.Cu" "F.Mask" "F.Paste")
			(net 9 "+3V3")
			(pinfunction "IN")
			(pintype "power_in")
		)
	)
	(footprint "antmicro-footprints:R_0402_1005Metric"
		(layer "F.Cu")
		(at 132.817962 121.1915 -90)
		(descr "Resistor SMD 0402")
		(tags "resistor SMD 0402")
		(property "Reference" "R802"
			(at 6.895 -0.53 90)
			(layer "F.SilkS")
			(effects
				(font
					(size 0.7 0.7)
					(thickness 0.15)
				)
				(justify right bottom)
			)
		)
		(property "Value" "R_0R_0402"
			(at -1.011843 1.772047 90)
			(layer "F.Fab")
			(effects
				(font
					(size 0.7 0.7)
					(thickness 0.15)
				)
				(justify right bottom)
			)
		)
		(property "Datasheet" "https://industrial.panasonic.com/cdbs/www-data/pdf/RDA0000/AOA0000C301.pdf"
			(at 0 0 270)
			(layer "F.Fab")
			(hide yes)
			(effects
				(font
					(size 1.27 1.27)
					(thickness 0.15)
				)
			)
		)
		(property "MPN" "ERJ2GE0R00X"
			(at 0 0 270)
			(unlocked yes)
			(layer "F.Fab")
			(hide yes)
			(effects
				(font
					(size 1 1)
					(thickness 0.15)
				)
			)
		)
		(property "Manufacturer" "Panasonic"
			(at 0 0 270)
			(unlocked yes)
			(layer "F.Fab")
			(hide yes)
			(effects
				(font
					(size 1 1)
					(thickness 0.15)
				)
			)
		)
		(property "License" "Apache-2.0"
			(at 0 0 270)
			(unlocked yes)
			(layer "F.Fab")
			(hide yes)
			(effects
				(font
					(size 1 1)
					(thickness 0.15)
				)
			)
		)
		(property "Author" "Antmicro"
			(at 0 0 270)
			(unlocked yes)
			(layer "F.Fab")
			(hide yes)
			(effects
				(font
					(size 1 1)
					(thickness 0.15)
				)
			)
		)
		(property "Val" "0R"
			(at 0 0 270)
			(unlocked yes)
			(layer "F.Fab")
			(hide yes)
			(effects
				(font
					(size 1 1)
					(thickness 0.15)
				)
			)
		)
		(property "Tolerance" "~"
			(at 0 0 270)
			(unlocked yes)
			(layer "F.Fab")
			(hide yes)
			(effects
				(font
					(size 1 1)
					(thickness 0.15)
				)
			)
		)
		(property "Current" "1A"
			(at 0 0 270)
			(unlocked yes)
			(layer "F.Fab")
			(hide yes)
			(effects
				(font
					(size 1 1)
					(thickness 0.15)
				)
			)
		)
		(sheetname "/Peripherals/")
		(sheetfile "peripherals.kicad_sch")
		(attr smd)
		(fp_rect
			(start -0.925 -0.47)
			(end 0.925 0.47)
			(stroke
				(width 0.05)
				(type default)
			)
			(fill no)
			(layer "F.CrtYd")
		)
		(fp_rect
			(start -0.5 -0.25)
			(end 0.5 0.25)
			(stroke
				(width 0.15)
				(type solid)
			)
			(fill no)
			(layer "F.Fab")
		)
		(fp_text user "Author: Antmicro"
			(at -0.95 4.169 270)
			(layer "F.Fab")
			(effects
				(font
					(size 0.7 0.7)
					(thickness 0.15)
				)
				(justify left bottom)
			)
		)
		(fp_text user "${REFERENCE}"
			(at -0.95 3.168 270)
			(layer "F.Fab")
			(effects
				(font
					(size 0.7 0.7)
					(thickness 0.15)
				)
				(justify left bottom)
			)
		)
		(fp_text user "License: Apache-2.0"
			(at -0.95 5.169 270)
			(layer "F.Fab")
			(effects
				(font
					(size 0.7 0.7)
					(thickness 0.15)
				)
				(justify left bottom)
			)
		)
		(pad "1" smd roundrect
			(at -0.48 0 270)
			(size 0.59 0.64)
			(layers "F.Cu" "F.Mask" "F.Paste")
			(roundrect_rratio 0.25)
			(net 317 "/Peripherals/VLED")
			(pintype "passive")
		)
		(pad "2" smd roundrect
			(at 0.48 0 270)
			(size 0.59 0.64)
			(layers "F.Cu" "F.Mask" "F.Paste")
			(roundrect_rratio 0.25)
			(net 9 "+3V3")
			(pintype "passive")
		)
	)
	(footprint "antmicro-footprints:R_0402_1005Metric"
		(layer "F.Cu")
		(at 110.951464 158.0015 180)
		(descr "Resistor SMD 0402")
		(tags "resistor SMD 0402")
		(property "Reference" "R228"
			(at 1.873502 -2.425 180)
			(layer "F.SilkS")
			(effects
				(font
					(size 0.7 0.7)
					(thickness 0.15)
				)
				(justify left bottom)
			)
		)
		(property "Value" "R_0R_0402"
			(at -1.011843 1.772047 180)
			(layer "F.Fab")
			(effects
				(font
					(size 0.7 0.7)
					(thickness 0.15)
				)
				(justify left bottom)
			)
		)
		(property "Datasheet" "https://industrial.panasonic.com/cdbs/www-data/pdf/RDA0000/AOA0000C301.pdf"
			(at 0 0 180)
			(layer "F.Fab")
			(hide yes)
			(effects
				(font
					(size 1.27 1.27)
					(thickness 0.15)
				)
			)
		)
		(property "Manufacturer" "Panasonic"
			(at 0 0 180)
			(unlocked yes)
			(layer "F.Fab")
			(hide yes)
			(effects
				(font
					(size 1 1)
					(thickness 0.15)
				)
			)
		)
		(property "MPN" "ERJ2GE0R00X"
			(at 0 0 180)
			(unlocked yes)
			(layer "F.Fab")
			(hide yes)
			(effects
				(font
					(size 1 1)
					(thickness 0.15)
				)
			)
		)
		(property "Val" "0R"
			(at 0 0 180)
			(unlocked yes)
			(layer "F.Fab")
			(hide yes)
			(effects
				(font
					(size 1 1)
					(thickness 0.15)
				)
			)
		)
		(property "License" "Apache-2.0"
			(at 0 0 180)
			(unlocked yes)
			(layer "F.Fab")
			(hide yes)
			(effects
				(font
					(size 1 1)
					(thickness 0.15)
				)
			)
		)
		(property "Author" "Antmicro"
			(at 0 0 180)
			(unlocked yes)
			(layer "F.Fab")
			(hide yes)
			(effects
				(font
					(size 1 1)
					(thickness 0.15)
				)
			)
		)
		(property "Tolerance" "~"
			(at 0 0 180)
			(unlocked yes)
			(layer "F.Fab")
			(hide yes)
			(effects
				(font
					(size 1 1)
					(thickness 0.15)
				)
			)
		)
		(property "Current" "1A"
			(at 0 0 180)
			(unlocked yes)
			(layer "F.Fab")
			(hide yes)
			(effects
				(font
					(size 1 1)
					(thickness 0.15)
				)
			)
		)
		(sheetname "/Compute module/")
		(sheetfile "compute-module.kicad_sch")
		(attr smd)
		(fp_rect
			(start -0.925 -0.47)
			(end 0.925 0.47)
			(stroke
				(width 0.05)
				(type default)
			)
			(fill no)
			(layer "F.CrtYd")
		)
		(fp_rect
			(start -0.5 -0.25)
			(end 0.5 0.25)
			(stroke
				(width 0.15)
				(type solid)
			)
			(fill no)
			(layer "F.Fab")
		)
		(fp_text user "Author: Antmicro"
			(at -0.95 4.169 180)
			(layer "F.Fab")
			(effects
				(font
					(size 0.7 0.7)
					(thickness 0.15)
				)
				(justify left bottom)
			)
		)
		(fp_text user "${REFERENCE}"
			(at -0.95 3.168 180)
			(layer "F.Fab")
			(effects
				(font
					(size 0.7 0.7)
					(thickness 0.15)
				)
				(justify left bottom)
			)
		)
		(fp_text user "License: Apache-2.0"
			(at -0.95 5.169 180)
			(layer "F.Fab")
			(effects
				(font
					(size 0.7 0.7)
					(thickness 0.15)
				)
				(justify left bottom)
			)
		)
		(pad "1" smd roundrect
			(at -0.48 0 180)
			(size 0.59 0.64)
			(layers "F.Cu" "F.Mask" "F.Paste")
			(roundrect_rratio 0.25)
			(net 155 "/Compute module/T3_P")
			(pintype "passive")
		)
		(pad "2" smd roundrect
			(at 0.48 0 180)
			(size 0.59 0.64)
			(layers "F.Cu" "F.Mask" "F.Paste")
			(roundrect_rratio 0.25)
			(net 161 "/Compute module/NVMe.TX3_P")
			(pintype "passive")
		)
	)
	(footprint "antmicro-footprints:Conn_Molex_Nano-Fit_1x2_SMD_1054301202"
		(layer "F.Cu")
		(at 49.767962 116.1165 180)
		(descr "Molex Nano-Fit Power Connectors, 105430-xx02, 2 Pins per row")
		(tags "connector Molex Nano-Fit")
		(property "Reference" "J301"
			(at -4.5 -5.7 0)
			(layer "F.SilkS")
			(effects
				(font
					(size 0.7 0.7)
					(thickness 0.15)
				)
				(justify right bottom)
			)
		)
		(property "Value" "Molex_Nano-Fit_1x2_SMD_1054301202"
			(at 0 7.1 0)
			(layer "F.Fab")
			(effects
				(font
					(size 0.7 0.7)
					(thickness 0.15)
				)
				(justify right bottom)
			)
		)
		(property "Datasheet" "https://www.farnell.com/cad/3578051.pdf"
			(at 0 0 180)
			(layer "F.Fab")
			(hide yes)
			(effects
				(font
					(size 1.27 1.27)
					(thickness 0.15)
				)
			)
		)
		(property "Manufacturer" "Molex"
			(at 0 0 180)
			(unlocked yes)
			(layer "F.Fab")
			(hide yes)
			(effects
				(font
					(size 1 1)
					(thickness 0.15)
				)
			)
		)
		(property "MPN" "105430-1202"
			(at 0 0 180)
			(unlocked yes)
			(layer "F.Fab")
			(hide yes)
			(effects
				(font
					(size 1 1)
					(thickness 0.15)
				)
			)
		)
		(property "Author" "Antmicro"
			(at 0 0 180)
			(unlocked yes)
			(layer "F.Fab")
			(hide yes)
			(effects
				(font
					(size 1 1)
					(thickness 0.15)
				)
			)
		)
		(property "License" "Apache-2.0"
			(at 0 0 180)
			(unlocked yes)
			(layer "F.Fab")
			(hide yes)
			(effects
				(font
					(size 1 1)
					(thickness 0.15)
				)
			)
		)
		(sheetname "/Supply/")
		(sheetfile "supply.kicad_sch")
		(attr smd)
		(fp_line
			(start 4.48 2.298)
			(end 4.48 -4.5)
			(stroke
				(width 0.15)
				(type solid)
			)
			(layer "F.SilkS")
		)
		(fp_line
			(start 4.48 2.298)
			(end 4.28 2.698)
			(stroke
				(width 0.15)
				(type solid)
			)
			(layer "F.SilkS")
		)
		(fp_line
			(start 4.48 -4.5)
			(end 2.68 -4.5)
			(stroke
				(width 0.15)
				(type solid)
			)
			(layer "F.SilkS")
		)
		(fp_line
			(start 4.28 2.698)
			(end 4.28 4.299)
			(stroke
				(width 0.15)
				(type solid)
			)
			(layer "F.SilkS")
		)
		(fp_line
			(start -0.22 -4.5)
			(end 0.78 -4.5)
			(stroke
				(width 0.15)
				(type solid)
			)
			(layer "F.SilkS")
		)
		(fp_line
			(start -1.72 -4.5)
			(end -4.47 -4.5)
			(stroke
				(width 0.15)
				(type solid)
			)
			(layer "F.SilkS")
		)
		(fp_line
			(start -4.321 4.299)
			(end 4.28 4.299)
			(stroke
				(width 0.15)
				(type solid)
			)
			(layer "F.SilkS")
		)
		(fp_line
			(start -4.321 2.499)
			(end -4.321 4.299)
			(stroke
				(width 0.15)
				(type solid)
			)
			(layer "F.SilkS")
		)
		(fp_line
			(start -4.47 2.099)
			(end -4.321 2.499)
			(stroke
				(width 0.15)
				(type solid)
			)
			(layer "F.SilkS")
		)
		(fp_line
			(start -4.47 -4.5)
			(end -4.47 2.099)
			(stroke
				(width 0.15)
				(type solid)
			)
			(layer "F.SilkS")
		)
		(fp_circle
			(center 2.428 -4.91)
			(end 2.478 -4.91)
			(stroke
				(width 0.15)
				(type solid)
			)
			(fill yes)
			(layer "F.SilkS")
		)
		(fp_rect
			(start -4.77 -6.21)
			(end 4.77 6.11)
			(stroke
				(width 0.05)
				(type solid)
			)
			(fill no)
			(layer "F.CrtYd")
		)
		(fp_text user "${REFERENCE}"
			(at -4.77 8.11 180)
			(layer "F.Fab")
			(effects
				(font
					(size 0.7 0.7)
					(thickness 0.15)
				)
				(justify left bottom)
			)
		)
		(fp_text user "License: Apache-2.0"
			(at -4.77 10.51 180)
			(layer "F.Fab")
			(effects
				(font
					(size 0.7 0.7)
					(thickness 0.15)
				)
				(justify left bottom)
			)
		)
		(fp_text user "Author: Antmicro"
			(at -4.77 9.31 180)
			(layer "F.Fab")
			(effects
				(font
					(size 0.7 0.7)
					(thickness 0.15)
				)
				(justify left bottom)
			)
		)
		(pad "1" smd roundrect
			(at 1.528 -4.901 270)
			(size 2.5 1.24)
			(layers "F.Cu" "F.Mask" "F.Paste")
			(roundrect_rratio 0.25)
			(net 472 "Net-(D301-C)")
			(pintype "passive")
		)
		(pad "2" smd roundrect
			(at -0.97 -4.901 270)
			(size 2.5 1.24)
			(layers "F.Cu" "F.Mask" "F.Paste")
			(roundrect_rratio 0.25)
			(net 3 "GND")
			(pintype "passive")
		)
		(pad "MP" smd roundrect
			(at -3.54 0.029 180)
			(size 1.1 8.2)
			(layers "F.Cu" "F.Mask" "F.Paste")
			(roundrect_rratio 0.25)
			(net 3 "GND")
			(pintype "passive")
		)
		(pad "MP" smd roundrect
			(at 3.499 0.029 180)
			(size 1.1 8.2)
			(layers "F.Cu" "F.Mask" "F.Paste")
			(roundrect_rratio 0.25)
			(net 3 "GND")
			(pintype "passive")
		)
	)
	(footprint "antmicro-footprints:SOD-523"
		(layer "F.Cu")
		(at 88.692962 129.6665 180)
		(property "Reference" "D910"
			(at -0.695 3.68 0)
			(layer "F.SilkS")
			(effects
				(font
					(size 0.7 0.7)
					(thickness 0.15)
				)
				(justify right bottom)
			)
		)
		(property "Value" "RB521S30T1G"
			(at 0 1.499 0)
			(layer "F.Fab")
			(effects
				(font
					(size 0.7 0.7)
					(thickness 0.15)
				)
				(justify right bottom)
			)
		)
		(property "Datasheet" "https://www.onsemi.com/pdf/datasheet/rb521s30t1-d.pdf"
			(at 0 0 180)
			(layer "F.Fab")
			(hide yes)
			(effects
				(font
					(size 1.27 1.27)
					(thickness 0.15)
				)
			)
		)
		(property "MPN" "RB521S30T1G"
			(at 0 0 180)
			(unlocked yes)
			(layer "F.Fab")
			(hide yes)
			(effects
				(font
					(size 1 1)
					(thickness 0.15)
				)
			)
		)
		(property "Manufacturer" "ON Semiconductor"
			(at 0 0 180)
			(unlocked yes)
			(layer "F.Fab")
			(hide yes)
			(effects
				(font
					(size 1 1)
					(thickness 0.15)
				)
			)
		)
		(property "Author" "Antmicro"
			(at 0 0 180)
			(unlocked yes)
			(layer "F.Fab")
			(hide yes)
			(effects
				(font
					(size 1 1)
					(thickness 0.15)
				)
			)
		)
		(property "License" "Apache-2.0"
			(at 0 0 180)
			(unlocked yes)
			(layer "F.Fab")
			(hide yes)
			(effects
				(font
					(size 1 1)
					(thickness 0.15)
				)
			)
		)
		(sheetname "/USB/")
		(sheetfile "usb.kicad_sch")
		(attr smd)
		(fp_line
			(start -0.35 -0.5)
			(end -0.35 0.5)
			(stroke
				(width 0.15)
				(type solid)
			)
			(layer "F.SilkS")
		)
		(fp_rect
			(start -1 -0.6)
			(end 1 0.6)
			(stroke
				(width 0.05)
				(type solid)
			)
			(fill no)
			(layer "F.CrtYd")
		)
		(fp_line
			(start 0.65 -0.425)
			(end 0.65 0.423)
			(stroke
				(width 0.15)
				(type solid)
			)
			(layer "F.Fab")
		)
		(fp_line
			(start -0.35 -0.4)
			(end -0.35 0.4)
			(stroke
				(width 0.15)
				(type solid)
			)
			(layer "F.Fab")
		)
		(fp_line
			(start -0.652 0.423)
			(end 0.65 0.423)
			(stroke
				(width 0.15)
				(type solid)
			)
			(layer "F.Fab")
		)
		(fp_line
			(start -0.652 0.423)
			(end -0.652 -0.425)
			(stroke
				(width 0.15)
				(type solid)
			)
			(layer "F.Fab")
		)
		(fp_line
			(start -0.652 -0.425)
			(end 0.65 -0.425)
			(stroke
				(width 0.15)
				(type solid)
			)
			(layer "F.Fab")
		)
		(fp_text user "${REFERENCE}"
			(at -1.276 3.499 180)
			(layer "F.Fab")
			(effects
				(font
					(size 0.7 0.7)
					(thickness 0.15)
				)
				(justify left bottom)
			)
		)
		(fp_text user "Author: Antmicro"
			(at -1.276 4.7 180)
			(layer "F.Fab")
			(effects
				(font
					(size 0.7 0.7)
					(thickness 0.15)
				)
				(justify left bottom)
			)
		)
		(fp_text user "License: Apache-2.0"
			(at -1.276 5.9 180)
			(layer "F.Fab")
			(effects
				(font
					(size 0.7 0.7)
					(thickness 0.15)
				)
				(justify left bottom)
			)
		)
		(pad "1" smd roundrect
			(at -0.701 0 180)
			(size 0.5 0.6)
			(layers "F.Cu" "F.Mask" "F.Paste")
			(roundrect_rratio 0.25)
			(net 471 "Net-(D910-C)")
			(pinfunction "C")
			(pintype "passive")
		)
		(pad "2" smd roundrect
			(at 0.699 0 180)
			(size 0.5 0.6)
			(layers "F.Cu" "F.Mask" "F.Paste")
			(roundrect_rratio 0.25)
			(net 27 "/USB/USB_3V3")
			(pinfunction "A")
			(pintype "passive")
		)
	)
	(footprint "antmicro-footprints:R_0402_1005Metric"
		(layer "F.Cu")
		(at 76.467962 159.1665 90)
		(descr "Resistor SMD 0402")
		(tags "resistor SMD 0402")
		(property "Reference" "R244"
			(at -2.325 1.45 90)
			(layer "F.SilkS")
			(effects
				(font
					(size 0.7 0.7)
					(thickness 0.15)
				)
				(justify left bottom)
			)
		)
		(property "Value" "R_0R_0402"
			(at -1.011843 1.772047 90)
			(layer "F.Fab")
			(effects
				(font
					(size 0.7 0.7)
					(thickness 0.15)
				)
				(justify left bottom)
			)
		)
		(property "Datasheet" "https://industrial.panasonic.com/cdbs/www-data/pdf/RDA0000/AOA0000C301.pdf"
			(at 0 0 90)
			(layer "F.Fab")
			(hide yes)
			(effects
				(font
					(size 1.27 1.27)
					(thickness 0.15)
				)
			)
		)
		(property "Manufacturer" "Panasonic"
			(at 0 0 90)
			(unlocked yes)
			(layer "F.Fab")
			(hide yes)
			(effects
				(font
					(size 1 1)
					(thickness 0.15)
				)
			)
		)
		(property "MPN" "ERJ2GE0R00X"
			(at 0 0 90)
			(unlocked yes)
			(layer "F.Fab")
			(hide yes)
			(effects
				(font
					(size 1 1)
					(thickness 0.15)
				)
			)
		)
		(property "Val" "0R"
			(at 0 0 90)
			(unlocked yes)
			(layer "F.Fab")
			(hide yes)
			(effects
				(font
					(size 1 1)
					(thickness 0.15)
				)
			)
		)
		(property "License" "Apache-2.0"
			(at 0 0 90)
			(unlocked yes)
			(layer "F.Fab")
			(hide yes)
			(effects
				(font
					(size 1 1)
					(thickness 0.15)
				)
			)
		)
		(property "Author" "Antmicro"
			(at 0 0 90)
			(unlocked yes)
			(layer "F.Fab")
			(hide yes)
			(effects
				(font
					(size 1 1)
					(thickness 0.15)
				)
			)
		)
		(property "Tolerance" "~"
			(at 0 0 90)
			(unlocked yes)
			(layer "F.Fab")
			(hide yes)
			(effects
				(font
					(size 1 1)
					(thickness 0.15)
				)
			)
		)
		(property "Current" "1A"
			(at 0 0 90)
			(unlocked yes)
			(layer "F.Fab")
			(hide yes)
			(effects
				(font
					(size 1 1)
					(thickness 0.15)
				)
			)
		)
		(sheetname "/Compute module/")
		(sheetfile "compute-module.kicad_sch")
		(attr smd exclude_from_pos_files exclude_from_bom dnp)
		(fp_rect
			(start -0.925 -0.47)
			(end 0.925 0.47)
			(stroke
				(width 0.05)
				(type default)
			)
			(fill no)
			(layer "F.CrtYd")
		)
		(fp_rect
			(start -0.5 -0.25)
			(end 0.5 0.25)
			(stroke
				(width 0.15)
				(type solid)
			)
			(fill no)
			(layer "F.Fab")
		)
		(fp_text user "Author: Antmicro"
			(at -0.95 4.169 90)
			(layer "F.Fab")
			(effects
				(font
					(size 0.7 0.7)
					(thickness 0.15)
				)
				(justify left bottom)
			)
		)
		(fp_text user "${REFERENCE}"
			(at -0.95 3.168 90)
			(layer "F.Fab")
			(effects
				(font
					(size 0.7 0.7)
					(thickness 0.15)
				)
				(justify left bottom)
			)
		)
		(fp_text user "License: Apache-2.0"
			(at -0.95 5.169 90)
			(layer "F.Fab")
			(effects
				(font
					(size 0.7 0.7)
					(thickness 0.15)
				)
				(justify left bottom)
			)
		)
		(pad "1" smd roundrect
			(at -0.48 0 90)
			(size 0.59 0.64)
			(layers "F.Cu" "F.Mask" "F.Paste")
			(roundrect_rratio 0.25)
			(net 132 "/Compute module/CM4_3V3")
			(pintype "passive")
		)
		(pad "2" smd roundrect
			(at 0.48 0 90)
			(size 0.59 0.64)
			(layers "F.Cu" "F.Mask" "F.Paste")
			(roundrect_rratio 0.25)
			(net 129 "Net-(J201-Pad73)")
			(pintype "passive")
		)
	)
	(footprint "antmicro-footprints:Nexperia_DFN-10_2.5x1mm_P0.5mm"
		(layer "F.Cu")
		(at 140.092962 135.579 180)
		(property "Reference" "D810"
			(at 1.485 -0.3175 0)
			(layer "F.SilkS")
			(effects
				(font
					(size 0.7 0.7)
					(thickness 0.15)
				)
				(justify right bottom)
			)
		)
		(property "Value" "PUSB3F96X_PASS"
			(at -0.016 1.705 0)
			(layer "F.Fab")
			(effects
				(font
					(size 0.7 0.7)
					(thickness 0.15)
				)
				(justify right bottom)
			)
		)
		(property "Datasheet" "https://mouser.com/datasheet/2/916/PUSB3F96-1600324.pdf"
			(at 0 0 180)
			(layer "F.Fab")
			(hide yes)
			(effects
				(font
					(size 1.27 1.27)
					(thickness 0.15)
				)
			)
		)
		(property "Manufacturer" "Nexperia"
			(at 0 0 180)
			(unlocked yes)
			(layer "F.Fab")
			(hide yes)
			(effects
				(font
					(size 1 1)
					(thickness 0.15)
				)
			)
		)
		(property "MPN" "PUSB3F96X"
			(at 0 0 180)
			(unlocked yes)
			(layer "F.Fab")
			(hide yes)
			(effects
				(font
					(size 1 1)
					(thickness 0.15)
				)
			)
		)
		(property "Author" "Antmicro"
			(at 0 0 180)
			(unlocked yes)
			(layer "F.Fab")
			(hide yes)
			(effects
				(font
					(size 1 1)
					(thickness 0.15)
				)
			)
		)
		(property "License" "Apache-2.0"
			(at 0 0 180)
			(unlocked yes)
			(layer "F.Fab")
			(hide yes)
			(effects
				(font
					(size 1 1)
					(thickness 0.15)
				)
			)
		)
		(sheetname "/Peripherals/")
		(sheetfile "peripherals.kicad_sch")
		(attr smd)
		(fp_line
			(start 1.375 0.4)
			(end 1.375 -0.4)
			(stroke
				(width 0.15)
				(type solid)
			)
			(layer "F.SilkS")
		)
		(fp_line
			(start -1.375 -0.4)
			(end -1.375 0.4)
			(stroke
				(width 0.15)
				(type solid)
			)
			(layer "F.SilkS")
		)
		(fp_circle
			(center -1.4 0.7)
			(end -1.349 0.7)
			(stroke
				(width 0.15)
				(type solid)
			)
			(fill yes)
			(layer "F.SilkS")
		)
		(fp_rect
			(start -1.4 -0.725)
			(end 1.4 0.725)
			(stroke
				(width 0.05)
				(type solid)
			)
			(fill no)
			(layer "F.CrtYd")
		)
		(fp_line
			(start 1.25 0.5)
			(end 1.25 -0.5)
			(stroke
				(width 0.15)
				(type solid)
			)
			(layer "F.Fab")
		)
		(fp_line
			(start 1.25 -0.5)
			(end -1.25 -0.5)
			(stroke
				(width 0.15)
				(type solid)
			)
			(layer "F.Fab")
		)
		(fp_line
			(start -0.9 0.5)
			(end 1.25 0.5)
			(stroke
				(width 0.15)
				(type solid)
			)
			(layer "F.Fab")
		)
		(fp_line
			(start -1.25 0.15)
			(end -0.9 0.5)
			(stroke
				(width 0.15)
				(type solid)
			)
			(layer "F.Fab")
		)
		(fp_line
			(start -1.25 -0.5)
			(end -1.25 0.15)
			(stroke
				(width 0.15)
				(type solid)
			)
			(layer "F.Fab")
		)
		(fp_text user "Author: Antmicro"
			(at -1.367 4.905 180)
			(layer "F.Fab")
			(effects
				(font
					(size 0.7 0.7)
					(thickness 0.15)
				)
				(justify left bottom)
			)
		)
		(fp_text user "License: Apache-2.0"
			(at -1.367 6.105 180)
			(layer "F.Fab")
			(effects
				(font
					(size 0.7 0.7)
					(thickness 0.15)
				)
				(justify left bottom)
			)
		)
		(fp_text user "${REFERENCE}"
			(at -1.367 3.704 180)
			(layer "F.Fab")
			(effects
				(font
					(size 0.7 0.7)
					(thickness 0.15)
				)
				(justify left bottom)
			)
		)
		(pad "1" smd rect
			(at -1 0.3875 180)
			(size 0.2 0.475)
			(layers "F.Cu" "F.Mask" "F.Paste")
			(net 224 "/Compute module/GPIO.12{slash}RXD5")
			(pinfunction "CH1")
			(pintype "passive")
			(solder_mask_margin 0.05)
		)
		(pad "2" smd rect
			(at -0.5 0.3875 180)
			(size 0.2 0.475)
			(layers "F.Cu" "F.Mask" "F.Paste")
			(net 222 "/Compute module/GPIO.16")
			(pinfunction "CH2")
			(pintype "passive")
			(solder_mask_margin 0.05)
		)
		(pad "3" smd rect
			(at 0 0.3875 180)
			(size 0.2 0.475)
			(layers "F.Cu" "F.Mask" "F.Paste")
			(net 3 "GND")
			(pinfunction "GND")
			(pintype "passive")
			(solder_mask_margin 0.05)
		)
		(pad "4" smd rect
			(at 0.5 0.3875 180)
			(size 0.2 0.475)
			(layers "F.Cu" "F.Mask" "F.Paste")
			(net 220 "/Compute module/GPIO.20")
			(pinfunction "CH3")
			(pintype "passive")
			(solder_mask_margin 0.05)
		)
		(pad "5" smd rect
			(at 1 0.3875 180)
			(size 0.2 0.475)
			(layers "F.Cu" "F.Mask" "F.Paste")
			(net 218 "/Compute module/GPIO.21")
			(pinfunction "CH4")
			(pintype "passive")
			(solder_mask_margin 0.05)
		)
		(pad "6" smd rect
			(at 1 -0.3875 180)
			(size 0.2 0.475)
			(layers "F.Cu" "F.Mask" "F.Paste")
			(net 218 "/Compute module/GPIO.21")
			(pinfunction "CH4")
			(pintype "passive")
			(solder_mask_margin 0.05)
		)
		(pad "7" smd rect
			(at 0.5 -0.3875 180)
			(size 0.2 0.475)
			(layers "F.Cu" "F.Mask" "F.Paste")
			(net 220 "/Compute module/GPIO.20")
			(pinfunction "CH3")
			(pintype "passive")
			(solder_mask_margin 0.05)
		)
		(pad "8" smd rect
			(at 0 -0.3875 180)
			(size 0.2 0.475)
			(layers "F.Cu" "F.Mask" "F.Paste")
			(net 3 "GND")
			(pinfunction "GND")
			(pintype "passive")
			(solder_mask_margin 0.05)
		)
		(pad "9" smd rect
			(at -0.501 -0.3875 180)
			(size 0.2 0.475)
			(layers "F.Cu" "F.Mask" "F.Paste")
			(net 222 "/Compute module/GPIO.16")
			(pinfunction "CH2")
			(pintype "passive")
			(solder_mask_margin 0.05)
		)
		(pad "10" smd rect
			(at -1 -0.3875 180)
			(size 0.2 0.475)
			(layers "F.Cu" "F.Mask" "F.Paste")
			(net 224 "/Compute module/GPIO.12{slash}RXD5")
			(pinfunction "CH1")
			(pintype "passive")
			(solder_mask_margin 0.05)
		)
	)
	(footprint "antmicro-footprints:RJ45_X-2337992-8_Horizontal"
		(layer "F.Cu")
		(at 70.483512 131.631 180)
		(property "Reference" "J401"
			(at 8.783512 -2.919 180)
			(layer "F.SilkS")
			(effects
				(font
					(size 0.7 0.7)
					(thickness 0.15)
				)
				(justify left bottom)
			)
		)
		(property "Value" "Bus_RJ45_5-2337992-8"
			(at -2.6 22 180)
			(layer "F.Fab")
			(effects
				(font
					(size 0.7 0.7)
					(thickness 0.15)
				)
				(justify left bottom)
			)
		)
		(property "Datasheet" "https://www.te.com/commerce/DocumentDelivery/DDEController?Action=showdoc&DocId=Customer+Drawing%7F5-2337992-8%7FA%7Fpdf%7FEnglish%7FENG_CD_5-2337992-8_A.pdf%7F5-2337992-8"
			(at 0 0 180)
			(layer "F.Fab")
			(hide yes)
			(effects
				(font
					(size 1.27 1.27)
					(thickness 0.15)
				)
			)
		)
		(property "MPN" "5-2337992-8"
			(at 0 0 180)
			(unlocked yes)
			(layer "F.Fab")
			(hide yes)
			(effects
				(font
					(size 1 1)
					(thickness 0.15)
				)
			)
		)
		(property "Manufacturer" "TE Connectivity"
			(at 0 0 180)
			(unlocked yes)
			(layer "F.Fab")
			(hide yes)
			(effects
				(font
					(size 1 1)
					(thickness 0.15)
				)
			)
		)
		(property "Author" "Antmicro"
			(at 0 0 180)
			(unlocked yes)
			(layer "F.Fab")
			(hide yes)
			(effects
				(font
					(size 1 1)
					(thickness 0.15)
				)
			)
		)
		(property "License" "Apache-2.0"
			(at 0 0 180)
			(unlocked yes)
			(layer "F.Fab")
			(hide yes)
			(effects
				(font
					(size 1 1)
					(thickness 0.15)
				)
			)
		)
		(property ki_fp_filters "CONN18_5-2337992-8_TEC")
		(sheetname "/Ethernet/")
		(sheetfile "ethernet.kicad_sch")
		(attr through_hole)
		(fp_line
			(start 13.791 19.771)
			(end 13.791 7.217)
			(stroke
				(width 0.15)
				(type solid)
			)
			(layer "F.SilkS")
		)
		(fp_line
			(start 13.791 4.48)
			(end 13.791 -1.845)
			(stroke
				(width 0.15)
				(type solid)
			)
			(layer "F.SilkS")
		)
		(fp_line
			(start 13.791 -1.845)
			(end -2.363 -1.845)
			(stroke
				(width 0.15)
				(type solid)
			)
			(layer "F.SilkS")
		)
		(fp_line
			(start -2.363 19.771)
			(end 13.791 19.771)
			(stroke
				(width 0.15)
				(type solid)
			)
			(layer "F.SilkS")
		)
		(fp_line
			(start -2.363 7.217)
			(end -2.363 19.771)
			(stroke
				(width 0.15)
				(type solid)
			)
			(layer "F.SilkS")
		)
		(fp_line
			(start -2.363 -1.845)
			(end -2.363 4.48)
			(stroke
				(width 0.15)
				(type solid)
			)
			(layer "F.SilkS")
		)
		(fp_rect
			(start -2.4 -1.8)
			(end 13.9 19.999)
			(stroke
				(width 0.05)
				(type solid)
			)
			(fill no)
			(layer "F.CrtYd")
		)
		(fp_line
			(start 13.665 19.644)
			(end 13.665 -1.718)
			(stroke
				(width 0.15)
				(type solid)
			)
			(layer "F.Fab")
		)
		(fp_line
			(start 13.665 -1.718)
			(end -2.237 -1.718)
			(stroke
				(width 0.15)
				(type solid)
			)
			(layer "F.Fab")
		)
		(fp_line
			(start -2.237 19.644)
			(end 13.665 19.644)
			(stroke
				(width 0.15)
				(type solid)
			)
			(layer "F.Fab")
		)
		(fp_line
			(start -2.237 -1.718)
			(end -2.237 19.644)
			(stroke
				(width 0.15)
				(type solid)
			)
			(layer "F.Fab")
		)
		(fp_text user "${REFERENCE}"
			(at -2.644 23.4 180)
			(layer "F.Fab")
			(effects
				(font
					(size 0.7 0.7)
					(thickness 0.15)
				)
				(justify left bottom)
			)
		)
		(fp_text user "Author: Antmicro"
			(at -2.644 24.8 180)
			(layer "F.Fab")
			(effects
				(font
					(size 0.7 0.7)
					(thickness 0.15)
				)
				(justify left bottom)
			)
		)
		(fp_text user "License: Apache-2.0"
			(at -2.644 26.2 180)
			(layer "F.Fab")
			(effects
				(font
					(size 0.7 0.7)
					(thickness 0.15)
				)
				(justify left bottom)
			)
		)
		(pad "" np_thru_hole circle
			(at 0 8.9 180)
			(size 3.25 3.25)
			(drill 3.25)
			(layers "*.Cu" "*.Mask")
		)
		(pad "" np_thru_hole circle
			(at 11.429 8.9 180)
			(size 3.25 3.25)
			(drill 3.25)
			(layers "*.Cu" "*.Mask")
		)
		(pad "1" thru_hole circle
			(at 0 0 180)
			(size 1.397 1.397)
			(drill 0.889)
			(layers "*.Cu" "*.Mask")
			(remove_unused_layers no)
			(net 88 "/Compute module/ETHERNET.D0_P")
			(pinfunction "P1")
			(pintype "bidirectional")
		)
		(pad "2" thru_hole circle
			(at 1.269 2.539 180)
			(size 1.397 1.397)
			(drill 0.889)
			(layers "*.Cu" "*.Mask")
			(remove_unused_layers no)
			(net 84 "/Compute module/ETHERNET.D0_N")
			(pinfunction "P2")
			(pintype "bidirectional")
		)
		(pad "3" thru_hole circle
			(at 2.539 0 180)
			(size 1.397 1.397)
			(drill 0.889)
			(layers "*.Cu" "*.Mask")
			(remove_unused_layers no)
			(net 80 "/Compute module/ETHERNET.D1_P")
			(pinfunction "P3")
			(pintype "bidirectional")
		)
		(pad "4" thru_hole circle
			(at 3.809 2.539 180)
			(size 1.397 1.397)
			(drill 0.889)
			(layers "*.Cu" "*.Mask")
			(remove_unused_layers no)
			(net 91 "Net-(J401-P4)")
			(pinfunction "P4")
			(pintype "bidirectional")
		)
		(pad "5" thru_hole circle
			(at 5.078 0 180)
			(size 1.397 1.397)
			(drill 0.889)
			(layers "*.Cu" "*.Mask")
			(remove_unused_layers no)
			(net 91 "Net-(J401-P4)")
			(pinfunction "P5")
			(pintype "bidirectional")
		)
		(pad "6" thru_hole circle
			(at 6.349 2.539 180)
			(size 1.397 1.397)
			(drill 0.889)
			(layers "*.Cu" "*.Mask")
			(remove_unused_layers no)
			(net 82 "/Compute module/ETHERNET.D1_N")
			(pinfunction "P6")
			(pintype "bidirectional")
		)
		(pad "7" thru_hole circle
			(at 7.618 0 180)
			(size 1.397 1.397)
			(drill 0.889)
			(layers "*.Cu" "*.Mask")
			(remove_unused_layers no)
			(net 85 "/Compute module/ETHERNET.D2_P")
			(pinfunction "P7")
			(pintype "bidirectional")
		)
		(pad "8" thru_hole circle
			(at 8.89 2.539 180)
			(size 1.397 1.397)
			(drill 0.889)
			(layers "*.Cu" "*.Mask")
			(remove_unused_layers no)
			(net 83 "/Compute module/ETHERNET.D2_N")
			(pinfunction "P8")
			(pintype "bidirectional")
		)
		(pad "9" thru_hole circle
			(at 10.159 0 180)
			(size 1.397 1.397)
			(drill 0.889)
			(layers "*.Cu" "*.Mask")
			(remove_unused_layers no)
			(net 79 "/Compute module/ETHERNET.D3_P")
			(pinfunction "P9")
			(pintype "bidirectional")
		)
		(pad "10" thru_hole circle
			(at 11.429 2.539 180)
			(size 1.397 1.397)
			(drill 0.889)
			(layers "*.Cu" "*.Mask")
			(remove_unused_layers no)
			(net 81 "/Compute module/ETHERNET.D3_N")
			(pinfunction "P10")
			(pintype "bidirectional")
		)
		(pad "11" thru_hole circle
			(at 0 5.078 180)
			(size 1.397 1.397)
			(drill 0.889)
			(layers "*.Cu" "*.Mask")
			(remove_unused_layers no)
			(net 61 "/Ethernet/PAIR_12")
			(pinfunction "VC1")
			(pintype "bidirectional")
		)
		(pad "12" thru_hole circle
			(at 2.539 6.339 180)
			(size 1.397 1.397)
			(drill 0.889)
			(layers "*.Cu" "*.Mask")
			(remove_unused_layers no)
			(net 62 "/Ethernet/PAIR_36")
			(pinfunction "VC2")
			(pintype "bidirectional")
		)
		(pad "13" thru_hole circle
			(at 8.89 6.339 180)
			(size 1.397 1.397)
			(drill 0.889)
			(layers "*.Cu" "*.Mask")
			(remove_unused_layers no)
			(net 64 "/Ethernet/PAIR_78")
			(pinfunction "VC3")
			(pintype "bidirectional")
		)
		(pad "14" thru_hole circle
			(at 11.429 5.07 180)
			(size 1.397 1.397)
			(drill 0.889)
			(layers "*.Cu" "*.Mask")
			(remove_unused_layers no)
			(net 63 "/Ethernet/PAIR_910")
			(pinfunction "VC4")
			(pintype "bidirectional")
		)
		(pad "15" thru_hole circle
			(at -0.927 12.958 180)
			(size 1.524 1.524)
			(drill 1.016)
			(layers "*.Cu" "*.Mask")
			(remove_unused_layers no)
			(net 9 "+3V3")
			(pinfunction "LED_GRN+")
			(pintype "passive")
		)
		(pad "16" thru_hole circle
			(at 1.614 12.958 180)
			(size 1.524 1.524)
			(drill 1.016)
			(layers "*.Cu" "*.Mask")
			(remove_unused_layers no)
			(net 176 "Net-(J401-LED_GRN-)")
			(pinfunction "LED_GRN-")
			(pintype "passive")
		)
		(pad "17" thru_hole circle
			(at 9.814 12.958 180)
			(size 1.524 1.524)
			(drill 1.016)
			(layers "*.Cu" "*.Mask")
			(remove_unused_layers no)
			(net 9 "+3V3")
			(pinfunction "LED_YEL+")
			(pintype "passive")
		)
		(pad "18" thru_hole circle
			(at 12.355 12.958 180)
			(size 1.524 1.524)
			(drill 1.016)
			(layers "*.Cu" "*.Mask")
			(remove_unused_layers no)
			(net 175 "Net-(J401-LED_YEL-)")
			(pinfunction "LED_YEL-")
			(pintype "passive")
		)
		(pad "19" thru_hole circle
			(at -2.136 5.85 180)
			(size 2.1 2.1)
			(drill 1.6)
			(layers "*.Cu" "*.Mask")
			(remove_unused_layers no)
			(net 92 "Net-(C403-Pad1)")
			(pinfunction "SHIELD")
			(pintype "passive")
		)
		(pad "20" thru_hole circle
			(at 13.563 5.85 180)
			(size 2.1082 2.1082)
			(drill 1.6002)
			(layers "*.Cu" "*.Mask")
			(remove_unused_layers no)
			(net 92 "Net-(C403-Pad1)")
			(pinfunction "SHIELD")
			(pintype "passive")
		)
	)
	(footprint "antmicro-footprints:Nexperia_DFN-10_2.5x1mm_P0.5mm"
		(layer "F.Cu")
		(at 109.112462 125.3415)
		(property "Reference" "D707"
			(at -1.3195 1.65 0)
			(layer "F.SilkS")
			(effects
				(font
					(size 0.7 0.7)
					(thickness 0.15)
				)
				(justify left bottom)
			)
		)
		(property "Value" "PUSB3F96X_PASS"
			(at -0.016 1.705 0)
			(layer "F.Fab")
			(effects
				(font
					(size 0.7 0.7)
					(thickness 0.15)
				)
				(justify left bottom)
			)
		)
		(property "Datasheet" "https://mouser.com/datasheet/2/916/PUSB3F96-1600324.pdf"
			(at 0 0 0)
			(layer "F.Fab")
			(hide yes)
			(effects
				(font
					(size 1.27 1.27)
					(thickness 0.15)
				)
			)
		)
		(property "Manufacturer" "Nexperia"
			(at 0 0 0)
			(unlocked yes)
			(layer "F.Fab")
			(hide yes)
			(effects
				(font
					(size 1 1)
					(thickness 0.15)
				)
			)
		)
		(property "MPN" "PUSB3F96X"
			(at 0 0 0)
			(unlocked yes)
			(layer "F.Fab")
			(hide yes)
			(effects
				(font
					(size 1 1)
					(thickness 0.15)
				)
			)
		)
		(property "Author" "Antmicro"
			(at 0 0 0)
			(unlocked yes)
			(layer "F.Fab")
			(hide yes)
			(effects
				(font
					(size 1 1)
					(thickness 0.15)
				)
			)
		)
		(property "License" "Apache-2.0"
			(at 0 0 0)
			(unlocked yes)
			(layer "F.Fab")
			(hide yes)
			(effects
				(font
					(size 1 1)
					(thickness 0.15)
				)
			)
		)
		(sheetname "/Display/")
		(sheetfile "display.kicad_sch")
		(attr smd)
		(fp_line
			(start -1.375 -0.4)
			(end -1.375 0.4)
			(stroke
				(width 0.15)
				(type solid)
			)
			(layer "F.SilkS")
		)
		(fp_line
			(start 1.375 0.4)
			(end 1.375 -0.4)
			(stroke
				(width 0.15)
				(type solid)
			)
			(layer "F.SilkS")
		)
		(fp_circle
			(center -1.4 0.7)
			(end -1.349 0.7)
			(stroke
				(width 0.15)
				(type solid)
			)
			(fill yes)
			(layer "F.SilkS")
		)
		(fp_rect
			(start -1.4 -0.725)
			(end 1.4 0.725)
			(stroke
				(width 0.05)
				(type solid)
			)
			(fill no)
			(layer "F.CrtYd")
		)
		(fp_line
			(start -1.25 -0.5)
			(end -1.25 0.15)
			(stroke
				(width 0.15)
				(type solid)
			)
			(layer "F.Fab")
		)
		(fp_line
			(start -1.25 0.15)
			(end -0.9 0.5)
			(stroke
				(width 0.15)
				(type solid)
			)
			(layer "F.Fab")
		)
		(fp_line
			(start -0.9 0.5)
			(end 1.25 0.5)
			(stroke
				(width 0.15)
				(type solid)
			)
			(layer "F.Fab")
		)
		(fp_line
			(start 1.25 -0.5)
			(end -1.25 -0.5)
			(stroke
				(width 0.15)
				(type solid)
			)
			(layer "F.Fab")
		)
		(fp_line
			(start 1.25 0.5)
			(end 1.25 -0.5)
			(stroke
				(width 0.15)
				(type solid)
			)
			(layer "F.Fab")
		)
		(fp_text user "${REFERENCE}"
			(at -1.367 3.704 0)
			(layer "F.Fab")
			(effects
				(font
					(size 0.7 0.7)
					(thickness 0.15)
				)
				(justify left bottom)
			)
		)
		(fp_text user "Author: Antmicro"
			(at -1.367 4.905 0)
			(layer "F.Fab")
			(effects
				(font
					(size 0.7 0.7)
					(thickness 0.15)
				)
				(justify left bottom)
			)
		)
		(fp_text user "License: Apache-2.0"
			(at -1.367 6.105 0)
			(layer "F.Fab")
			(effects
				(font
					(size 0.7 0.7)
					(thickness 0.15)
				)
				(justify left bottom)
			)
		)
		(pad "1" smd rect
			(at -1 0.3875)
			(size 0.2 0.475)
			(layers "F.Cu" "F.Mask" "F.Paste")
			(net 35 "/Compute module/HDMI.D0_P")
			(pinfunction "CH1")
			(pintype "passive")
			(solder_mask_margin 0.05)
		)
		(pad "2" smd rect
			(at -0.5 0.3875)
			(size 0.2 0.475)
			(layers "F.Cu" "F.Mask" "F.Paste")
			(net 34 "/Compute module/HDMI.D0_N")
			(pinfunction "CH2")
			(pintype "passive")
			(solder_mask_margin 0.05)
		)
		(pad "3" smd rect
			(at 0 0.3875)
			(size 0.2 0.475)
			(layers "F.Cu" "F.Mask" "F.Paste")
			(net 3 "GND")
			(pinfunction "GND")
			(pintype "passive")
			(solder_mask_margin 0.05)
		)
		(pad "4" smd rect
			(at 0.5 0.3875)
			(size 0.2 0.475)
			(layers "F.Cu" "F.Mask" "F.Paste")
			(net 25 "/Compute module/HDMI.CLK_P")
			(pinfunction "CH3")
			(pintype "passive")
			(solder_mask_margin 0.05)
		)
		(pad "5" smd rect
			(at 1 0.3875)
			(size 0.2 0.475)
			(layers "F.Cu" "F.Mask" "F.Paste")
			(net 23 "/Compute module/HDMI.CLK_N")
			(pinfunction "CH4")
			(pintype "passive")
			(solder_mask_margin 0.05)
		)
		(pad "6" smd rect
			(at 1 -0.3875)
			(size 0.2 0.475)
			(layers "F.Cu" "F.Mask" "F.Paste")
			(net 23 "/Compute module/HDMI.CLK_N")
			(pinfunction "CH4")
			(pintype "passive")
			(solder_mask_margin 0.05)
		)
		(pad "7" smd rect
			(at 0.5 -0.3875)
			(size 0.2 0.475)
			(layers "F.Cu" "F.Mask" "F.Paste")
			(net 25 "/Compute module/HDMI.CLK_P")
			(pinfunction "CH3")
			(pintype "passive")
			(solder_mask_margin 0.05)
		)
		(pad "8" smd rect
			(at 0 -0.3875)
			(size 0.2 0.475)
			(layers "F.Cu" "F.Mask" "F.Paste")
			(net 3 "GND")
			(pinfunction "GND")
			(pintype "passive")
			(solder_mask_margin 0.05)
		)
		(pad "9" smd rect
			(at -0.501 -0.3875)
			(size 0.2 0.475)
			(layers "F.Cu" "F.Mask" "F.Paste")
			(net 34 "/Compute module/HDMI.D0_N")
			(pinfunction "CH2")
			(pintype "passive")
			(solder_mask_margin 0.05)
		)
		(pad "10" smd rect
			(at -1 -0.3875)
			(size 0.2 0.475)
			(layers "F.Cu" "F.Mask" "F.Paste")
			(net 35 "/Compute module/HDMI.D0_P")
			(pinfunction "CH1")
			(pintype "passive")
			(solder_mask_margin 0.05)
		)
	)
	(footprint "antmicro-footprints:C_0402_1005Metric"
		(layer "F.Cu")
		(at 86.167962 145.0165)
		(descr "Capacitor SMD 0402")
		(tags "capacitor SMD 0402")
		(property "Reference" "C934"
			(at -3.55 -0.15 0)
			(layer "F.SilkS")
			(effects
				(font
					(size 0.7 0.7)
					(thickness 0.15)
				)
				(justify left bottom)
			)
		)
		(property "Value" "C_100n_0402"
			(at -1.022927 2.155213 0)
			(layer "F.Fab")
			(effects
				(font
					(size 0.7 0.7)
					(thickness 0.15)
				)
				(justify left bottom)
			)
		)
		(property "Datasheet" "https://www.murata.com/products/productdetail?partno=GRM155R61H104KE14%23"
			(at 0 0 0)
			(layer "F.Fab")
			(hide yes)
			(effects
				(font
					(size 1.27 1.27)
					(thickness 0.15)
				)
			)
		)
		(property "MPN" "GRM155R61H104KE14D"
			(at 0 0 0)
			(unlocked yes)
			(layer "F.Fab")
			(hide yes)
			(effects
				(font
					(size 1 1)
					(thickness 0.15)
				)
			)
		)
		(property "Manufacturer" "Murata"
			(at 0 0 0)
			(unlocked yes)
			(layer "F.Fab")
			(hide yes)
			(effects
				(font
					(size 1 1)
					(thickness 0.15)
				)
			)
		)
		(property "License" "Apache-2.0"
			(at 0 0 0)
			(unlocked yes)
			(layer "F.Fab")
			(hide yes)
			(effects
				(font
					(size 1 1)
					(thickness 0.15)
				)
			)
		)
		(property "Author" "Antmicro"
			(at 0 0 0)
			(unlocked yes)
			(layer "F.Fab")
			(hide yes)
			(effects
				(font
					(size 1 1)
					(thickness 0.15)
				)
			)
		)
		(property "Val" "100n"
			(at 0 0 0)
			(unlocked yes)
			(layer "F.Fab")
			(hide yes)
			(effects
				(font
					(size 1 1)
					(thickness 0.15)
				)
			)
		)
		(property "Voltage" "50V"
			(at 0 0 0)
			(unlocked yes)
			(layer "F.Fab")
			(hide yes)
			(effects
				(font
					(size 1 1)
					(thickness 0.15)
				)
			)
		)
		(property "Dielectric" "X5R"
			(at 0 0 0)
			(unlocked yes)
			(layer "F.Fab")
			(hide yes)
			(effects
				(font
					(size 1 1)
					(thickness 0.15)
				)
			)
		)
		(sheetname "/USB/")
		(sheetfile "usb.kicad_sch")
		(attr smd)
		(fp_rect
			(start -0.925 -0.47)
			(end 0.925 0.47)
			(stroke
				(width 0.05)
				(type default)
			)
			(fill no)
			(layer "F.CrtYd")
		)
		(fp_line
			(start -0.494 -0.25)
			(end 0.504 -0.25)
			(stroke
				(width 0.15)
				(type solid)
			)
			(layer "F.Fab")
		)
		(fp_line
			(start -0.494 0.248)
			(end -0.494 -0.25)
			(stroke
				(width 0.15)
				(type solid)
			)
			(layer "F.Fab")
		)
		(fp_line
			(start 0.504 -0.25)
			(end 0.504 0.248)
			(stroke
				(width 0.15)
				(type solid)
			)
			(layer "F.Fab")
		)
		(fp_line
			(start 0.504 0.248)
			(end -0.494 0.248)
			(stroke
				(width 0.15)
				(type solid)
			)
			(layer "F.Fab")
		)
		(fp_text user "${REFERENCE}"
			(at -0.939 4.599 0)
			(layer "F.Fab")
			(effects
				(font
					(size 0.7 0.7)
					(thickness 0.15)
				)
				(justify left bottom)
			)
		)
		(fp_text user "License: Apache-2.0"
			(at -0.939 5.799 0)
			(layer "F.Fab")
			(effects
				(font
					(size 0.7 0.7)
					(thickness 0.15)
				)
				(justify left bottom)
			)
		)
		(fp_text user "Author: Antmicro"
			(at -0.939 3.399 0)
			(layer "F.Fab")
			(effects
				(font
					(size 0.7 0.7)
					(thickness 0.15)
				)
				(justify left bottom)
			)
		)
		(pad "1" smd roundrect
			(at -0.48 0)
			(size 0.59 0.64)
			(layers "F.Cu" "F.Mask" "F.Paste")
			(roundrect_rratio 0.25)
			(net 3 "GND")
			(pintype "passive")
		)
		(pad "2" smd roundrect
			(at 0.48 0)
			(size 0.59 0.64)
			(layers "F.Cu" "F.Mask" "F.Paste")
			(roundrect_rratio 0.25)
			(net 27 "/USB/USB_3V3")
			(pintype "passive")
		)
	)
	(footprint "antmicro-footprints:C_0402_1005Metric"
		(layer "F.Cu")
		(at 100.242962 128.4165)
		(descr "Capacitor SMD 0402")
		(tags "capacitor SMD 0402")
		(property "Reference" "C930"
			(at -0.715 -0.02 90)
			(layer "F.SilkS")
			(effects
				(font
					(size 0.7 0.7)
					(thickness 0.15)
				)
				(justify left bottom)
			)
		)
		(property "Value" "C_100n_0402"
			(at -1.022927 2.155213 0)
			(layer "F.Fab")
			(effects
				(font
					(size 0.7 0.7)
					(thickness 0.15)
				)
				(justify left bottom)
			)
		)
		(property "Datasheet" "https://www.murata.com/products/productdetail?partno=GRM155R61H104KE14%23"
			(at 0 0 0)
			(layer "F.Fab")
			(hide yes)
			(effects
				(font
					(size 1.27 1.27)
					(thickness 0.15)
				)
			)
		)
		(property "Manufacturer" "Murata"
			(at 0 0 0)
			(unlocked yes)
			(layer "F.Fab")
			(hide yes)
			(effects
				(font
					(size 1 1)
					(thickness 0.15)
				)
			)
		)
		(property "MPN" "GRM155R61H104KE14D"
			(at 0 0 0)
			(unlocked yes)
			(layer "F.Fab")
			(hide yes)
			(effects
				(font
					(size 1 1)
					(thickness 0.15)
				)
			)
		)
		(property "Val" "100n"
			(at 0 0 0)
			(unlocked yes)
			(layer "F.Fab")
			(hide yes)
			(effects
				(font
					(size 1 1)
					(thickness 0.15)
				)
			)
		)
		(property "License" "Apache-2.0"
			(at 0 0 0)
			(unlocked yes)
			(layer "F.Fab")
			(hide yes)
			(effects
				(font
					(size 1 1)
					(thickness 0.15)
				)
			)
		)
		(property "Author" "Antmicro"
			(at 0 0 0)
			(unlocked yes)
			(layer "F.Fab")
			(hide yes)
			(effects
				(font
					(size 1 1)
					(thickness 0.15)
				)
			)
		)
		(property "Voltage" "50V"
			(at 0 0 0)
			(unlocked yes)
			(layer "F.Fab")
			(hide yes)
			(effects
				(font
					(size 1 1)
					(thickness 0.15)
				)
			)
		)
		(property "Dielectric" "X5R"
			(at 0 0 0)
			(unlocked yes)
			(layer "F.Fab")
			(hide yes)
			(effects
				(font
					(size 1 1)
					(thickness 0.15)
				)
			)
		)
		(sheetname "/USB/")
		(sheetfile "usb.kicad_sch")
		(attr smd)
		(fp_rect
			(start -0.925 -0.47)
			(end 0.925 0.47)
			(stroke
				(width 0.05)
				(type default)
			)
			(fill no)
			(layer "F.CrtYd")
		)
		(fp_line
			(start -0.494 -0.25)
			(end 0.504 -0.25)
			(stroke
				(width 0.15)
				(type solid)
			)
			(layer "F.Fab")
		)
		(fp_line
			(start -0.494 0.248)
			(end -0.494 -0.25)
			(stroke
				(width 0.15)
				(type solid)
			)
			(layer "F.Fab")
		)
		(fp_line
			(start 0.504 -0.25)
			(end 0.504 0.248)
			(stroke
				(width 0.15)
				(type solid)
			)
			(layer "F.Fab")
		)
		(fp_line
			(start 0.504 0.248)
			(end -0.494 0.248)
			(stroke
				(width 0.15)
				(type solid)
			)
			(layer "F.Fab")
		)
		(fp_text user "${REFERENCE}"
			(at -0.939 4.599 0)
			(layer "F.Fab")
			(effects
				(font
					(size 0.7 0.7)
					(thickness 0.15)
				)
				(justify left bottom)
			)
		)
		(fp_text user "License: Apache-2.0"
			(at -0.939 5.799 0)
			(layer "F.Fab")
			(effects
				(font
					(size 0.7 0.7)
					(thickness 0.15)
				)
				(justify left bottom)
			)
		)
		(fp_text user "Author: Antmicro"
			(at -0.939 3.399 0)
			(layer "F.Fab")
			(effects
				(font
					(size 0.7 0.7)
					(thickness 0.15)
				)
				(justify left bottom)
			)
		)
		(pad "1" smd roundrect
			(at -0.48 0)
			(size 0.59 0.64)
			(layers "F.Cu" "F.Mask" "F.Paste")
			(roundrect_rratio 0.25)
			(net 127 "Net-(Q903-G)")
			(pintype "passive")
		)
		(pad "2" smd roundrect
			(at 0.48 0)
			(size 0.59 0.64)
			(layers "F.Cu" "F.Mask" "F.Paste")
			(roundrect_rratio 0.25)
			(net 28 "/USB/+5V_{CAP}")
			(pintype "passive")
		)
	)
	(footprint "antmicro-footprints:TP_SMD_0.75mm"
		(layer "F.Cu")
		(at 76.967962 166.1415 180)
		(property "Reference" "TP201"
			(at 9.115 0.96 0)
			(layer "F.SilkS")
			(effects
				(font
					(size 0.7 0.7)
					(thickness 0.15)
				)
				(justify right bottom)
			)
		)
		(property "Value" "TP_0.75mm_SMD"
			(at 0 1.2 0)
			(layer "F.Fab")
			(effects
				(font
					(size 0.7 0.7)
					(thickness 0.15)
				)
				(justify right bottom)
			)
		)
		(property "Author" "Antmicro"
			(at 0 0 180)
			(unlocked yes)
			(layer "F.Fab")
			(hide yes)
			(effects
				(font
					(size 1 1)
					(thickness 0.15)
				)
			)
		)
		(property "License" "Apache-2.0"
			(at 0 0 180)
			(unlocked yes)
			(layer "F.Fab")
			(hide yes)
			(effects
				(font
					(size 1 1)
					(thickness 0.15)
				)
			)
		)
		(property "MPN" ""
			(at 0 0 180)
			(unlocked yes)
			(layer "F.Fab")
			(hide yes)
			(effects
				(font
					(size 1 1)
					(thickness 0.15)
				)
			)
		)
		(property "Manufacturer" ""
			(at 0 0 180)
			(unlocked yes)
			(layer "F.Fab")
			(hide yes)
			(effects
				(font
					(size 1 1)
					(thickness 0.15)
				)
			)
		)
		(sheetname "/Compute module/")
		(sheetfile "compute-module.kicad_sch")
		(attr exclude_from_pos_files exclude_from_bom)
		(fp_circle
			(center 0 0)
			(end 0.475 0)
			(stroke
				(width 0.05)
				(type default)
			)
			(fill no)
			(layer "F.CrtYd")
		)
		(fp_text user "Author: Antmicro"
			(at -0.4 3.901 180)
			(layer "F.Fab")
			(effects
				(font
					(size 0.7 0.7)
					(thickness 0.15)
				)
				(justify left bottom)
			)
		)
		(fp_text user "${REFERENCE}"
			(at -0.4 2.7 180)
			(layer "F.Fab")
			(effects
				(font
					(size 0.7 0.7)
					(thickness 0.15)
				)
				(justify left bottom)
			)
		)
		(fp_text user "License: Apache-2.0"
			(at -0.4 5.101 180)
			(layer "F.Fab")
			(effects
				(font
					(size 0.7 0.7)
					(thickness 0.15)
				)
				(justify left bottom)
			)
		)
		(pad "1" smd circle
			(at 0 0 180)
			(size 0.75 0.75)
			(layers "F.Cu" "F.Mask")
			(net 249 "/Compute module/RUN_PG")
			(pinfunction "1")
			(pintype "passive")
		)
	)
	(footprint "antmicro-footprints:R_0402_1005Metric"
		(layer "F.Cu")
		(at 80.017962 168.2415 180)
		(descr "Resistor SMD 0402")
		(tags "resistor SMD 0402")
		(property "Reference" "R215"
			(at -1.34 0.395 0)
			(layer "F.SilkS")
			(effects
				(font
					(size 0.7 0.7)
					(thickness 0.15)
				)
				(justify right bottom)
			)
		)
		(property "Value" "R_2k2_0402"
			(at -1.011843 1.772047 0)
			(layer "F.Fab")
			(effects
				(font
					(size 0.7 0.7)
					(thickness 0.15)
				)
				(justify right bottom)
			)
		)
		(property "Datasheet" "https://www.bourns.com/docs/product-datasheets/cr.pdf"
			(at 0 0 180)
			(layer "F.Fab")
			(hide yes)
			(effects
				(font
					(size 1.27 1.27)
					(thickness 0.15)
				)
			)
		)
		(property "Manufacturer" "Bourns"
			(at 0 0 180)
			(unlocked yes)
			(layer "F.Fab")
			(hide yes)
			(effects
				(font
					(size 1 1)
					(thickness 0.15)
				)
			)
		)
		(property "MPN" "CR0402-FX-2201GLF"
			(at 0 0 180)
			(unlocked yes)
			(layer "F.Fab")
			(hide yes)
			(effects
				(font
					(size 1 1)
					(thickness 0.15)
				)
			)
		)
		(property "Val" "2k2"
			(at 0 0 180)
			(unlocked yes)
			(layer "F.Fab")
			(hide yes)
			(effects
				(font
					(size 1 1)
					(thickness 0.15)
				)
			)
		)
		(property "License" "Apache-2.0"
			(at 0 0 180)
			(unlocked yes)
			(layer "F.Fab")
			(hide yes)
			(effects
				(font
					(size 1 1)
					(thickness 0.15)
				)
			)
		)
		(property "Author" "Antmicro"
			(at 0 0 180)
			(unlocked yes)
			(layer "F.Fab")
			(hide yes)
			(effects
				(font
					(size 1 1)
					(thickness 0.15)
				)
			)
		)
		(property "Tolerance" "1%"
			(at 0 0 180)
			(unlocked yes)
			(layer "F.Fab")
			(hide yes)
			(effects
				(font
					(size 1 1)
					(thickness 0.15)
				)
			)
		)
		(sheetname "/Compute module/")
		(sheetfile "compute-module.kicad_sch")
		(attr smd)
		(fp_rect
			(start -0.925 -0.47)
			(end 0.925 0.47)
			(stroke
				(width 0.05)
				(type default)
			)
			(fill no)
			(layer "F.CrtYd")
		)
		(fp_rect
			(start -0.5 -0.25)
			(end 0.5 0.25)
			(stroke
				(width 0.15)
				(type solid)
			)
			(fill no)
			(layer "F.Fab")
		)
		(fp_text user "Author: Antmicro"
			(at -0.95 4.169 180)
			(layer "F.Fab")
			(effects
				(font
					(size 0.7 0.7)
					(thickness 0.15)
				)
				(justify left bottom)
			)
		)
		(fp_text user "${REFERENCE}"
			(at -0.95 3.168 180)
			(layer "F.Fab")
			(effects
				(font
					(size 0.7 0.7)
					(thickness 0.15)
				)
				(justify left bottom)
			)
		)
		(fp_text user "License: Apache-2.0"
			(at -0.95 5.169 180)
			(layer "F.Fab")
			(effects
				(font
					(size 0.7 0.7)
					(thickness 0.15)
				)
				(justify left bottom)
			)
		)
		(pad "1" smd roundrect
			(at -0.48 0 180)
			(size 0.59 0.64)
			(layers "F.Cu" "F.Mask" "F.Paste")
			(roundrect_rratio 0.25)
			(net 330 "Net-(Q209-D)")
			(pintype "passive")
		)
		(pad "2" smd roundrect
			(at 0.48 0 180)
			(size 0.59 0.64)
			(layers "F.Cu" "F.Mask" "F.Paste")
			(roundrect_rratio 0.25)
			(net 255 "/Compute module/~{RPi_RST}")
			(pintype "passive")
		)
	)
	(footprint "antmicro-footprints:TP_SMD_0.75mm"
		(layer "F.Cu")
		(at 117.717962 141.5165 -90)
		(property "Reference" "TP303"
			(at 0.58 -0.4 90)
			(layer "F.SilkS")
			(effects
				(font
					(size 0.7 0.7)
					(thickness 0.15)
				)
				(justify right bottom)
			)
		)
		(property "Value" "TP_0.75mm_SMD"
			(at 0 1.2 90)
			(layer "F.Fab")
			(effects
				(font
					(size 0.7 0.7)
					(thickness 0.15)
				)
				(justify right bottom)
			)
		)
		(property "Author" "Antmicro"
			(at 0 0 270)
			(unlocked yes)
			(layer "F.Fab")
			(hide yes)
			(effects
				(font
					(size 1 1)
					(thickness 0.15)
				)
			)
		)
		(property "License" "Apache-2.0"
			(at 0 0 270)
			(unlocked yes)
			(layer "F.Fab")
			(hide yes)
			(effects
				(font
					(size 1 1)
					(thickness 0.15)
				)
			)
		)
		(property "MPN" ""
			(at 0 0 270)
			(unlocked yes)
			(layer "F.Fab")
			(hide yes)
			(effects
				(font
					(size 1 1)
					(thickness 0.15)
				)
			)
		)
		(property "Manufacturer" ""
			(at 0 0 270)
			(unlocked yes)
			(layer "F.Fab")
			(hide yes)
			(effects
				(font
					(size 1 1)
					(thickness 0.15)
				)
			)
		)
		(sheetname "/Supply/")
		(sheetfile "supply.kicad_sch")
		(attr exclude_from_pos_files exclude_from_bom)
		(fp_circle
			(center 0 0)
			(end 0.475 0)
			(stroke
				(width 0.05)
				(type default)
			)
			(fill no)
			(layer "F.CrtYd")
		)
		(fp_text user "${REFERENCE}"
			(at -0.4 2.7 270)
			(layer "F.Fab")
			(effects
				(font
					(size 0.7 0.7)
					(thickness 0.15)
				)
				(justify left bottom)
			)
		)
		(fp_text user "Author: Antmicro"
			(at -0.4 3.901 270)
			(layer "F.Fab")
			(effects
				(font
					(size 0.7 0.7)
					(thickness 0.15)
				)
				(justify left bottom)
			)
		)
		(fp_text user "License: Apache-2.0"
			(at -0.4 5.101 270)
			(layer "F.Fab")
			(effects
				(font
					(size 0.7 0.7)
					(thickness 0.15)
				)
				(justify left bottom)
			)
		)
		(pad "1" smd circle
			(at 0 0 270)
			(size 0.75 0.75)
			(layers "F.Cu" "F.Mask")
			(net 380 "/Compute module/NVMe_EN")
			(pinfunction "1")
			(pintype "passive")
		)
	)
	(footprint "antmicro-footprints:C_0402_1005Metric"
		(layer "F.Cu")
		(at 66.092962 177.7005 -90)
		(descr "Capacitor SMD 0402")
		(tags "capacitor SMD 0402")
		(property "Reference" "C816"
			(at -2.704 13.955 90)
			(layer "F.SilkS")
			(effects
				(font
					(size 0.7 0.7)
					(thickness 0.15)
				)
				(justify right bottom)
			)
		)
		(property "Value" "C_template_name_0402"
			(at -1.022927 2.155213 90)
			(layer "F.Fab")
			(effects
				(font
					(size 0.7 0.7)
					(thickness 0.15)
				)
				(justify right bottom)
			)
		)
		(property "Datasheet" "template_datasheet"
			(at 0 0 270)
			(layer "F.Fab")
			(hide yes)
			(effects
				(font
					(size 1.27 1.27)
					(thickness 0.15)
				)
			)
		)
		(property "MPN" "template_MPN"
			(at 0 0 270)
			(unlocked yes)
			(layer "F.Fab")
			(hide yes)
			(effects
				(font
					(size 1 1)
					(thickness 0.15)
				)
			)
		)
		(property "Manufacturer" "template_manufacturer"
			(at 0 0 270)
			(unlocked yes)
			(layer "F.Fab")
			(hide yes)
			(effects
				(font
					(size 1 1)
					(thickness 0.15)
				)
			)
		)
		(property "License" "Apache-2.0"
			(at 0 0 270)
			(unlocked yes)
			(layer "F.Fab")
			(hide yes)
			(effects
				(font
					(size 1 1)
					(thickness 0.15)
				)
			)
		)
		(property "Author" "Antmicro"
			(at 0 0 270)
			(unlocked yes)
			(layer "F.Fab")
			(hide yes)
			(effects
				(font
					(size 1 1)
					(thickness 0.15)
				)
			)
		)
		(property "Val" "template_value"
			(at 0 0 270)
			(unlocked yes)
			(layer "F.Fab")
			(hide yes)
			(effects
				(font
					(size 1 1)
					(thickness 0.15)
				)
			)
		)
		(property "Voltage" "template_voltage"
			(at 0 0 270)
			(unlocked yes)
			(layer "F.Fab")
			(hide yes)
			(effects
				(font
					(size 1 1)
					(thickness 0.15)
				)
			)
		)
		(property "Dielectric" "template_dielectric"
			(at 0 0 270)
			(unlocked yes)
			(layer "F.Fab")
			(hide yes)
			(effects
				(font
					(size 1 1)
					(thickness 0.15)
				)
			)
		)
		(sheetname "/Peripherals/")
		(sheetfile "peripherals.kicad_sch")
		(attr smd exclude_from_pos_files exclude_from_bom dnp)
		(fp_rect
			(start -0.925 -0.47)
			(end 0.925 0.47)
			(stroke
				(width 0.05)
				(type default)
			)
			(fill no)
			(layer "F.CrtYd")
		)
		(fp_line
			(start -0.494 0.248)
			(end -0.494 -0.25)
			(stroke
				(width 0.15)
				(type solid)
			)
			(layer "F.Fab")
		)
		(fp_line
			(start 0.504 0.248)
			(end -0.494 0.248)
			(stroke
				(width 0.15)
				(type solid)
			)
			(layer "F.Fab")
		)
		(fp_line
			(start -0.494 -0.25)
			(end 0.504 -0.25)
			(stroke
				(width 0.15)
				(type solid)
			)
			(layer "F.Fab")
		)
		(fp_line
			(start 0.504 -0.25)
			(end 0.504 0.248)
			(stroke
				(width 0.15)
				(type solid)
			)
			(layer "F.Fab")
		)
		(fp_text user "${REFERENCE}"
			(at -0.939 4.599 270)
			(layer "F.Fab")
			(effects
				(font
					(size 0.7 0.7)
					(thickness 0.15)
				)
				(justify left bottom)
			)
		)
		(fp_text user "License: Apache-2.0"
			(at -0.939 5.799 270)
			(layer "F.Fab")
			(effects
				(font
					(size 0.7 0.7)
					(thickness 0.15)
				)
				(justify left bottom)
			)
		)
		(fp_text user "Author: Antmicro"
			(at -0.939 3.399 270)
			(layer "F.Fab")
			(effects
				(font
					(size 0.7 0.7)
					(thickness 0.15)
				)
				(justify left bottom)
			)
		)
		(pad "1" smd roundrect
			(at -0.48 0 270)
			(size 0.59 0.64)
			(layers "F.Cu" "F.Mask" "F.Paste")
			(roundrect_rratio 0.25)
			(net 3 "GND")
			(pintype "passive")
		)
		(pad "2" smd roundrect
			(at 0.48 0 270)
			(size 0.59 0.64)
			(layers "F.Cu" "F.Mask" "F.Paste")
			(roundrect_rratio 0.25)
			(net 109 "Net-(C816-Pad2)")
			(pintype "passive")
		)
	)
	(footprint "antmicro-footprints:Conn_JST_SH_1x4_SM04B-SRSS-TB-LF-SN"
		(layer "F.Cu")
		(at 122.817962 114.6165 180)
		(property "Reference" "J802"
			(at 3.81 2.53 90)
			(layer "F.SilkS")
			(effects
				(font
					(size 0.7 0.7)
					(thickness 0.15)
				)
				(justify right bottom)
			)
		)
		(property "Value" "JST_SH_1x4_SM04B-SRSS-TB-LF-SN"
			(at 0 3.9 0)
			(layer "F.Fab")
			(effects
				(font
					(size 0.7 0.7)
					(thickness 0.15)
				)
				(justify right bottom)
			)
		)
		(property "Datasheet" "https://www.jst-mfg.com/product/pdf/eng/eSH.pdf"
			(at 0 0 180)
			(layer "F.Fab")
			(hide yes)
			(effects
				(font
					(size 1.27 1.27)
					(thickness 0.15)
				)
			)
		)
		(property "MPN" "SM04B-SRSS-TB(LF)(SN)"
			(at 0 0 180)
			(unlocked yes)
			(layer "F.Fab")
			(hide yes)
			(effects
				(font
					(size 1 1)
					(thickness 0.15)
				)
			)
		)
		(property "Manufacturer" "JST Automotive Connectors"
			(at 0 0 180)
			(unlocked yes)
			(layer "F.Fab")
			(hide yes)
			(effects
				(font
					(size 1 1)
					(thickness 0.15)
				)
			)
		)
		(property "Author" "Antmicro"
			(at 0 0 180)
			(unlocked yes)
			(layer "F.Fab")
			(hide yes)
			(effects
				(font
					(size 1 1)
					(thickness 0.15)
				)
			)
		)
		(property "License" "Apache-2.0"
			(at 0 0 180)
			(unlocked yes)
			(layer "F.Fab")
			(hide yes)
			(effects
				(font
					(size 1 1)
					(thickness 0.15)
				)
			)
		)
		(sheetname "/Peripherals/")
		(sheetfile "peripherals.kicad_sch")
		(attr smd)
		(fp_line
			(start 3.2 -2)
			(end 3.2 0.6)
			(stroke
				(width 0.15)
				(type solid)
			)
			(layer "F.SilkS")
		)
		(fp_line
			(start 2 -2)
			(end 3.2 -2)
			(stroke
				(width 0.15)
				(type solid)
			)
			(layer "F.SilkS")
		)
		(fp_line
			(start -2 2.6)
			(end 2 2.6)
			(stroke
				(width 0.15)
				(type solid)
			)
			(layer "F.SilkS")
		)
		(fp_line
			(start -2 -2)
			(end -3.2 -2)
			(stroke
				(width 0.15)
				(type solid)
			)
			(layer "F.SilkS")
		)
		(fp_line
			(start -3.2 -2)
			(end -3.2 0.6)
			(stroke
				(width 0.15)
				(type solid)
			)
			(layer "F.SilkS")
		)
		(fp_circle
			(center -2.1 -2.5)
			(end -2.05 -2.5)
			(stroke
				(width 0.15)
				(type solid)
			)
			(fill yes)
			(layer "F.SilkS")
		)
		(fp_rect
			(start -3.65 -3.14)
			(end 3.65 2.9)
			(stroke
				(width 0.05)
				(type solid)
			)
			(fill no)
			(layer "F.CrtYd")
		)
		(fp_rect
			(start -3 -2.475)
			(end 3 2.475)
			(stroke
				(width 0.15)
				(type solid)
			)
			(fill no)
			(layer "F.Fab")
		)
		(fp_text user "${REFERENCE}"
			(at -4 8.28 180)
			(layer "F.Fab")
			(effects
				(font
					(size 0.7 0.7)
					(thickness 0.15)
				)
				(justify left bottom)
			)
		)
		(fp_text user "Author: Antmicro"
			(at -4 7.08 180)
			(layer "F.Fab")
			(effects
				(font
					(size 0.7 0.7)
					(thickness 0.15)
				)
				(justify left bottom)
			)
		)
		(fp_text user "License: Apache-2.0"
			(at -4 5.88 180)
			(layer "F.Fab")
			(effects
				(font
					(size 0.7 0.7)
					(thickness 0.15)
				)
				(justify left bottom)
			)
		)
		(pad "1" smd roundrect
			(at -1.5 -2.12)
			(size 0.6 1.55)
			(layers "F.Cu" "F.Mask" "F.Paste")
			(roundrect_rratio 0.25)
			(net 3 "GND")
			(pintype "passive")
		)
		(pad "2" smd roundrect
			(at -0.5 -2.12)
			(size 0.6 1.55)
			(layers "F.Cu" "F.Mask" "F.Paste")
			(roundrect_rratio 0.25)
			(net 9 "+3V3")
			(pintype "passive")
		)
		(pad "3" smd roundrect
			(at 0.5 -2.12)
			(size 0.6 1.55)
			(layers "F.Cu" "F.Mask" "F.Paste")
			(roundrect_rratio 0.25)
			(net 143 "/CSI/I_{2}C1.SDA")
			(pintype "passive")
		)
		(pad "4" smd roundrect
			(at 1.5 -2.12)
			(size 0.6 1.55)
			(layers "F.Cu" "F.Mask" "F.Paste")
			(roundrect_rratio 0.25)
			(net 142 "/CSI/I_{2}C1.SCL")
			(pintype "passive")
		)
		(pad "MP" smd roundrect
			(at -2.8 1.755 180)
			(size 1.2 1.8)
			(layers "F.Cu" "F.Mask" "F.Paste")
			(roundrect_rratio 0.25)
			(net 3 "GND")
			(pintype "passive")
		)
		(pad "MP" smd roundrect
			(at 2.8 1.755 180)
			(size 1.2 1.8)
			(layers "F.Cu" "F.Mask" "F.Paste")
			(roundrect_rratio 0.25)
			(net 3 "GND")
			(pintype "passive")
		)
	)
	(footprint "antmicro-footprints:LED_0603_1608Metric_G"
		(layer "F.Cu")
		(at 75.627962 133.3165 180)
		(descr "LED SMD 0603 Green")
		(tags "LED SMD 0603 Green")
		(property "Reference" "D912"
			(at 5.177962 -2.105775 0)
			(layer "F.SilkS")
			(effects
				(font
					(size 0.7 0.7)
					(thickness 0.15)
				)
				(justify right bottom)
			)
		)
		(property "Value" "LED_G_0603_KP-1608CGCK"
			(at -0.001 1.599 0)
			(layer "F.Fab")
			(effects
				(font
					(size 0.7 0.7)
					(thickness 0.15)
				)
				(justify right bottom)
			)
		)
		(property "Datasheet" "http://www.kingbright.com/attachments/file/psearch//000/00/00/KP-1608CGCK(Ver.23B).pdf"
			(at 0 0 180)
			(layer "F.Fab")
			(hide yes)
			(effects
				(font
					(size 1.27 1.27)
					(thickness 0.15)
				)
			)
		)
		(property "MPN" "KP-1608CGCK"
			(at 0 0 180)
			(unlocked yes)
			(layer "F.Fab")
			(hide yes)
			(effects
				(font
					(size 1 1)
					(thickness 0.15)
				)
			)
		)
		(property "Manufacturer" "Kingbright"
			(at 0 0 180)
			(unlocked yes)
			(layer "F.Fab")
			(hide yes)
			(effects
				(font
					(size 1 1)
					(thickness 0.15)
				)
			)
		)
		(property "Color" "Green"
			(at 0 0 180)
			(unlocked yes)
			(layer "F.Fab")
			(hide yes)
			(effects
				(font
					(size 1 1)
					(thickness 0.15)
				)
			)
		)
		(property "Author" "Antmicro"
			(at 0 0 180)
			(unlocked yes)
			(layer "F.Fab")
			(hide yes)
			(effects
				(font
					(size 1 1)
					(thickness 0.15)
				)
			)
		)
		(property "License" "Apache-2.0"
			(at 0 0 180)
			(unlocked yes)
			(layer "F.Fab")
			(hide yes)
			(effects
				(font
					(size 1 1)
					(thickness 0.15)
				)
			)
		)
		(sheetname "/USB/")
		(sheetfile "usb.kicad_sch")
		(attr smd)
		(fp_line
			(start 0.22 0.35)
			(end -0.22 0.35)
			(stroke
				(width 0.15)
				(type solid)
			)
			(layer "F.SilkS")
		)
		(fp_line
			(start 0.22 -0.35)
			(end -0.22 -0.35)
			(stroke
				(width 0.15)
				(type solid)
			)
			(layer "F.SilkS")
		)
		(fp_line
			(start 0.105328 0.201008)
			(end 0.105328 -0.198992)
			(stroke
				(width 0.1)
				(type solid)
			)
			(layer "F.SilkS")
		)
		(fp_line
			(start 0.105328 0.201008)
			(end -0.094672 0.001008)
			(stroke
				(width 0.1)
				(type solid)
			)
			(layer "F.SilkS")
		)
		(fp_line
			(start 0.105328 0.001008)
			(end 0.24 0.001)
			(stroke
				(width 0.1)
				(type solid)
			)
			(layer "F.SilkS")
		)
		(fp_line
			(start -0.094672 0.201008)
			(end -0.094672 -0.198992)
			(stroke
				(width 0.1)
				(type solid)
			)
			(layer "F.SilkS")
		)
		(fp_line
			(start -0.094672 0.001008)
			(end 0.105328 -0.198992)
			(stroke
				(width 0.1)
				(type solid)
			)
			(layer "F.SilkS")
		)
		(fp_line
			(start -0.094672 0.001008)
			(end -0.24 0.001008)
			(stroke
				(width 0.1)
				(type solid)
			)
			(layer "F.SilkS")
		)
		(fp_line
			(start -1.18 -0.319)
			(end -1.18 0.321)
			(stroke
				(width 0.15)
				(type solid)
			)
			(layer "F.SilkS")
		)
		(fp_rect
			(start 1.25 0.65)
			(end -1.25 -0.65)
			(stroke
				(width 0.05)
				(type solid)
			)
			(fill no)
			(layer "F.CrtYd")
		)
		(fp_line
			(start 0.599 0)
			(end 0.201 0)
			(stroke
				(width 0.15)
				(type solid)
			)
			(layer "F.Fab")
		)
		(fp_line
			(start 0.201 0.2)
			(end 0.201 0)
			(stroke
				(width 0.15)
				(type solid)
			)
			(layer "F.Fab")
		)
		(fp_line
			(start 0.201 0)
			(end 0.201 -0.202)
			(stroke
				(width 0.15)
				(type solid)
			)
			(layer "F.Fab")
		)
		(fp_line
			(start 0.201 -0.202)
			(end -0.101 0)
			(stroke
				(width 0.15)
				(type solid)
			)
			(layer "F.Fab")
		)
		(fp_line
			(start -0.101 0)
			(end 0.201 0.2)
			(stroke
				(width 0.15)
				(type solid)
			)
			(layer "F.Fab")
		)
		(fp_line
			(start -0.199 0.2)
			(end -0.199 0.1)
			(stroke
				(width 0.15)
				(type solid)
			)
			(layer "F.Fab")
		)
		(fp_line
			(start -0.199 0)
			(end -0.597 0)
			(stroke
				(width 0.15)
				(type solid)
			)
			(layer "F.Fab")
		)
		(fp_line
			(start -0.199 -0.202)
			(end -0.199 0.1)
			(stroke
				(width 0.15)
				(type solid)
			)
			(layer "F.Fab")
		)
		(fp_rect
			(start 0.848 0.4)
			(end -0.85 -0.402)
			(stroke
				(width 0.15)
				(type solid)
			)
			(fill no)
			(layer "F.Fab")
		)
		(fp_text user "${REFERENCE}"
			(at -1.4224 5.999 180)
			(layer "F.Fab")
			(effects
				(font
					(size 0.7 0.7)
					(thickness 0.15)
				)
				(justify left bottom)
			)
		)
		(fp_text user "Author: Antmicro"
			(at -1.4224 4.799 180)
			(layer "F.Fab")
			(effects
				(font
					(size 0.7 0.7)
					(thickness 0.15)
				)
				(justify left bottom)
			)
		)
		(fp_text user "License: Apache-2.0"
			(at -1.4224 3.599 180)
			(layer "F.Fab")
			(effects
				(font
					(size 0.7 0.7)
					(thickness 0.15)
				)
				(justify left bottom)
			)
		)
		(pad "1" smd roundrect
			(at -0.7 0)
			(size 0.8 1)
			(layers "F.Cu" "F.Mask" "F.Paste")
			(roundrect_rratio 0.2)
			(net 488 "Net-(D912-C)")
			(pinfunction "C")
			(pintype "passive")
		)
		(pad "2" smd roundrect
			(at 0.7 0)
			(size 0.8 1)
			(layers "F.Cu" "F.Mask" "F.Paste")
			(roundrect_rratio 0.2)
			(net 489 "Net-(D912-A)")
			(pinfunction "A")
			(pintype "passive")
		)
	)
	(footprint "antmicro-footprints:R_0402_1005Metric"
		(layer "F.Cu")
		(at 123.805476 164.8165)
		(descr "Resistor SMD 0402")
		(tags "resistor SMD 0402")
		(property "Reference" "R507"
			(at -3.837514 0.46 0)
			(layer "F.SilkS")
			(effects
				(font
					(size 0.7 0.7)
					(thickness 0.15)
				)
				(justify left bottom)
			)
		)
		(property "Value" "R_10k_0402"
			(at -1.011843 1.772047 0)
			(layer "F.Fab")
			(effects
				(font
					(size 0.7 0.7)
					(thickness 0.15)
				)
				(justify left bottom)
			)
		)
		(property "Datasheet" "https://www.bourns.com/docs/product-datasheets/cr.pdf"
			(at 0 0 0)
			(layer "F.Fab")
			(hide yes)
			(effects
				(font
					(size 1.27 1.27)
					(thickness 0.15)
				)
			)
		)
		(property "Manufacturer" "Bourns"
			(at 0 0 0)
			(unlocked yes)
			(layer "F.Fab")
			(hide yes)
			(effects
				(font
					(size 1 1)
					(thickness 0.15)
				)
			)
		)
		(property "MPN" "CR0402-FX-1002GLF"
			(at 0 0 0)
			(unlocked yes)
			(layer "F.Fab")
			(hide yes)
			(effects
				(font
					(size 1 1)
					(thickness 0.15)
				)
			)
		)
		(property "Val" "10k"
			(at 0 0 0)
			(unlocked yes)
			(layer "F.Fab")
			(hide yes)
			(effects
				(font
					(size 1 1)
					(thickness 0.15)
				)
			)
		)
		(property "License" "Apache-2.0"
			(at 0 0 0)
			(unlocked yes)
			(layer "F.Fab")
			(hide yes)
			(effects
				(font
					(size 1 1)
					(thickness 0.15)
				)
			)
		)
		(property "Author" "Antmicro"
			(at 0 0 0)
			(unlocked yes)
			(layer "F.Fab")
			(hide yes)
			(effects
				(font
					(size 1 1)
					(thickness 0.15)
				)
			)
		)
		(property "Tolerance" "1%"
			(at 0 0 0)
			(unlocked yes)
			(layer "F.Fab")
			(hide yes)
			(effects
				(font
					(size 1 1)
					(thickness 0.15)
				)
			)
		)
		(sheetname "/NVMe & microSD/")
		(sheetfile "nvme-micro-sd.kicad_sch")
		(attr smd)
		(fp_rect
			(start -0.925 -0.47)
			(end 0.925 0.47)
			(stroke
				(width 0.05)
				(type default)
			)
			(fill no)
			(layer "F.CrtYd")
		)
		(fp_rect
			(start -0.5 -0.25)
			(end 0.5 0.25)
			(stroke
				(width 0.15)
				(type solid)
			)
			(fill no)
			(layer "F.Fab")
		)
		(fp_text user "${REFERENCE}"
			(at -0.95 3.168 0)
			(layer "F.Fab")
			(effects
				(font
					(size 0.7 0.7)
					(thickness 0.15)
				)
				(justify left bottom)
			)
		)
		(fp_text user "Author: Antmicro"
			(at -0.95 4.169 0)
			(layer "F.Fab")
			(effects
				(font
					(size 0.7 0.7)
					(thickness 0.15)
				)
				(justify left bottom)
			)
		)
		(fp_text user "License: Apache-2.0"
			(at -0.95 5.169 0)
			(layer "F.Fab")
			(effects
				(font
					(size 0.7 0.7)
					(thickness 0.15)
				)
				(justify left bottom)
			)
		)
		(pad "1" smd roundrect
			(at -0.48 0)
			(size 0.59 0.64)
			(layers "F.Cu" "F.Mask" "F.Paste")
			(roundrect_rratio 0.25)
			(net 9 "+3V3")
			(pintype "passive")
		)
		(pad "2" smd roundrect
			(at 0.48 0)
			(size 0.59 0.64)
			(layers "F.Cu" "F.Mask" "F.Paste")
			(roundrect_rratio 0.25)
			(net 7 "/Compute module/SDIO.CLK")
			(pintype "passive")
		)
	)
	(footprint "antmicro-footprints:C_0805_2012Metric"
		(layer "F.Cu")
		(at 76.237962 124.2465 180)
		(descr "Capacitor SMD 0805")
		(tags "capacitor SMD 0805")
		(property "Reference" "C932"
			(at -0.662038 -1.8785 0)
			(layer "F.SilkS")
			(effects
				(font
					(size 0.7 0.7)
					(thickness 0.15)
				)
				(justify right bottom)
			)
		)
		(property "Value" "C_22u_25V_0805"
			(at -2.055717 1.963152 0)
			(layer "F.Fab")
			(effects
				(font
					(size 0.7 0.7)
					(thickness 0.15)
				)
				(justify right bottom)
			)
		)
		(property "Datasheet" "https://product.samsungsem.com/mlcc/CL21A226MAYNNN.do"
			(at 0 0 180)
			(layer "F.Fab")
			(hide yes)
			(effects
				(font
					(size 1.27 1.27)
					(thickness 0.15)
				)
			)
		)
		(property "Manufacturer" "Samsung Electro-Mechanics"
			(at 0 0 180)
			(unlocked yes)
			(layer "F.Fab")
			(hide yes)
			(effects
				(font
					(size 1 1)
					(thickness 0.15)
				)
			)
		)
		(property "MPN" "CL21A226MAYNNNE"
			(at 0 0 180)
			(unlocked yes)
			(layer "F.Fab")
			(hide yes)
			(effects
				(font
					(size 1 1)
					(thickness 0.15)
				)
			)
		)
		(property "Val" "22u"
			(at 0 0 180)
			(unlocked yes)
			(layer "F.Fab")
			(hide yes)
			(effects
				(font
					(size 1 1)
					(thickness 0.15)
				)
			)
		)
		(property "License" "Apache-2.0"
			(at 0 0 180)
			(unlocked yes)
			(layer "F.Fab")
			(hide yes)
			(effects
				(font
					(size 1 1)
					(thickness 0.15)
				)
			)
		)
		(property "Author" "Antmicro"
			(at 0 0 180)
			(unlocked yes)
			(layer "F.Fab")
			(hide yes)
			(effects
				(font
					(size 1 1)
					(thickness 0.15)
				)
			)
		)
		(property "Voltage" "25V"
			(at 0 0 180)
			(unlocked yes)
			(layer "F.Fab")
			(hide yes)
			(effects
				(font
					(size 1 1)
					(thickness 0.15)
				)
			)
		)
		(property "Dielectric" "X5R"
			(at 0 0 180)
			(unlocked yes)
			(layer "F.Fab")
			(hide yes)
			(effects
				(font
					(size 1 1)
					(thickness 0.15)
				)
			)
		)
		(property "Public" "False"
			(at 0 0 180)
			(unlocked yes)
			(layer "F.Fab")
			(hide yes)
			(effects
				(font
					(size 1 1)
					(thickness 0.15)
				)
			)
		)
		(sheetname "/USB/")
		(sheetfile "usb.kicad_sch")
		(attr smd)
		(fp_line
			(start -0.3 0.7)
			(end 0.3 0.7)
			(stroke
				(width 0.15)
				(type solid)
			)
			(layer "F.SilkS")
		)
		(fp_line
			(start -0.3 -0.7)
			(end 0.3 -0.7)
			(stroke
				(width 0.15)
				(type solid)
			)
			(layer "F.SilkS")
		)
		(fp_rect
			(start 1.95 -0.9)
			(end -1.95 0.9)
			(stroke
				(width 0.05)
				(type default)
			)
			(fill no)
			(layer "F.CrtYd")
		)
		(fp_rect
			(start -0.95 -0.675)
			(end 0.95 0.675)
			(stroke
				(width 0.15)
				(type solid)
			)
			(fill no)
			(layer "F.Fab")
		)
		(fp_text user "Author: Antmicro"
			(at -1.9 5.947 180)
			(layer "F.Fab")
			(effects
				(font
					(size 0.7 0.7)
					(thickness 0.15)
				)
				(justify left bottom)
			)
		)
		(fp_text user "${REFERENCE}"
			(at -1.9 3.947 180)
			(layer "F.Fab")
			(effects
				(font
					(size 0.7 0.7)
					(thickness 0.15)
				)
				(justify left bottom)
			)
		)
		(fp_text user "License: Apache-2.0"
			(at -1.9 4.947 180)
			(layer "F.Fab")
			(effects
				(font
					(size 0.7 0.7)
					(thickness 0.15)
				)
				(justify left bottom)
			)
		)
		(pad "1" smd roundrect
			(at -1.1 0 180)
			(size 1.2 1.3)
			(layers "F.Cu" "F.Mask" "F.Paste")
			(roundrect_rratio 0.25)
			(net 26 "/USB/USBD_VBUS")
			(pintype "passive")
		)
		(pad "2" smd roundrect
			(at 1.1 0 180)
			(size 1.2 1.3)
			(layers "F.Cu" "F.Mask" "F.Paste")
			(roundrect_rratio 0.25)
			(net 3 "GND")
			(pintype "passive")
		)
	)
	(footprint "antmicro-footprints:R_0402_1005Metric"
		(layer "F.Cu")
		(at 101.167962 133.8915 180)
		(descr "Resistor SMD 0402")
		(tags "resistor SMD 0402")
		(property "Reference" "R927"
			(at -3.74 -0.465 0)
			(layer "F.SilkS")
			(effects
				(font
					(size 0.7 0.7)
					(thickness 0.15)
				)
				(justify right bottom)
			)
		)
		(property "Value" "R_4k7_0402"
			(at -1.011843 1.772047 0)
			(layer "F.Fab")
			(effects
				(font
					(size 0.7 0.7)
					(thickness 0.15)
				)
				(justify right bottom)
			)
		)
		(property "Datasheet" "https://www.bourns.com/docs/product-datasheets/cr.pdf"
			(at 0 0 180)
			(layer "F.Fab")
			(hide yes)
			(effects
				(font
					(size 1.27 1.27)
					(thickness 0.15)
				)
			)
		)
		(property "Manufacturer" "Bourns"
			(at 0 0 180)
			(unlocked yes)
			(layer "F.Fab")
			(hide yes)
			(effects
				(font
					(size 1 1)
					(thickness 0.15)
				)
			)
		)
		(property "MPN" "CR0402-FX-4701GLF"
			(at 0 0 180)
			(unlocked yes)
			(layer "F.Fab")
			(hide yes)
			(effects
				(font
					(size 1 1)
					(thickness 0.15)
				)
			)
		)
		(property "Val" "4k7"
			(at 0 0 180)
			(unlocked yes)
			(layer "F.Fab")
			(hide yes)
			(effects
				(font
					(size 1 1)
					(thickness 0.15)
				)
			)
		)
		(property "License" "Apache-2.0"
			(at 0 0 180)
			(unlocked yes)
			(layer "F.Fab")
			(hide yes)
			(effects
				(font
					(size 1 1)
					(thickness 0.15)
				)
			)
		)
		(property "Author" "Antmicro"
			(at 0 0 180)
			(unlocked yes)
			(layer "F.Fab")
			(hide yes)
			(effects
				(font
					(size 1 1)
					(thickness 0.15)
				)
			)
		)
		(property "Tolerance" "1%"
			(at 0 0 180)
			(unlocked yes)
			(layer "F.Fab")
			(hide yes)
			(effects
				(font
					(size 1 1)
					(thickness 0.15)
				)
			)
		)
		(sheetname "/USB/")
		(sheetfile "usb.kicad_sch")
		(attr smd)
		(fp_rect
			(start -0.925 -0.47)
			(end 0.925 0.47)
			(stroke
				(width 0.05)
				(type default)
			)
			(fill no)
			(layer "F.CrtYd")
		)
		(fp_rect
			(start -0.5 -0.25)
			(end 0.5 0.25)
			(stroke
				(width 0.15)
				(type solid)
			)
			(fill no)
			(layer "F.Fab")
		)
		(fp_text user "${REFERENCE}"
			(at -0.95 3.168 180)
			(layer "F.Fab")
			(effects
				(font
					(size 0.7 0.7)
					(thickness 0.15)
				)
				(justify left bottom)
			)
		)
		(fp_text user "License: Apache-2.0"
			(at -0.95 5.169 180)
			(layer "F.Fab")
			(effects
				(font
					(size 0.7 0.7)
					(thickness 0.15)
				)
				(justify left bottom)
			)
		)
		(fp_text user "Author: Antmicro"
			(at -0.95 4.169 180)
			(layer "F.Fab")
			(effects
				(font
					(size 0.7 0.7)
					(thickness 0.15)
				)
				(justify left bottom)
			)
		)
		(pad "1" smd roundrect
			(at -0.48 0 180)
			(size 0.59 0.64)
			(layers "F.Cu" "F.Mask" "F.Paste")
			(roundrect_rratio 0.25)
			(net 3 "GND")
			(pintype "passive")
		)
		(pad "2" smd roundrect
			(at 0.48 0 180)
			(size 0.59 0.64)
			(layers "F.Cu" "F.Mask" "F.Paste")
			(roundrect_rratio 0.25)
			(net 127 "Net-(Q903-G)")
			(pintype "passive")
		)
	)
	(footprint "antmicro-footprints:R_0402_1005Metric"
		(layer "F.Cu")
		(at 56.867962 135.7915 180)
		(descr "Resistor SMD 0402")
		(tags "resistor SMD 0402")
		(property "Reference" "R420"
			(at -1.45 -1.415 0)
			(layer "F.SilkS")
			(effects
				(font
					(size 0.7 0.7)
					(thickness 0.15)
				)
				(justify right bottom)
			)
		)
		(property "Value" "R_100k_0402"
			(at -1.011843 1.772047 0)
			(layer "F.Fab")
			(effects
				(font
					(size 0.7 0.7)
					(thickness 0.15)
				)
				(justify right bottom)
			)
		)
		(property "Datasheet" "https://www.bourns.com/docs/product-datasheets/cr.pdf"
			(at 0 0 180)
			(layer "F.Fab")
			(hide yes)
			(effects
				(font
					(size 1.27 1.27)
					(thickness 0.15)
				)
			)
		)
		(property "Manufacturer" "Bourns"
			(at 0 0 180)
			(unlocked yes)
			(layer "F.Fab")
			(hide yes)
			(effects
				(font
					(size 1 1)
					(thickness 0.15)
				)
			)
		)
		(property "MPN" "CR0402-FX-1003GLF"
			(at 0 0 180)
			(unlocked yes)
			(layer "F.Fab")
			(hide yes)
			(effects
				(font
					(size 1 1)
					(thickness 0.15)
				)
			)
		)
		(property "Val" "100k"
			(at 0 0 180)
			(unlocked yes)
			(layer "F.Fab")
			(hide yes)
			(effects
				(font
					(size 1 1)
					(thickness 0.15)
				)
			)
		)
		(property "License" "Apache-2.0"
			(at 0 0 180)
			(unlocked yes)
			(layer "F.Fab")
			(hide yes)
			(effects
				(font
					(size 1 1)
					(thickness 0.15)
				)
			)
		)
		(property "Author" "Antmicro"
			(at 0 0 180)
			(unlocked yes)
			(layer "F.Fab")
			(hide yes)
			(effects
				(font
					(size 1 1)
					(thickness 0.15)
				)
			)
		)
		(property "Tolerance" "1%"
			(at 0 0 180)
			(unlocked yes)
			(layer "F.Fab")
			(hide yes)
			(effects
				(font
					(size 1 1)
					(thickness 0.15)
				)
			)
		)
		(sheetname "/Ethernet/")
		(sheetfile "ethernet.kicad_sch")
		(attr smd exclude_from_pos_files exclude_from_bom dnp)
		(fp_rect
			(start -0.925 -0.47)
			(end 0.925 0.47)
			(stroke
				(width 0.05)
				(type default)
			)
			(fill no)
			(layer "F.CrtYd")
		)
		(fp_rect
			(start -0.5 -0.25)
			(end 0.5 0.25)
			(stroke
				(width 0.15)
				(type solid)
			)
			(fill no)
			(layer "F.Fab")
		)
		(fp_text user "License: Apache-2.0"
			(at -0.95 5.169 180)
			(layer "F.Fab")
			(effects
				(font
					(size 0.7 0.7)
					(thickness 0.15)
				)
				(justify left bottom)
			)
		)
		(fp_text user "Author: Antmicro"
			(at -0.95 4.169 180)
			(layer "F.Fab")
			(effects
				(font
					(size 0.7 0.7)
					(thickness 0.15)
				)
				(justify left bottom)
			)
		)
		(fp_text user "${REFERENCE}"
			(at -0.95 3.168 180)
			(layer "F.Fab")
			(effects
				(font
					(size 0.7 0.7)
					(thickness 0.15)
				)
				(justify left bottom)
			)
		)
		(pad "1" smd roundrect
			(at -0.48 0 180)
			(size 0.59 0.64)
			(layers "F.Cu" "F.Mask" "F.Paste")
			(roundrect_rratio 0.25)
			(net 1 "GNDD")
			(pintype "passive")
		)
		(pad "2" smd roundrect
			(at 0.48 0 180)
			(size 0.59 0.64)
			(layers "F.Cu" "F.Mask" "F.Paste")
			(roundrect_rratio 0.25)
			(net 126 "/Ethernet/ULS-12_CTRL")
			(pintype "passive")
		)
	)
	(footprint "antmicro-footprints:C_0402_1005Metric"
		(layer "F.Cu")
		(at 88.592962 143.907236 180)
		(descr "Capacitor SMD 0402")
		(tags "capacitor SMD 0402")
		(property "Reference" "C913"
			(at -1.187038 -1.412764 0)
			(layer "F.SilkS")
			(effects
				(font
					(size 0.7 0.7)
					(thickness 0.15)
				)
				(justify right bottom)
			)
		)
		(property "Value" "C_100n_0402"
			(at -1.022927 2.155213 0)
			(layer "F.Fab")
			(effects
				(font
					(size 0.7 0.7)
					(thickness 0.15)
				)
				(justify right bottom)
			)
		)
		(property "Datasheet" "https://www.murata.com/products/productdetail?partno=GRM155R61H104KE14%23"
			(at 0 0 180)
			(layer "F.Fab")
			(hide yes)
			(effects
				(font
					(size 1.27 1.27)
					(thickness 0.15)
				)
			)
		)
		(property "Manufacturer" "Murata"
			(at 0 0 180)
			(unlocked yes)
			(layer "F.Fab")
			(hide yes)
			(effects
				(font
					(size 1 1)
					(thickness 0.15)
				)
			)
		)
		(property "MPN" "GRM155R61H104KE14D"
			(at 0 0 180)
			(unlocked yes)
			(layer "F.Fab")
			(hide yes)
			(effects
				(font
					(size 1 1)
					(thickness 0.15)
				)
			)
		)
		(property "Val" "100n"
			(at 0 0 180)
			(unlocked yes)
			(layer "F.Fab")
			(hide yes)
			(effects
				(font
					(size 1 1)
					(thickness 0.15)
				)
			)
		)
		(property "License" "Apache-2.0"
			(at 0 0 180)
			(unlocked yes)
			(layer "F.Fab")
			(hide yes)
			(effects
				(font
					(size 1 1)
					(thickness 0.15)
				)
			)
		)
		(property "Author" "Antmicro"
			(at 0 0 180)
			(unlocked yes)
			(layer "F.Fab")
			(hide yes)
			(effects
				(font
					(size 1 1)
					(thickness 0.15)
				)
			)
		)
		(property "Voltage" "50V"
			(at 0 0 180)
			(unlocked yes)
			(layer "F.Fab")
			(hide yes)
			(effects
				(font
					(size 1 1)
					(thickness 0.15)
				)
			)
		)
		(property "Dielectric" "X5R"
			(at 0 0 180)
			(unlocked yes)
			(layer "F.Fab")
			(hide yes)
			(effects
				(font
					(size 1 1)
					(thickness 0.15)
				)
			)
		)
		(sheetname "/USB/")
		(sheetfile "usb.kicad_sch")
		(attr smd)
		(fp_rect
			(start -0.925 -0.47)
			(end 0.925 0.47)
			(stroke
				(width 0.05)
				(type default)
			)
			(fill no)
			(layer "F.CrtYd")
		)
		(fp_line
			(start 0.504 0.248)
			(end -0.494 0.248)
			(stroke
				(width 0.15)
				(type solid)
			)
			(layer "F.Fab")
		)
		(fp_line
			(start 0.504 -0.25)
			(end 0.504 0.248)
			(stroke
				(width 0.15)
				(type solid)
			)
			(layer "F.Fab")
		)
		(fp_line
			(start -0.494 0.248)
			(end -0.494 -0.25)
			(stroke
				(width 0.15)
				(type solid)
			)
			(layer "F.Fab")
		)
		(fp_line
			(start -0.494 -0.25)
			(end 0.504 -0.25)
			(stroke
				(width 0.15)
				(type solid)
			)
			(layer "F.Fab")
		)
		(fp_text user "Author: Antmicro"
			(at -0.939 3.399 180)
			(layer "F.Fab")
			(effects
				(font
					(size 0.7 0.7)
					(thickness 0.15)
				)
				(justify left bottom)
			)
		)
		(fp_text user "${REFERENCE}"
			(at -0.939 4.599 180)
			(layer "F.Fab")
			(effects
				(font
					(size 0.7 0.7)
					(thickness 0.15)
				)
				(justify left bottom)
			)
		)
		(fp_text user "License: Apache-2.0"
			(at -0.939 5.799 180)
			(layer "F.Fab")
			(effects
				(font
					(size 0.7 0.7)
					(thickness 0.15)
				)
				(justify left bottom)
			)
		)
		(pad "1" smd roundrect
			(at -0.48 0 180)
			(size 0.59 0.64)
			(layers "F.Cu" "F.Mask" "F.Paste")
			(roundrect_rratio 0.25)
			(net 27 "/USB/USB_3V3")
			(pintype "passive")
		)
		(pad "2" smd roundrect
			(at 0.48 0 180)
			(size 0.59 0.64)
			(layers "F.Cu" "F.Mask" "F.Paste")
			(roundrect_rratio 0.25)
			(net 3 "GND")
			(pintype "passive")
		)
	)
	(footprint "antmicro-footprints:TP_SMD_0.75mm"
		(layer "F.Cu")
		(at 74.77 153.68 180)
		(property "Reference" "TP213"
			(at 3.79 -0.22 180)
			(layer "F.SilkS")
			(effects
				(font
					(size 0.7 0.7)
					(thickness 0.15)
				)
				(justify left bottom)
			)
		)
		(property "Value" "TP_0.75mm_SMD"
			(at 0 1.2 180)
			(layer "F.Fab")
			(effects
				(font
					(size 0.7 0.7)
					(thickness 0.15)
				)
				(justify left bottom)
			)
		)
		(property "Author" "Antmicro"
			(at 0 0 180)
			(unlocked yes)
			(layer "F.Fab")
			(hide yes)
			(effects
				(font
					(size 1 1)
					(thickness 0.15)
				)
			)
		)
		(property "License" "Apache-2.0"
			(at 0 0 180)
			(unlocked yes)
			(layer "F.Fab")
			(hide yes)
			(effects
				(font
					(size 1 1)
					(thickness 0.15)
				)
			)
		)
		(property "MPN" ""
			(at 0 0 180)
			(unlocked yes)
			(layer "F.Fab")
			(hide yes)
			(effects
				(font
					(size 1 1)
					(thickness 0.15)
				)
			)
		)
		(property "Manufacturer" ""
			(at 0 0 180)
			(unlocked yes)
			(layer "F.Fab")
			(hide yes)
			(effects
				(font
					(size 1 1)
					(thickness 0.15)
				)
			)
		)
		(sheetname "/Compute module/")
		(sheetfile "compute-module.kicad_sch")
		(attr exclude_from_pos_files exclude_from_bom)
		(fp_circle
			(center 0 0)
			(end 0.475 0)
			(stroke
				(width 0.05)
				(type default)
			)
			(fill no)
			(layer "F.CrtYd")
		)
		(fp_text user "Author: Antmicro"
			(at -0.4 3.901 180)
			(layer "F.Fab")
			(effects
				(font
					(size 0.7 0.7)
					(thickness 0.15)
				)
				(justify left bottom)
			)
		)
		(fp_text user "${REFERENCE}"
			(at -0.4 2.7 180)
			(layer "F.Fab")
			(effects
				(font
					(size 0.7 0.7)
					(thickness 0.15)
				)
				(justify left bottom)
			)
		)
		(fp_text user "License: Apache-2.0"
			(at -0.4 5.101 180)
			(layer "F.Fab")
			(effects
				(font
					(size 0.7 0.7)
					(thickness 0.15)
				)
				(justify left bottom)
			)
		)
		(pad "1" smd circle
			(at 0 0 180)
			(size 0.75 0.75)
			(layers "F.Cu" "F.Mask")
			(net 18 "V_{IO}")
			(pinfunction "1")
			(pintype "passive")
		)
	)
	(footprint "antmicro-footprints:TP_SMD_0.75mm"
		(layer "F.Cu")
		(at 110.742962 146.8915 180)
		(property "Reference" "TP212"
			(at -0.907038 -3.6335 270)
			(layer "F.SilkS")
			(effects
				(font
					(size 0.7 0.7)
					(thickness 0.15)
				)
				(justify left bottom)
			)
		)
		(property "Value" "TP_0.75mm_SMD"
			(at 0 1.2 180)
			(layer "F.Fab")
			(effects
				(font
					(size 0.7 0.7)
					(thickness 0.15)
				)
				(justify left bottom)
			)
		)
		(property "Author" "Antmicro"
			(at 0 0 180)
			(unlocked yes)
			(layer "F.Fab")
			(hide yes)
			(effects
				(font
					(size 1 1)
					(thickness 0.15)
				)
			)
		)
		(property "License" "Apache-2.0"
			(at 0 0 180)
			(unlocked yes)
			(layer "F.Fab")
			(hide yes)
			(effects
				(font
					(size 1 1)
					(thickness 0.15)
				)
			)
		)
		(property "MPN" ""
			(at 0 0 180)
			(unlocked yes)
			(layer "F.Fab")
			(hide yes)
			(effects
				(font
					(size 1 1)
					(thickness 0.15)
				)
			)
		)
		(property "Manufacturer" ""
			(at 0 0 180)
			(unlocked yes)
			(layer "F.Fab")
			(hide yes)
			(effects
				(font
					(size 1 1)
					(thickness 0.15)
				)
			)
		)
		(sheetname "/Compute module/")
		(sheetfile "compute-module.kicad_sch")
		(attr exclude_from_pos_files exclude_from_bom)
		(fp_circle
			(center 0 0)
			(end 0.475 0)
			(stroke
				(width 0.05)
				(type default)
			)
			(fill no)
			(layer "F.CrtYd")
		)
		(fp_text user "License: Apache-2.0"
			(at -0.4 5.101 180)
			(layer "F.Fab")
			(effects
				(font
					(size 0.7 0.7)
					(thickness 0.15)
				)
				(justify left bottom)
			)
		)
		(fp_text user "Author: Antmicro"
			(at -0.4 3.901 180)
			(layer "F.Fab")
			(effects
				(font
					(size 0.7 0.7)
					(thickness 0.15)
				)
				(justify left bottom)
			)
		)
		(fp_text user "${REFERENCE}"
			(at -0.4 2.7 180)
			(layer "F.Fab")
			(effects
				(font
					(size 0.7 0.7)
					(thickness 0.15)
				)
				(justify left bottom)
			)
		)
		(pad "1" smd circle
			(at 0 0 180)
			(size 0.75 0.75)
			(layers "F.Cu" "F.Mask")
			(net 256 "/Compute module/VDAC_COMP")
			(pinfunction "1")
			(pintype "passive")
		)
	)
	(footprint "antmicro-footprints:R_0402_1005Metric"
		(layer "F.Cu")
		(at 137.142962 161.5415 90)
		(descr "Resistor SMD 0402")
		(tags "resistor SMD 0402")
		(property "Reference" "R604"
			(at -1.7335 1.232038 90)
			(layer "F.SilkS")
			(effects
				(font
					(size 0.7 0.7)
					(thickness 0.15)
				)
				(justify left bottom)
			)
		)
		(property "Value" "R_4k7_0402"
			(at -1.011843 1.772047 90)
			(layer "F.Fab")
			(effects
				(font
					(size 0.7 0.7)
					(thickness 0.15)
				)
				(justify left bottom)
			)
		)
		(property "Datasheet" "https://www.bourns.com/docs/product-datasheets/cr.pdf"
			(at 0 0 90)
			(layer "F.Fab")
			(hide yes)
			(effects
				(font
					(size 1.27 1.27)
					(thickness 0.15)
				)
			)
		)
		(property "Manufacturer" "Bourns"
			(at 0 0 90)
			(unlocked yes)
			(layer "F.Fab")
			(hide yes)
			(effects
				(font
					(size 1 1)
					(thickness 0.15)
				)
			)
		)
		(property "MPN" "CR0402-FX-4701GLF"
			(at 0 0 90)
			(unlocked yes)
			(layer "F.Fab")
			(hide yes)
			(effects
				(font
					(size 1 1)
					(thickness 0.15)
				)
			)
		)
		(property "Val" "4k7"
			(at 0 0 90)
			(unlocked yes)
			(layer "F.Fab")
			(hide yes)
			(effects
				(font
					(size 1 1)
					(thickness 0.15)
				)
			)
		)
		(property "License" "Apache-2.0"
			(at 0 0 90)
			(unlocked yes)
			(layer "F.Fab")
			(hide yes)
			(effects
				(font
					(size 1 1)
					(thickness 0.15)
				)
			)
		)
		(property "Author" "Antmicro"
			(at 0 0 90)
			(unlocked yes)
			(layer "F.Fab")
			(hide yes)
			(effects
				(font
					(size 1 1)
					(thickness 0.15)
				)
			)
		)
		(property "Tolerance" "1%"
			(at 0 0 90)
			(unlocked yes)
			(layer "F.Fab")
			(hide yes)
			(effects
				(font
					(size 1 1)
					(thickness 0.15)
				)
			)
		)
		(sheetname "/CSI/")
		(sheetfile "csi.kicad_sch")
		(attr smd)
		(fp_rect
			(start -0.925 -0.47)
			(end 0.925 0.47)
			(stroke
				(width 0.05)
				(type default)
			)
			(fill no)
			(layer "F.CrtYd")
		)
		(fp_rect
			(start -0.5 -0.25)
			(end 0.5 0.25)
			(stroke
				(width 0.15)
				(type solid)
			)
			(fill no)
			(layer "F.Fab")
		)
		(fp_text user "Author: Antmicro"
			(at -0.95 4.169 90)
			(layer "F.Fab")
			(effects
				(font
					(size 0.7 0.7)
					(thickness 0.15)
				)
				(justify left bottom)
			)
		)
		(fp_text user "License: Apache-2.0"
			(at -0.95 5.169 90)
			(layer "F.Fab")
			(effects
				(font
					(size 0.7 0.7)
					(thickness 0.15)
				)
				(justify left bottom)
			)
		)
		(fp_text user "${REFERENCE}"
			(at -0.95 3.168 90)
			(layer "F.Fab")
			(effects
				(font
					(size 0.7 0.7)
					(thickness 0.15)
				)
				(justify left bottom)
			)
		)
		(pad "1" smd roundrect
			(at -0.48 0 90)
			(size 0.59 0.64)
			(layers "F.Cu" "F.Mask" "F.Paste")
			(roundrect_rratio 0.25)
			(net 3 "GND")
			(pintype "passive")
		)
		(pad "2" smd roundrect
			(at 0.48 0 90)
			(size 0.59 0.64)
			(layers "F.Cu" "F.Mask" "F.Paste")
			(roundrect_rratio 0.25)
			(net 372 "Net-(U601-ISET)")
			(pintype "passive")
		)
	)
	(footprint "antmicro-footprints:LED_0603_1608Metric_G"
		(layer "F.Cu")
		(at 136.537962 156.0165 180)
		(descr "LED SMD 0603 Green")
		(tags "LED SMD 0603 Green")
		(property "Reference" "D601"
			(at -3.98 -0.4 0)
			(layer "F.SilkS")
			(effects
				(font
					(size 0.7 0.7)
					(thickness 0.15)
				)
				(justify right bottom)
			)
		)
		(property "Value" "LED_G_0603_KP-1608CGCK"
			(at -0.001 1.599 0)
			(layer "F.Fab")
			(effects
				(font
					(size 0.7 0.7)
					(thickness 0.15)
				)
				(justify right bottom)
			)
		)
		(property "Datasheet" "http://www.kingbright.com/attachments/file/psearch//000/00/00/KP-1608CGCK(Ver.23B).pdf"
			(at 0 0 180)
			(layer "F.Fab")
			(hide yes)
			(effects
				(font
					(size 1.27 1.27)
					(thickness 0.15)
				)
			)
		)
		(property "MPN" "KP-1608CGCK"
			(at 0 0 180)
			(unlocked yes)
			(layer "F.Fab")
			(hide yes)
			(effects
				(font
					(size 1 1)
					(thickness 0.15)
				)
			)
		)
		(property "Manufacturer" "Kingbright"
			(at 0 0 180)
			(unlocked yes)
			(layer "F.Fab")
			(hide yes)
			(effects
				(font
					(size 1 1)
					(thickness 0.15)
				)
			)
		)
		(property "Color" "Green"
			(at 0 0 180)
			(unlocked yes)
			(layer "F.Fab")
			(hide yes)
			(effects
				(font
					(size 1 1)
					(thickness 0.15)
				)
			)
		)
		(property "Author" "Antmicro"
			(at 0 0 180)
			(unlocked yes)
			(layer "F.Fab")
			(hide yes)
			(effects
				(font
					(size 1 1)
					(thickness 0.15)
				)
			)
		)
		(property "License" "Apache-2.0"
			(at 0 0 180)
			(unlocked yes)
			(layer "F.Fab")
			(hide yes)
			(effects
				(font
					(size 1 1)
					(thickness 0.15)
				)
			)
		)
		(sheetname "/CSI/")
		(sheetfile "csi.kicad_sch")
		(attr smd)
		(fp_line
			(start 0.22 0.35)
			(end -0.22 0.35)
			(stroke
				(width 0.15)
				(type solid)
			)
			(layer "F.SilkS")
		)
		(fp_line
			(start 0.22 -0.35)
			(end -0.22 -0.35)
			(stroke
				(width 0.15)
				(type solid)
			)
			(layer "F.SilkS")
		)
		(fp_line
			(start 0.105328 0.201008)
			(end 0.105328 -0.198992)
			(stroke
				(width 0.1)
				(type solid)
			)
			(layer "F.SilkS")
		)
		(fp_line
			(start 0.105328 0.201008)
			(end -0.094672 0.001008)
			(stroke
				(width 0.1)
				(type solid)
			)
			(layer "F.SilkS")
		)
		(fp_line
			(start 0.105328 0.001008)
			(end 0.24 0.001)
			(stroke
				(width 0.1)
				(type solid)
			)
			(layer "F.SilkS")
		)
		(fp_line
			(start -0.094672 0.201008)
			(end -0.094672 -0.198992)
			(stroke
				(width 0.1)
				(type solid)
			)
			(layer "F.SilkS")
		)
		(fp_line
			(start -0.094672 0.001008)
			(end 0.105328 -0.198992)
			(stroke
				(width 0.1)
				(type solid)
			)
			(layer "F.SilkS")
		)
		(fp_line
			(start -0.094672 0.001008)
			(end -0.24 0.001008)
			(stroke
				(width 0.1)
				(type solid)
			)
			(layer "F.SilkS")
		)
		(fp_line
			(start -1.18 -0.319)
			(end -1.18 0.321)
			(stroke
				(width 0.15)
				(type solid)
			)
			(layer "F.SilkS")
		)
		(fp_rect
			(start 1.25 0.65)
			(end -1.25 -0.65)
			(stroke
				(width 0.05)
				(type solid)
			)
			(fill no)
			(layer "F.CrtYd")
		)
		(fp_line
			(start 0.599 0)
			(end 0.201 0)
			(stroke
				(width 0.15)
				(type solid)
			)
			(layer "F.Fab")
		)
		(fp_line
			(start 0.201 0.2)
			(end 0.201 0)
			(stroke
				(width 0.15)
				(type solid)
			)
			(layer "F.Fab")
		)
		(fp_line
			(start 0.201 0)
			(end 0.201 -0.202)
			(stroke
				(width 0.15)
				(type solid)
			)
			(layer "F.Fab")
		)
		(fp_line
			(start 0.201 -0.202)
			(end -0.101 0)
			(stroke
				(width 0.15)
				(type solid)
			)
			(layer "F.Fab")
		)
		(fp_line
			(start -0.101 0)
			(end 0.201 0.2)
			(stroke
				(width 0.15)
				(type solid)
			)
			(layer "F.Fab")
		)
		(fp_line
			(start -0.199 0.2)
			(end -0.199 0.1)
			(stroke
				(width 0.15)
				(type solid)
			)
			(layer "F.Fab")
		)
		(fp_line
			(start -0.199 0)
			(end -0.597 0)
			(stroke
				(width 0.15)
				(type solid)
			)
			(layer "F.Fab")
		)
		(fp_line
			(start -0.199 -0.202)
			(end -0.199 0.1)
			(stroke
				(width 0.15)
				(type solid)
			)
			(layer "F.Fab")
		)
		(fp_rect
			(start 0.848 0.4)
			(end -0.85 -0.402)
			(stroke
				(width 0.15)
				(type solid)
			)
			(fill no)
			(layer "F.Fab")
		)
		(fp_text user "License: Apache-2.0"
			(at -1.4224 3.599 180)
			(layer "F.Fab")
			(effects
				(font
					(size 0.7 0.7)
					(thickness 0.15)
				)
				(justify left bottom)
			)
		)
		(fp_text user "${REFERENCE}"
			(at -1.4224 5.999 180)
			(layer "F.Fab")
			(effects
				(font
					(size 0.7 0.7)
					(thickness 0.15)
				)
				(justify left bottom)
			)
		)
		(fp_text user "Author: Antmicro"
			(at -1.4224 4.799 180)
			(layer "F.Fab")
			(effects
				(font
					(size 0.7 0.7)
					(thickness 0.15)
				)
				(justify left bottom)
			)
		)
		(pad "1" smd roundrect
			(at -0.7 0)
			(size 0.8 1)
			(layers "F.Cu" "F.Mask" "F.Paste")
			(roundrect_rratio 0.2)
			(net 3 "GND")
			(pinfunction "C")
			(pintype "passive")
		)
		(pad "2" smd roundrect
			(at 0.7 0)
			(size 0.8 1)
			(layers "F.Cu" "F.Mask" "F.Paste")
			(roundrect_rratio 0.2)
			(net 479 "Net-(D601-A)")
			(pinfunction "A")
			(pintype "passive")
		)
	)
	(footprint "antmicro-footprints:TP_SMD_0.75mm"
		(layer "F.Cu")
		(at 97.592962 121.4665)
		(property "Reference" "TP911"
			(at 25.935 26.15 0)
			(layer "F.SilkS")
			(effects
				(font
					(size 0.7 0.7)
					(thickness 0.15)
				)
				(justify left bottom)
			)
		)
		(property "Value" "TP_0.75mm_SMD"
			(at 0 1.2 0)
			(layer "F.Fab")
			(effects
				(font
					(size 0.7 0.7)
					(thickness 0.15)
				)
				(justify left bottom)
			)
		)
		(property "MPN" ""
			(at 0 0 0)
			(unlocked yes)
			(layer "F.Fab")
			(hide yes)
			(effects
				(font
					(size 1 1)
					(thickness 0.15)
				)
			)
		)
		(property "Manufacturer" ""
			(at 0 0 0)
			(unlocked yes)
			(layer "F.Fab")
			(hide yes)
			(effects
				(font
					(size 1 1)
					(thickness 0.15)
				)
			)
		)
		(property "Author" "Antmicro"
			(at 0 0 0)
			(unlocked yes)
			(layer "F.Fab")
			(hide yes)
			(effects
				(font
					(size 1 1)
					(thickness 0.15)
				)
			)
		)
		(property "License" "Apache-2.0"
			(at 0 0 0)
			(unlocked yes)
			(layer "F.Fab")
			(hide yes)
			(effects
				(font
					(size 1 1)
					(thickness 0.15)
				)
			)
		)
		(sheetname "/USB/")
		(sheetfile "usb.kicad_sch")
		(attr exclude_from_pos_files exclude_from_bom)
		(fp_circle
			(center 0 0)
			(end 0.475 0)
			(stroke
				(width 0.05)
				(type default)
			)
			(fill no)
			(layer "F.CrtYd")
		)
		(fp_text user "${REFERENCE}"
			(at -0.4 2.7 0)
			(layer "F.Fab")
			(effects
				(font
					(size 0.7 0.7)
					(thickness 0.15)
				)
				(justify left bottom)
			)
		)
		(fp_text user "License: Apache-2.0"
			(at -0.4 5.101 0)
			(layer "F.Fab")
			(effects
				(font
					(size 0.7 0.7)
					(thickness 0.15)
				)
				(justify left bottom)
			)
		)
		(fp_text user "Author: Antmicro"
			(at -0.4 3.901 0)
			(layer "F.Fab")
			(effects
				(font
					(size 0.7 0.7)
					(thickness 0.15)
				)
				(justify left bottom)
			)
		)
		(pad "1" smd circle
			(at 0 0)
			(size 0.75 0.75)
			(layers "F.Cu" "F.Mask")
			(net 436 "Net-(U906-OUT1)")
			(pinfunction "1")
			(pintype "passive")
		)
	)
	(footprint "antmicro-footprints:TP_SMD_0.75mm"
		(layer "F.Cu")
		(at 47.58 135.3)
		(property "Reference" "TP402"
			(at -2.96 1.57 0)
			(layer "F.SilkS")
			(effects
				(font
					(size 0.7 0.7)
					(thickness 0.15)
				)
				(justify left bottom)
			)
		)
		(property "Value" "TP_0.75mm_SMD"
			(at 0 1.2 0)
			(layer "F.Fab")
			(effects
				(font
					(size 0.7 0.7)
					(thickness 0.15)
				)
				(justify left bottom)
			)
		)
		(property "MPN" ""
			(at 0 0 0)
			(unlocked yes)
			(layer "F.Fab")
			(hide yes)
			(effects
				(font
					(size 1 1)
					(thickness 0.15)
				)
			)
		)
		(property "Manufacturer" ""
			(at 0 0 0)
			(unlocked yes)
			(layer "F.Fab")
			(hide yes)
			(effects
				(font
					(size 1 1)
					(thickness 0.15)
				)
			)
		)
		(property "Author" "Antmicro"
			(at 0 0 0)
			(unlocked yes)
			(layer "F.Fab")
			(hide yes)
			(effects
				(font
					(size 1 1)
					(thickness 0.15)
				)
			)
		)
		(property "License" "Apache-2.0"
			(at 0 0 0)
			(unlocked yes)
			(layer "F.Fab")
			(hide yes)
			(effects
				(font
					(size 1 1)
					(thickness 0.15)
				)
			)
		)
		(sheetname "/Ethernet/")
		(sheetfile "ethernet.kicad_sch")
		(attr exclude_from_pos_files exclude_from_bom)
		(fp_circle
			(center 0 0)
			(end 0.475 0)
			(stroke
				(width 0.05)
				(type default)
			)
			(fill no)
			(layer "F.CrtYd")
		)
		(fp_text user "${REFERENCE}"
			(at -0.4 2.7 0)
			(layer "F.Fab")
			(effects
				(font
					(size 0.7 0.7)
					(thickness 0.15)
				)
				(justify left bottom)
			)
		)
		(fp_text user "Author: Antmicro"
			(at -0.4 3.901 0)
			(layer "F.Fab")
			(effects
				(font
					(size 0.7 0.7)
					(thickness 0.15)
				)
				(justify left bottom)
			)
		)
		(fp_text user "License: Apache-2.0"
			(at -0.4 5.101 0)
			(layer "F.Fab")
			(effects
				(font
					(size 0.7 0.7)
					(thickness 0.15)
				)
				(justify left bottom)
			)
		)
		(pad "1" smd circle
			(at 0 0)
			(size 0.75 0.75)
			(layers "F.Cu" "F.Mask")
			(net 1 "GNDD")
			(pinfunction "1")
			(pintype "passive")
		)
	)
	(footprint "antmicro-footprints:R_0402_1005Metric"
		(layer "F.Cu")
		(at 75.067962 166.7165)
		(descr "Resistor SMD 0402")
		(tags "resistor SMD 0402")
		(property "Reference" "R803"
			(at -1.45 -1.31 0)
			(layer "F.SilkS")
			(effects
				(font
					(size 0.7 0.7)
					(thickness 0.15)
				)
				(justify left bottom)
			)
		)
		(property "Value" "R_10k_0402"
			(at -1.011843 1.772047 0)
			(layer "F.Fab")
			(effects
				(font
					(size 0.7 0.7)
					(thickness 0.15)
				)
				(justify left bottom)
			)
		)
		(property "Datasheet" "https://www.bourns.com/docs/product-datasheets/cr.pdf"
			(at 0 0 0)
			(layer "F.Fab")
			(hide yes)
			(effects
				(font
					(size 1.27 1.27)
					(thickness 0.15)
				)
			)
		)
		(property "MPN" "CR0402-FX-1002GLF"
			(at 0 0 0)
			(unlocked yes)
			(layer "F.Fab")
			(hide yes)
			(effects
				(font
					(size 1 1)
					(thickness 0.15)
				)
			)
		)
		(property "Manufacturer" "Bourns"
			(at 0 0 0)
			(unlocked yes)
			(layer "F.Fab")
			(hide yes)
			(effects
				(font
					(size 1 1)
					(thickness 0.15)
				)
			)
		)
		(property "License" "Apache-2.0"
			(at 0 0 0)
			(unlocked yes)
			(layer "F.Fab")
			(hide yes)
			(effects
				(font
					(size 1 1)
					(thickness 0.15)
				)
			)
		)
		(property "Author" "Antmicro"
			(at 0 0 0)
			(unlocked yes)
			(layer "F.Fab")
			(hide yes)
			(effects
				(font
					(size 1 1)
					(thickness 0.15)
				)
			)
		)
		(property "Val" "10k"
			(at 0 0 0)
			(unlocked yes)
			(layer "F.Fab")
			(hide yes)
			(effects
				(font
					(size 1 1)
					(thickness 0.15)
				)
			)
		)
		(property "Tolerance" "1%"
			(at 0 0 0)
			(unlocked yes)
			(layer "F.Fab")
			(hide yes)
			(effects
				(font
					(size 1 1)
					(thickness 0.15)
				)
			)
		)
		(sheetname "/Peripherals/")
		(sheetfile "peripherals.kicad_sch")
		(attr smd exclude_from_pos_files exclude_from_bom dnp)
		(fp_rect
			(start -0.925 -0.47)
			(end 0.925 0.47)
			(stroke
				(width 0.05)
				(type default)
			)
			(fill no)
			(layer "F.CrtYd")
		)
		(fp_rect
			(start -0.5 -0.25)
			(end 0.5 0.25)
			(stroke
				(width 0.15)
				(type solid)
			)
			(fill no)
			(layer "F.Fab")
		)
		(fp_text user "License: Apache-2.0"
			(at -0.95 5.169 0)
			(layer "F.Fab")
			(effects
				(font
					(size 0.7 0.7)
					(thickness 0.15)
				)
				(justify left bottom)
			)
		)
		(fp_text user "Author: Antmicro"
			(at -0.95 4.169 0)
			(layer "F.Fab")
			(effects
				(font
					(size 0.7 0.7)
					(thickness 0.15)
				)
				(justify left bottom)
			)
		)
		(fp_text user "${REFERENCE}"
			(at -0.95 3.168 0)
			(layer "F.Fab")
			(effects
				(font
					(size 0.7 0.7)
					(thickness 0.15)
				)
				(justify left bottom)
			)
		)
		(pad "1" smd roundrect
			(at -0.48 0)
			(size 0.59 0.64)
			(layers "F.Cu" "F.Mask" "F.Paste")
			(roundrect_rratio 0.25)
			(net 374 "Net-(U801-I2C_ADR0)")
			(pintype "passive")
		)
		(pad "2" smd roundrect
			(at 0.48 0)
			(size 0.59 0.64)
			(layers "F.Cu" "F.Mask" "F.Paste")
			(roundrect_rratio 0.25)
			(net 9 "+3V3")
			(pintype "passive")
		)
	)
	(footprint "antmicro-footprints:SOT-23-3"
		(layer "F.Cu")
		(at 107.492962 152.692)
		(property "Reference" "Q202"
			(at 0.775 -0.667 0)
			(layer "F.SilkS")
			(effects
				(font
					(size 0.7 0.7)
					(thickness 0.15)
				)
				(justify left bottom)
			)
		)
		(property "Value" "SSM3J332R"
			(at -1.9 2.7 0)
			(layer "F.Fab")
			(effects
				(font
					(size 0.7 0.7)
					(thickness 0.15)
				)
				(justify left bottom)
			)
		)
		(property "Datasheet" "https://www.mouser.com/datasheet/2/408/SSM3J332R_datasheet_en_20181015-1150575.pdf"
			(at 0 0 0)
			(layer "F.Fab")
			(hide yes)
			(effects
				(font
					(size 1.27 1.27)
					(thickness 0.15)
				)
			)
		)
		(property "MPN" "SSM3J332R,LF"
			(at 0 0 0)
			(unlocked yes)
			(layer "F.Fab")
			(hide yes)
			(effects
				(font
					(size 1 1)
					(thickness 0.15)
				)
			)
		)
		(property "Manufacturer" "Toshiba"
			(at 0 0 0)
			(unlocked yes)
			(layer "F.Fab")
			(hide yes)
			(effects
				(font
					(size 1 1)
					(thickness 0.15)
				)
			)
		)
		(property "Author" "Antmicro"
			(at 0 0 0)
			(unlocked yes)
			(layer "F.Fab")
			(hide yes)
			(effects
				(font
					(size 1 1)
					(thickness 0.15)
				)
			)
		)
		(property "License" "Apache-2.0"
			(at 0 0 0)
			(unlocked yes)
			(layer "F.Fab")
			(hide yes)
			(effects
				(font
					(size 1 1)
					(thickness 0.15)
				)
			)
		)
		(sheetname "/Compute module/")
		(sheetfile "compute-module.kicad_sch")
		(attr smd)
		(fp_line
			(start -1.45 -1.35)
			(end -0.85 -1.35)
			(stroke
				(width 0.15)
				(type solid)
			)
			(layer "F.SilkS")
		)
		(fp_line
			(start -0.85 -1.35)
			(end -0.7 -1.5)
			(stroke
				(width 0.15)
				(type solid)
			)
			(layer "F.SilkS")
		)
		(fp_line
			(start -0.7 1.5)
			(end -0.7 1.35)
			(stroke
				(width 0.15)
				(type solid)
			)
			(layer "F.SilkS")
		)
		(fp_line
			(start 0.7 -1.5)
			(end -0.7 -1.5)
			(stroke
				(width 0.15)
				(type solid)
			)
			(layer "F.SilkS")
		)
		(fp_line
			(start 0.7 -0.4)
			(end 0.7 -1.5)
			(stroke
				(width 0.15)
				(type solid)
			)
			(layer "F.SilkS")
		)
		(fp_line
			(start 0.7 0.4)
			(end 0.7 1.5)
			(stroke
				(width 0.15)
				(type solid)
			)
			(layer "F.SilkS")
		)
		(fp_line
			(start 0.7 1.5)
			(end -0.7 1.5)
			(stroke
				(width 0.15)
				(type solid)
			)
			(layer "F.SilkS")
		)
		(fp_line
			(start -1.75 -0.5)
			(end -1.75 -1.4)
			(stroke
				(width 0.05)
				(type solid)
			)
			(layer "F.CrtYd")
		)
		(fp_line
			(start -1.75 0.5)
			(end -0.85 0.5)
			(stroke
				(width 0.05)
				(type solid)
			)
			(layer "F.CrtYd")
		)
		(fp_line
			(start -1.75 1.4)
			(end -1.75 0.5)
			(stroke
				(width 0.05)
				(type solid)
			)
			(layer "F.CrtYd")
		)
		(fp_line
			(start -0.9 -1.6)
			(end -0.9 -1.4)
			(stroke
				(width 0.05)
				(type solid)
			)
			(layer "F.CrtYd")
		)
		(fp_line
			(start -0.9 -1.6)
			(end 0.825 -1.6)
			(stroke
				(width 0.05)
				(type solid)
			)
			(layer "F.CrtYd")
		)
		(fp_line
			(start -0.9 -1.4)
			(end -1.75 -1.4)
			(stroke
				(width 0.05)
				(type solid)
			)
			(layer "F.CrtYd")
		)
		(fp_line
			(start -0.85 -0.5)
			(end -1.75 -0.5)
			(stroke
				(width 0.05)
				(type solid)
			)
			(layer "F.CrtYd")
		)
		(fp_line
			(start -0.85 0.5)
			(end -0.85 -0.5)
			(stroke
				(width 0.05)
				(type solid)
			)
			(layer "F.CrtYd")
		)
		(fp_line
			(start -0.85 1.4)
			(end -1.75 1.4)
			(stroke
				(width 0.05)
				(type solid)
			)
			(layer "F.CrtYd")
		)
		(fp_line
			(start -0.85 1.65)
			(end -0.85 1.4)
			(stroke
				(width 0.05)
				(type solid)
			)
			(layer "F.CrtYd")
		)
		(fp_line
			(start 0.825 -1.6)
			(end 0.825 -0.45)
			(stroke
				(width 0.05)
				(type solid)
			)
			(layer "F.CrtYd")
		)
		(fp_line
			(start 0.825 -0.45)
			(end 1.75 -0.45)
			(stroke
				(width 0.05)
				(type solid)
			)
			(layer "F.CrtYd")
		)
		(fp_line
			(start 0.85 0.45)
			(end 0.85 1.65)
			(stroke
				(width 0.05)
				(type solid)
			)
			(layer "F.CrtYd")
		)
		(fp_line
			(start 0.85 1.65)
			(end -0.85 1.65)
			(stroke
				(width 0.05)
				(type solid)
			)
			(layer "F.CrtYd")
		)
		(fp_line
			(start 1.75 -0.45)
			(end 1.75 0.45)
			(stroke
				(width 0.05)
				(type solid)
			)
			(layer "F.CrtYd")
		)
		(fp_line
			(start 1.75 0.45)
			(end 0.85 0.45)
			(stroke
				(width 0.05)
				(type solid)
			)
			(layer "F.CrtYd")
		)
		(fp_line
			(start -0.712 -1.325)
			(end -0.712 1.523)
			(stroke
				(width 0.15)
				(type solid)
			)
			(layer "F.Fab")
		)
		(fp_line
			(start -0.712 1.519)
			(end 0.688 1.519)
			(stroke
				(width 0.15)
				(type solid)
			)
			(layer "F.Fab")
		)
		(fp_line
			(start -0.437 -1.526)
			(end -0.712 -1.325)
			(stroke
				(width 0.15)
				(type solid)
			)
			(layer "F.Fab")
		)
		(fp_line
			(start -0.437 -1.526)
			(end 0.688 -1.526)
			(stroke
				(width 0.15)
				(type solid)
			)
			(layer "F.Fab")
		)
		(fp_line
			(start 0.688 1.519)
			(end 0.688 -1.52)
			(stroke
				(width 0.15)
				(type solid)
			)
			(layer "F.Fab")
		)
		(fp_text user "License: Apache-2.0"
			(at -1.8 6.8 0)
			(layer "F.Fab")
			(effects
				(font
					(size 0.7 0.7)
					(thickness 0.15)
				)
				(justify left bottom)
			)
		)
		(fp_text user "Author: Antmicro"
			(at -1.837 5.3 0)
			(layer "F.Fab")
			(effects
				(font
					(size 0.7 0.7)
					(thickness 0.15)
				)
				(justify left bottom)
			)
		)
		(fp_text user "${REFERENCE}"
			(at -1.837 4 0)
			(layer "F.Fab")
			(effects
				(font
					(size 0.7 0.7)
					(thickness 0.15)
				)
				(justify left bottom)
			)
		)
		(pad "1" smd roundrect
			(at -1.1 -0.951)
			(size 1 0.6)
			(layers "F.Cu" "F.Mask" "F.Paste")
			(roundrect_rratio 0.15)
			(net 327 "Net-(Q201-D)")
			(pinfunction "G")
			(pintype "input")
		)
		(pad "2" smd roundrect
			(at -1.1 0.949)
			(size 1 0.6)
			(layers "F.Cu" "F.Mask" "F.Paste")
			(roundrect_rratio 0.15)
			(net 10 "+5V")
			(pinfunction "S")
			(pintype "passive")
		)
		(pad "3" smd roundrect
			(at 1.1 -0.0005)
			(size 1 0.6)
			(layers "F.Cu" "F.Mask" "F.Paste")
			(roundrect_rratio 0.15)
			(net 257 "/Compute module/Pf_5V.HPD")
			(pinfunction "D")
			(pintype "passive")
		)
	)
	(footprint "antmicro-footprints:Vishay_PowerPAK_1212-8_Single"
		(layer "F.Cu")
		(at 75.342962 129.6915 -90)
		(descr "PowerPAK 1212-8 Single")
		(tags "Vishay PowerPAK 1212-8 Single")
		(property "Reference" "Q902"
			(at -1.95 -1.4 0)
			(layer "F.SilkS")
			(effects
				(font
					(size 0.7 0.7)
					(thickness 0.15)
				)
				(justify right bottom)
			)
		)
		(property "Value" "SQS401EN-T1_BE3"
			(at 0 2.7 90)
			(layer "F.Fab")
			(effects
				(font
					(size 0.7 0.7)
					(thickness 0.15)
				)
				(justify right bottom)
			)
		)
		(property "Datasheet" "https://www.vishay.com/docs/65529/sqs401en.pdf"
			(at 0 0 270)
			(layer "F.Fab")
			(hide yes)
			(effects
				(font
					(size 1.27 1.27)
					(thickness 0.15)
				)
			)
		)
		(property "MPN" "SQS401EN-T1_BE3"
			(at 0 0 270)
			(unlocked yes)
			(layer "F.Fab")
			(hide yes)
			(effects
				(font
					(size 1 1)
					(thickness 0.15)
				)
			)
		)
		(property "Manufacturer" "Vishay"
			(at 0 0 270)
			(unlocked yes)
			(layer "F.Fab")
			(hide yes)
			(effects
				(font
					(size 1 1)
					(thickness 0.15)
				)
			)
		)
		(property "Author" "Antmicro"
			(at 0 0 270)
			(unlocked yes)
			(layer "F.Fab")
			(hide yes)
			(effects
				(font
					(size 1 1)
					(thickness 0.15)
				)
			)
		)
		(property "License" "Apache-2.0"
			(at 0 0 270)
			(unlocked yes)
			(layer "F.Fab")
			(hide yes)
			(effects
				(font
					(size 1 1)
					(thickness 0.15)
				)
			)
		)
		(sheetname "/USB/")
		(sheetfile "usb.kicad_sch")
		(attr smd)
		(fp_line
			(start -1.635 1.634)
			(end 1.634 1.634)
			(stroke
				(width 0.15)
				(type solid)
			)
			(layer "F.SilkS")
		)
		(fp_line
			(start -1.635 1.3)
			(end -1.635 1.634)
			(stroke
				(width 0.15)
				(type solid)
			)
			(layer "F.SilkS")
		)
		(fp_line
			(start 1.634 1.3)
			(end 1.634 1.634)
			(stroke
				(width 0.15)
				(type solid)
			)
			(layer "F.SilkS")
		)
		(fp_line
			(start -1.651 -1.651)
			(end -1.651 -1.317)
			(stroke
				(width 0.15)
				(type solid)
			)
			(layer "F.SilkS")
		)
		(fp_line
			(start -1.651 -1.651)
			(end 1.648 -1.651)
			(stroke
				(width 0.15)
				(type solid)
			)
			(layer "F.SilkS")
		)
		(fp_line
			(start 1.648 -1.651)
			(end 1.648 -1.317)
			(stroke
				(width 0.15)
				(type solid)
			)
			(layer "F.SilkS")
		)
		(fp_circle
			(center -1.9 -1.4)
			(end -1.85 -1.4)
			(stroke
				(width 0.15)
				(type solid)
			)
			(fill yes)
			(layer "F.SilkS")
		)
		(fp_rect
			(start -2 -1.8)
			(end 2 1.798)
			(stroke
				(width 0.05)
				(type solid)
			)
			(fill no)
			(layer "F.CrtYd")
		)
		(fp_line
			(start -1.6425 -1.4175)
			(end -1.4175 -1.6425)
			(stroke
				(width 0.15)
				(type solid)
			)
			(layer "F.Fab")
		)
		(fp_rect
			(start -1.651 -1.651)
			(end 1.648 1.648)
			(stroke
				(width 0.15)
				(type solid)
			)
			(fill no)
			(layer "F.Fab")
		)
		(fp_text user "Author: Antmicro"
			(at -8 5.9 270)
			(layer "F.Fab")
			(effects
				(font
					(size 0.7 0.7)
					(thickness 0.15)
				)
				(justify left bottom)
			)
		)
		(fp_text user "${REFERENCE}"
			(at -8 4.7 270)
			(layer "F.Fab")
			(effects
				(font
					(size 0.7 0.7)
					(thickness 0.15)
				)
				(justify left bottom)
			)
		)
		(fp_text user "License: Apache-2.0"
			(at -8 7.1 270)
			(layer "F.Fab")
			(effects
				(font
					(size 0.7 0.7)
					(thickness 0.15)
				)
				(justify left bottom)
			)
		)
		(pad "1" smd rect
			(at -1.436 -0.99 270)
			(size 0.99 0.405)
			(layers "F.Cu" "F.Mask" "F.Paste")
			(net 26 "/USB/USBD_VBUS")
			(pinfunction "S")
			(pintype "passive")
		)
		(pad "2" smd rect
			(at -1.436 -0.332 270)
			(size 0.99 0.405)
			(layers "F.Cu" "F.Mask" "F.Paste")
			(net 26 "/USB/USBD_VBUS")
			(pinfunction "S")
			(pintype "passive")
		)
		(pad "3" smd rect
			(at -1.436 0.33 270)
			(size 0.99 0.405)
			(layers "F.Cu" "F.Mask" "F.Paste")
			(net 26 "/USB/USBD_VBUS")
			(pinfunction "S")
			(pintype "passive")
		)
		(pad "4" smd rect
			(at -1.436 0.988 270)
			(size 0.99 0.405)
			(layers "F.Cu" "F.Mask" "F.Paste")
			(net 341 "Net-(Q902-G)")
			(pinfunction "G")
			(pintype "input")
		)
		(pad "5" smd custom
			(at 0.557 0 270)
			(size 1.725 2.235)
			(layers "F.Cu" "F.Mask" "F.Paste")
			(net 443 "/Supply/V_{BUS}")
			(pinfunction "D")
			(pintype "passive")
			(zone_connect 2)
			(options
				(clearance outline)
				(anchor rect)
			)
			(primitives
				(gr_poly
					(pts
						(xy 0.8625 0.1275) (xy 0.8625 -0.1275) (xy 1.3725 -0.1275) (xy 1.3725 -0.5325) (xy 0.8625 -0.5325)
						(xy 0.8625 -0.7875) (xy 1.3725 -0.7875) (xy 1.3725 -1.195) (xy 0.6125 -1.195) (xy 0.6125 1.195)
						(xy 1.3725 1.195) (xy 1.3725 0.7875) (xy 0.8625 0.7875) (xy 0.8625 0.5325) (xy 1.3725 0.5325)
						(xy 1.3725 0.1275)
					)
					(width 0)
					(fill yes)
				)
			)
		)
	)
	(footprint "antmicro-footprints:Nexperia_DFN-10_2.5x1mm_P0.5mm"
		(layer "F.Cu")
		(at 79.530962 121.3665)
		(property "Reference" "D902"
			(at -1.443 1.61 0)
			(layer "F.SilkS")
			(effects
				(font
					(size 0.7 0.7)
					(thickness 0.15)
				)
				(justify left bottom)
			)
		)
		(property "Value" "PUSB3F96X_PASS"
			(at -0.016 1.705 0)
			(layer "F.Fab")
			(effects
				(font
					(size 0.7 0.7)
					(thickness 0.15)
				)
				(justify left bottom)
			)
		)
		(property "Datasheet" "https://mouser.com/datasheet/2/916/PUSB3F96-1600324.pdf"
			(at 0 0 0)
			(layer "F.Fab")
			(hide yes)
			(effects
				(font
					(size 1.27 1.27)
					(thickness 0.15)
				)
			)
		)
		(property "Manufacturer" "Nexperia"
			(at 0 0 0)
			(unlocked yes)
			(layer "F.Fab")
			(hide yes)
			(effects
				(font
					(size 1 1)
					(thickness 0.15)
				)
			)
		)
		(property "MPN" "PUSB3F96X"
			(at 0 0 0)
			(unlocked yes)
			(layer "F.Fab")
			(hide yes)
			(effects
				(font
					(size 1 1)
					(thickness 0.15)
				)
			)
		)
		(property "Author" "Antmicro"
			(at 0 0 0)
			(unlocked yes)
			(layer "F.Fab")
			(hide yes)
			(effects
				(font
					(size 1 1)
					(thickness 0.15)
				)
			)
		)
		(property "License" "Apache-2.0"
			(at 0 0 0)
			(unlocked yes)
			(layer "F.Fab")
			(hide yes)
			(effects
				(font
					(size 1 1)
					(thickness 0.15)
				)
			)
		)
		(sheetname "/USB/")
		(sheetfile "usb.kicad_sch")
		(attr smd)
		(fp_line
			(start -1.375 -0.4)
			(end -1.375 0.4)
			(stroke
				(width 0.15)
				(type solid)
			)
			(layer "F.SilkS")
		)
		(fp_line
			(start 1.375 0.4)
			(end 1.375 -0.4)
			(stroke
				(width 0.15)
				(type solid)
			)
			(layer "F.SilkS")
		)
		(fp_circle
			(center -1.4 0.7)
			(end -1.349 0.7)
			(stroke
				(width 0.15)
				(type solid)
			)
			(fill yes)
			(layer "F.SilkS")
		)
		(fp_rect
			(start -1.4 -0.725)
			(end 1.4 0.725)
			(stroke
				(width 0.05)
				(type solid)
			)
			(fill no)
			(layer "F.CrtYd")
		)
		(fp_line
			(start -1.25 -0.5)
			(end -1.25 0.15)
			(stroke
				(width 0.15)
				(type solid)
			)
			(layer "F.Fab")
		)
		(fp_line
			(start -1.25 0.15)
			(end -0.9 0.5)
			(stroke
				(width 0.15)
				(type solid)
			)
			(layer "F.Fab")
		)
		(fp_line
			(start -0.9 0.5)
			(end 1.25 0.5)
			(stroke
				(width 0.15)
				(type solid)
			)
			(layer "F.Fab")
		)
		(fp_line
			(start 1.25 -0.5)
			(end -1.25 -0.5)
			(stroke
				(width 0.15)
				(type solid)
			)
			(layer "F.Fab")
		)
		(fp_line
			(start 1.25 0.5)
			(end 1.25 -0.5)
			(stroke
				(width 0.15)
				(type solid)
			)
			(layer "F.Fab")
		)
		(fp_text user "License: Apache-2.0"
			(at -1.367 6.105 0)
			(layer "F.Fab")
			(effects
				(font
					(size 0.7 0.7)
					(thickness 0.15)
				)
				(justify left bottom)
			)
		)
		(fp_text user "Author: Antmicro"
			(at -1.367 4.905 0)
			(layer "F.Fab")
			(effects
				(font
					(size 0.7 0.7)
					(thickness 0.15)
				)
				(justify left bottom)
			)
		)
		(fp_text user "${REFERENCE}"
			(at -1.367 3.704 0)
			(layer "F.Fab")
			(effects
				(font
					(size 0.7 0.7)
					(thickness 0.15)
				)
				(justify left bottom)
			)
		)
		(pad "1" smd rect
			(at -1 0.3875)
			(size 0.2 0.475)
			(layers "F.Cu" "F.Mask" "F.Paste")
			(net 207 "/USB/USBD_CC1")
			(pinfunction "CH1")
			(pintype "passive")
			(solder_mask_margin 0.05)
		)
		(pad "2" smd rect
			(at -0.5 0.3875)
			(size 0.2 0.475)
			(layers "F.Cu" "F.Mask" "F.Paste")
			(net 208 "/USB/USBD_CC2")
			(pinfunction "CH2")
			(pintype "passive")
			(solder_mask_margin 0.05)
		)
		(pad "3" smd rect
			(at 0 0.3875)
			(size 0.2 0.475)
			(layers "F.Cu" "F.Mask" "F.Paste")
			(net 3 "GND")
			(pinfunction "GND")
			(pintype "passive")
			(solder_mask_margin 0.05)
		)
		(pad "4" smd rect
			(at 0.5 0.3875)
			(size 0.2 0.475)
			(layers "F.Cu" "F.Mask" "F.Paste")
			(net 209 "/USB/DD_P")
			(pinfunction "CH3")
			(pintype "passive")
			(solder_mask_margin 0.05)
		)
		(pad "5" smd rect
			(at 1 0.3875)
			(size 0.2 0.475)
			(layers "F.Cu" "F.Mask" "F.Paste")
			(net 210 "/USB/DD_N")
			(pinfunction "CH4")
			(pintype "passive")
			(solder_mask_margin 0.05)
		)
		(pad "6" smd rect
			(at 1 -0.3875)
			(size 0.2 0.475)
			(layers "F.Cu" "F.Mask" "F.Paste")
			(net 210 "/USB/DD_N")
			(pinfunction "CH4")
			(pintype "passive")
			(solder_mask_margin 0.05)
		)
		(pad "7" smd rect
			(at 0.5 -0.3875)
			(size 0.2 0.475)
			(layers "F.Cu" "F.Mask" "F.Paste")
			(net 209 "/USB/DD_P")
			(pinfunction "CH3")
			(pintype "passive")
			(solder_mask_margin 0.05)
		)
		(pad "8" smd rect
			(at 0 -0.3875)
			(size 0.2 0.475)
			(layers "F.Cu" "F.Mask" "F.Paste")
			(net 3 "GND")
			(pinfunction "GND")
			(pintype "passive")
			(solder_mask_margin 0.05)
		)
		(pad "9" smd rect
			(at -0.501 -0.3875)
			(size 0.2 0.475)
			(layers "F.Cu" "F.Mask" "F.Paste")
			(net 208 "/USB/USBD_CC2")
			(pinfunction "CH2")
			(pintype "passive")
			(solder_mask_margin 0.05)
		)
		(pad "10" smd rect
			(at -1 -0.3875)
			(size 0.2 0.475)
			(layers "F.Cu" "F.Mask" "F.Paste")
			(net 207 "/USB/USBD_CC1")
			(pinfunction "CH1")
			(pintype "passive")
			(solder_mask_margin 0.05)
		)
	)
	(footprint "antmicro-footprints:R_0402_1005Metric"
		(layer "F.Cu")
		(at 46.542962 131.7165)
		(descr "Resistor SMD 0402")
		(tags "resistor SMD 0402")
		(property "Reference" "R401"
			(at -3.975 0.475 0)
			(layer "F.SilkS")
			(effects
				(font
					(size 0.7 0.7)
					(thickness 0.15)
				)
				(justify left bottom)
			)
		)
		(property "Value" "R_1k3_0402"
			(at -1.011843 1.772047 0)
			(layer "F.Fab")
			(effects
				(font
					(size 0.7 0.7)
					(thickness 0.15)
				)
				(justify left bottom)
			)
		)
		(property "Datasheet" "https://www.bourns.com/docs/product-datasheets/cr.pdf"
			(at 0 0 0)
			(layer "F.Fab")
			(hide yes)
			(effects
				(font
					(size 1.27 1.27)
					(thickness 0.15)
				)
			)
		)
		(property "Manufacturer" "Bourns"
			(at 0 0 0)
			(unlocked yes)
			(layer "F.Fab")
			(hide yes)
			(effects
				(font
					(size 1 1)
					(thickness 0.15)
				)
			)
		)
		(property "MPN" "CR0402-FX-1301GLF"
			(at 0 0 0)
			(unlocked yes)
			(layer "F.Fab")
			(hide yes)
			(effects
				(font
					(size 1 1)
					(thickness 0.15)
				)
			)
		)
		(property "Val" "1k3"
			(at 0 0 0)
			(unlocked yes)
			(layer "F.Fab")
			(hide yes)
			(effects
				(font
					(size 1 1)
					(thickness 0.15)
				)
			)
		)
		(property "License" "Apache-2.0"
			(at 0 0 0)
			(unlocked yes)
			(layer "F.Fab")
			(hide yes)
			(effects
				(font
					(size 1 1)
					(thickness 0.15)
				)
			)
		)
		(property "Author" "Antmicro"
			(at 0 0 0)
			(unlocked yes)
			(layer "F.Fab")
			(hide yes)
			(effects
				(font
					(size 1 1)
					(thickness 0.15)
				)
			)
		)
		(property "Tolerance" "1%"
			(at 0 0 0)
			(unlocked yes)
			(layer "F.Fab")
			(hide yes)
			(effects
				(font
					(size 1 1)
					(thickness 0.15)
				)
			)
		)
		(sheetname "/Ethernet/")
		(sheetfile "ethernet.kicad_sch")
		(attr smd)
		(fp_rect
			(start -0.925 -0.47)
			(end 0.925 0.47)
			(stroke
				(width 0.05)
				(type default)
			)
			(fill no)
			(layer "F.CrtYd")
		)
		(fp_rect
			(start -0.5 -0.25)
			(end 0.5 0.25)
			(stroke
				(width 0.15)
				(type solid)
			)
			(fill no)
			(layer "F.Fab")
		)
		(fp_text user "Author: Antmicro"
			(at -0.95 4.169 0)
			(layer "F.Fab")
			(effects
				(font
					(size 0.7 0.7)
					(thickness 0.15)
				)
				(justify left bottom)
			)
		)
		(fp_text user "License: Apache-2.0"
			(at -0.95 5.169 0)
			(layer "F.Fab")
			(effects
				(font
					(size 0.7 0.7)
					(thickness 0.15)
				)
				(justify left bottom)
			)
		)
		(fp_text user "${REFERENCE}"
			(at -0.95 3.168 0)
			(layer "F.Fab")
			(effects
				(font
					(size 0.7 0.7)
					(thickness 0.15)
				)
				(justify left bottom)
			)
		)
		(pad "1" smd roundrect
			(at -0.48 0)
			(size 0.59 0.64)
			(layers "F.Cu" "F.Mask" "F.Paste")
			(roundrect_rratio 0.25)
			(net 90 "/Ethernet/VSS")
			(pintype "passive")
		)
		(pad "2" smd roundrect
			(at 0.48 0)
			(size 0.59 0.64)
			(layers "F.Cu" "F.Mask" "F.Paste")
			(roundrect_rratio 0.25)
			(net 356 "/Ethernet/AMPS_CTL")
			(pintype "passive")
		)
	)
	(footprint "antmicro-footprints:TP_SMD_0.75mm"
		(layer "F.Cu")
		(at 134.787962 156.1165 -90)
		(property "Reference" "TP601"
			(at -3.8415 -1.062038 90)
			(layer "F.SilkS")
			(effects
				(font
					(size 0.7 0.7)
					(thickness 0.15)
				)
				(justify right bottom)
			)
		)
		(property "Value" "TP_0.75mm_SMD"
			(at 0 1.2 90)
			(layer "F.Fab")
			(effects
				(font
					(size 0.7 0.7)
					(thickness 0.15)
				)
				(justify right bottom)
			)
		)
		(property "MPN" ""
			(at 0 0 270)
			(unlocked yes)
			(layer "F.Fab")
			(hide yes)
			(effects
				(font
					(size 1 1)
					(thickness 0.15)
				)
			)
		)
		(property "Manufacturer" ""
			(at 0 0 270)
			(unlocked yes)
			(layer "F.Fab")
			(hide yes)
			(effects
				(font
					(size 1 1)
					(thickness 0.15)
				)
			)
		)
		(property "Author" "Antmicro"
			(at 0 0 270)
			(unlocked yes)
			(layer "F.Fab")
			(hide yes)
			(effects
				(font
					(size 1 1)
					(thickness 0.15)
				)
			)
		)
		(property "License" "Apache-2.0"
			(at 0 0 270)
			(unlocked yes)
			(layer "F.Fab")
			(hide yes)
			(effects
				(font
					(size 1 1)
					(thickness 0.15)
				)
			)
		)
		(sheetname "/CSI/")
		(sheetfile "csi.kicad_sch")
		(attr exclude_from_pos_files exclude_from_bom)
		(fp_circle
			(center 0 0)
			(end 0.475 0)
			(stroke
				(width 0.05)
				(type default)
			)
			(fill no)
			(layer "F.CrtYd")
		)
		(fp_text user "Author: Antmicro"
			(at -0.4 3.901 270)
			(layer "F.Fab")
			(effects
				(font
					(size 0.7 0.7)
					(thickness 0.15)
				)
				(justify left bottom)
			)
		)
		(fp_text user "${REFERENCE}"
			(at -0.4 2.7 270)
			(layer "F.Fab")
			(effects
				(font
					(size 0.7 0.7)
					(thickness 0.15)
				)
				(justify left bottom)
			)
		)
		(fp_text user "License: Apache-2.0"
			(at -0.4 5.101 270)
			(layer "F.Fab")
			(effects
				(font
					(size 0.7 0.7)
					(thickness 0.15)
				)
				(justify left bottom)
			)
		)
		(pad "1" smd circle
			(at 0 0 270)
			(size 0.75 0.75)
			(layers "F.Cu" "F.Mask")
			(net 370 "Net-(U601-FLG)")
			(pinfunction "1")
			(pintype "passive")
		)
	)
	(footprint "antmicro-footprints:TP_SMD_0.75mm"
		(layer "F.Cu")
		(at 74.2 154.99)
		(property "Reference" "TP302"
			(at -6.8392 0.87 0)
			(layer "F.SilkS")
			(effects
				(font
					(size 0.7 0.7)
					(thickness 0.15)
				)
				(justify left bottom)
			)
		)
		(property "Value" "TP_0.75mm_SMD"
			(at 0 1.2 0)
			(layer "F.Fab")
			(effects
				(font
					(size 0.7 0.7)
					(thickness 0.15)
				)
				(justify left bottom)
			)
		)
		(property "MPN" ""
			(at 0 0 0)
			(unlocked yes)
			(layer "F.Fab")
			(hide yes)
			(effects
				(font
					(size 1 1)
					(thickness 0.15)
				)
			)
		)
		(property "Manufacturer" ""
			(at 0 0 0)
			(unlocked yes)
			(layer "F.Fab")
			(hide yes)
			(effects
				(font
					(size 1 1)
					(thickness 0.15)
				)
			)
		)
		(property "Author" "Antmicro"
			(at 0 0 0)
			(unlocked yes)
			(layer "F.Fab")
			(hide yes)
			(effects
				(font
					(size 1 1)
					(thickness 0.15)
				)
			)
		)
		(property "License" "Apache-2.0"
			(at 0 0 0)
			(unlocked yes)
			(layer "F.Fab")
			(hide yes)
			(effects
				(font
					(size 1 1)
					(thickness 0.15)
				)
			)
		)
		(sheetname "/Supply/")
		(sheetfile "supply.kicad_sch")
		(attr exclude_from_pos_files exclude_from_bom)
		(fp_circle
			(center 0 0)
			(end 0.475 0)
			(stroke
				(width 0.05)
				(type default)
			)
			(fill no)
			(layer "F.CrtYd")
		)
		(fp_text user "${REFERENCE}"
			(at -0.4 2.7 0)
			(layer "F.Fab")
			(effects
				(font
					(size 0.7 0.7)
					(thickness 0.15)
				)
				(justify left bottom)
			)
		)
		(fp_text user "License: Apache-2.0"
			(at -0.4 5.101 0)
			(layer "F.Fab")
			(effects
				(font
					(size 0.7 0.7)
					(thickness 0.15)
				)
				(justify left bottom)
			)
		)
		(fp_text user "Author: Antmicro"
			(at -0.4 3.901 0)
			(layer "F.Fab")
			(effects
				(font
					(size 0.7 0.7)
					(thickness 0.15)
				)
				(justify left bottom)
			)
		)
		(pad "1" smd circle
			(at 0 0)
			(size 0.75 0.75)
			(layers "F.Cu" "F.Mask")
			(net 3 "GND")
			(pinfunction "1")
			(pintype "passive")
		)
	)
	(footprint "antmicro-footprints:SOT-523"
		(layer "F.Cu")
		(at 82.117962 169.5415 90)
		(property "Reference" "Q209"
			(at -0.735 1.24 180)
			(layer "F.SilkS")
			(effects
				(font
					(size 0.7 0.7)
					(thickness 0.15)
				)
				(justify left bottom)
			)
		)
		(property "Value" "PJE138K"
			(at 0.1 1.824 90)
			(layer "F.Fab")
			(effects
				(font
					(size 0.7 0.7)
					(thickness 0.15)
				)
				(justify left bottom)
			)
		)
		(property "Datasheet" "https://www.mouser.com/datasheet/2/1057/PJE138K-1876698.pdf"
			(at 0 0 90)
			(layer "F.Fab")
			(hide yes)
			(effects
				(font
					(size 1.27 1.27)
					(thickness 0.15)
				)
			)
		)
		(property "MPN" "PJE138K_R1_00001"
			(at 0 0 90)
			(unlocked yes)
			(layer "F.Fab")
			(hide yes)
			(effects
				(font
					(size 1 1)
					(thickness 0.15)
				)
			)
		)
		(property "Manufacturer" "PANJIT"
			(at 0 0 90)
			(unlocked yes)
			(layer "F.Fab")
			(hide yes)
			(effects
				(font
					(size 1 1)
					(thickness 0.15)
				)
			)
		)
		(property "Author" "Antmicro"
			(at 0 0 90)
			(unlocked yes)
			(layer "F.Fab")
			(hide yes)
			(effects
				(font
					(size 1 1)
					(thickness 0.15)
				)
			)
		)
		(property "License" "Apache-2.0"
			(at 0 0 90)
			(unlocked yes)
			(layer "F.Fab")
			(hide yes)
			(effects
				(font
					(size 1 1)
					(thickness 0.15)
				)
			)
		)
		(sheetname "/Compute module/")
		(sheetfile "compute-module.kicad_sch")
		(attr smd)
		(fp_line
			(start -0.277 -0.551)
			(end -0.277 -0.75)
			(stroke
				(width 0.15)
				(type solid)
			)
			(layer "F.SilkS")
		)
		(fp_line
			(start -0.725 -0.551)
			(end -0.277 -0.551)
			(stroke
				(width 0.15)
				(type solid)
			)
			(layer "F.SilkS")
		)
		(fp_line
			(start -0.927 -0.351)
			(end -0.725 -0.551)
			(stroke
				(width 0.15)
				(type solid)
			)
			(layer "F.SilkS")
		)
		(fp_line
			(start -0.927 -0.051)
			(end -0.927 -0.351)
			(stroke
				(width 0.15)
				(type solid)
			)
			(layer "F.SilkS")
		)
		(fp_circle
			(center -0.9652 0.9652)
			(end -0.9152 0.9652)
			(stroke
				(width 0.15)
				(type solid)
			)
			(fill yes)
			(layer "F.SilkS")
		)
		(fp_line
			(start 1.1 -1.16)
			(end 1.1 1.15)
			(stroke
				(width 0.05)
				(type solid)
			)
			(layer "F.CrtYd")
		)
		(fp_line
			(start -1.12 -1.16)
			(end 1.1 -1.16)
			(stroke
				(width 0.05)
				(type solid)
			)
			(layer "F.CrtYd")
		)
		(fp_line
			(start -1.12 -1.16)
			(end -1.12 1.15)
			(stroke
				(width 0.05)
				(type solid)
			)
			(layer "F.CrtYd")
		)
		(fp_line
			(start -1.12 1.15)
			(end 1.1 1.15)
			(stroke
				(width 0.05)
				(type solid)
			)
			(layer "F.CrtYd")
		)
		(fp_line
			(start 0.8 -0.425)
			(end -0.652 -0.425)
			(stroke
				(width 0.15)
				(type solid)
			)
			(layer "F.Fab")
		)
		(fp_line
			(start 0.8 -0.425)
			(end 0.8 0.424)
			(stroke
				(width 0.15)
				(type solid)
			)
			(layer "F.Fab")
		)
		(fp_line
			(start -0.652 -0.425)
			(end -0.802 -0.276)
			(stroke
				(width 0.15)
				(type solid)
			)
			(layer "F.Fab")
		)
		(fp_line
			(start -0.802 -0.276)
			(end -0.802 0.424)
			(stroke
				(width 0.15)
				(type solid)
			)
			(layer "F.Fab")
		)
		(fp_line
			(start 0.8 0.424)
			(end -0.802 0.424)
			(stroke
				(width 0.15)
				(type solid)
			)
			(layer "F.Fab")
		)
		(fp_circle
			(center -0.9652 0.9652)
			(end -0.9144 0.9652)
			(stroke
				(width 0.15)
				(type solid)
			)
			(fill no)
			(layer "F.Fab")
		)
		(fp_text user "License: Apache-2.0"
			(at -1.12 5.024 90)
			(layer "F.Fab")
			(effects
				(font
					(size 0.7 0.7)
					(thickness 0.15)
				)
				(justify left bottom)
			)
		)
		(fp_text user "Author: Antmicro"
			(at -1.12 6.224 90)
			(layer "F.Fab")
			(effects
				(font
					(size 0.7 0.7)
					(thickness 0.15)
				)
				(justify left bottom)
			)
		)
		(fp_text user "${REFERENCE}"
			(at -1.12 3.824 90)
			(layer "F.Fab")
			(effects
				(font
					(size 0.7 0.7)
					(thickness 0.15)
				)
				(justify left bottom)
			)
		)
		(pad "1" smd rect
			(at -0.5 0.65 90)
			(size 0.4 0.51)
			(layers "F.Cu" "F.Mask" "F.Paste")
			(net 4 "Net-(D204-A)")
			(pinfunction "G")
			(pintype "input")
		)
		(pad "2" smd rect
			(at 0.498 0.65 90)
			(size 0.4 0.51)
			(layers "F.Cu" "F.Mask" "F.Paste")
			(net 249 "/Compute module/RUN_PG")
			(pinfunction "S")
			(pintype "passive")
		)
		(pad "3" smd rect
			(at 0 -0.652 90)
			(size 0.4 0.51)
			(layers "F.Cu" "F.Mask" "F.Paste")
			(net 330 "Net-(Q209-D)")
			(pinfunction "D")
			(pintype "passive")
		)
	)
	(footprint "antmicro-footprints:Compute-Module-4_H1.5mm"
		(locked yes)
		(layer "F.Cu")
		(at 76.460961 157.754 90)
		(property "Reference" "M201"
			(at -0.3102 0.780439 90)
			(layer "F.SilkS")
			(hide yes)
			(effects
				(font
					(size 0.7 0.7)
					(thickness 0.15)
				)
				(justify left bottom)
			)
		)
		(property "Value" "Compute-Module-4_H1.5mm"
			(at 0 -0.5 90)
			(layer "F.Fab")
			(effects
				(font
					(size 0.7 0.7)
					(thickness 0.15)
				)
				(justify left bottom)
			)
		)
		(property "Datasheet" "https://datasheets.raspberrypi.com/cm4/cm4-datasheet.pdf"
			(at 0 0 90)
			(layer "F.Fab")
			(hide yes)
			(effects
				(font
					(size 1.27 1.27)
					(thickness 0.15)
				)
			)
		)
		(property "Manufacturer" "Raspberry Pi"
			(at 0 0 90)
			(unlocked yes)
			(layer "F.Fab")
			(hide yes)
			(effects
				(font
					(size 1 1)
					(thickness 0.15)
				)
			)
		)
		(property "MPN" "SC0294"
			(at 0 0 90)
			(unlocked yes)
			(layer "F.Fab")
			(hide yes)
			(effects
				(font
					(size 1 1)
					(thickness 0.15)
				)
			)
		)
		(property "Author" "Antmicro"
			(at 0 0 90)
			(unlocked yes)
			(layer "F.Fab")
			(hide yes)
			(effects
				(font
					(size 1 1)
					(thickness 0.15)
				)
			)
		)
		(property "License" "Apache-2.0"
			(at 0 0 90)
			(unlocked yes)
			(layer "F.Fab")
			(hide yes)
			(effects
				(font
					(size 1 1)
					(thickness 0.15)
				)
			)
		)
		(sheetname "/Compute module/")
		(sheetfile "compute-module.kicad_sch")
		(attr exclude_from_pos_files exclude_from_bom dnp)
		(fp_text user "99"
			(at -8.401 35.7 90)
			(layer "F.Fab")
			(effects
				(font
					(size 0.7 0.7)
					(thickness 0.15)
				)
				(justify left bottom)
			)
		)
		(fp_text user "100"
			(at -8.5 5.7 90)
			(layer "F.Fab")
			(effects
				(font
					(size 0.7 0.7)
					(thickness 0.15)
				)
				(justify left bottom)
			)
		)
		(fp_text user "99"
			(at -8.5 1.699 90)
			(layer "F.Fab")
			(effects
				(font
					(size 0.7 0.7)
					(thickness 0.15)
				)
				(justify left bottom)
			)
		)
		(fp_text user "Author: Antmicro"
			(at -22 43.77 90)
			(layer "F.Fab")
			(effects
				(font
					(size 0.7 0.7)
					(thickness 0.15)
				)
				(justify left bottom)
			)
		)
		(fp_text user "2"
			(at 14.599 39.6 90)
			(layer "F.Fab")
			(effects
				(font
					(size 0.7 0.7)
					(thickness 0.15)
				)
				(justify left bottom)
			)
		)
		(fp_text user "License: Apache-2.0"
			(at -22 44.97 90)
			(layer "F.Fab")
			(effects
				(font
					(size 0.7 0.7)
					(thickness 0.15)
				)
				(justify left bottom)
			)
		)
		(fp_text user "${REFERENCE}"
			(at -22 42.569 90)
			(layer "F.Fab")
			(effects
				(font
					(size 0.7 0.7)
					(thickness 0.15)
				)
				(justify left bottom)
			)
		)
		(fp_text user "1"
			(at 14.599 35.6 90)
			(layer "F.Fab")
			(effects
				(font
					(size 0.7 0.7)
					(thickness 0.15)
				)
				(justify left bottom)
			)
		)
		(fp_text user "100"
			(at -8.401 39.7 90)
			(layer "F.Fab")
			(effects
				(font
					(size 0.7 0.7)
					(thickness 0.15)
				)
				(justify left bottom)
			)
		)
		(fp_text user "1"
			(at 14.499 1.6 90)
			(layer "F.Fab")
			(effects
				(font
					(size 0.7 0.7)
					(thickness 0.15)
				)
				(justify left bottom)
			)
		)
		(fp_text user "2"
			(at 14.499 5.599 90)
			(layer "F.Fab")
			(effects
				(font
					(size 0.7 0.7)
					(thickness 0.15)
				)
				(justify left bottom)
			)
		)
	)
	(footprint "antmicro-footprints:SOT-523"
		(layer "F.Cu")
		(at 101.917962 149.6165 -90)
		(property "Reference" "Q201"
			(at 1.775 -1.407038 180)
			(layer "F.SilkS")
			(effects
				(font
					(size 0.7 0.7)
					(thickness 0.15)
				)
				(justify right bottom)
			)
		)
		(property "Value" "PJE138K"
			(at 0.1 1.824 90)
			(layer "F.Fab")
			(effects
				(font
					(size 0.7 0.7)
					(thickness 0.15)
				)
				(justify right bottom)
			)
		)
		(property "Datasheet" "https://www.mouser.com/datasheet/2/1057/PJE138K-1876698.pdf"
			(at 0 0 270)
			(layer "F.Fab")
			(hide yes)
			(effects
				(font
					(size 1.27 1.27)
					(thickness 0.15)
				)
			)
		)
		(property "MPN" "PJE138K_R1_00001"
			(at 0 0 270)
			(unlocked yes)
			(layer "F.Fab")
			(hide yes)
			(effects
				(font
					(size 1 1)
					(thickness 0.15)
				)
			)
		)
		(property "Manufacturer" "PANJIT"
			(at 0 0 270)
			(unlocked yes)
			(layer "F.Fab")
			(hide yes)
			(effects
				(font
					(size 1 1)
					(thickness 0.15)
				)
			)
		)
		(property "Author" "Antmicro"
			(at 0 0 270)
			(unlocked yes)
			(layer "F.Fab")
			(hide yes)
			(effects
				(font
					(size 1 1)
					(thickness 0.15)
				)
			)
		)
		(property "License" "Apache-2.0"
			(at 0 0 270)
			(unlocked yes)
			(layer "F.Fab")
			(hide yes)
			(effects
				(font
					(size 1 1)
					(thickness 0.15)
				)
			)
		)
		(sheetname "/Compute module/")
		(sheetfile "compute-module.kicad_sch")
		(attr smd)
		(fp_line
			(start -0.927 -0.051)
			(end -0.927 -0.351)
			(stroke
				(width 0.15)
				(type solid)
			)
			(layer "F.SilkS")
		)
		(fp_line
			(start -0.927 -0.351)
			(end -0.725 -0.551)
			(stroke
				(width 0.15)
				(type solid)
			)
			(layer "F.SilkS")
		)
		(fp_line
			(start -0.725 -0.551)
			(end -0.277 -0.551)
			(stroke
				(width 0.15)
				(type solid)
			)
			(layer "F.SilkS")
		)
		(fp_line
			(start -0.277 -0.551)
			(end -0.277 -0.75)
			(stroke
				(width 0.15)
				(type solid)
			)
			(layer "F.SilkS")
		)
		(fp_circle
			(center -0.9652 0.9652)
			(end -0.9152 0.9652)
			(stroke
				(width 0.15)
				(type solid)
			)
			(fill yes)
			(layer "F.SilkS")
		)
		(fp_line
			(start -1.12 1.15)
			(end 1.1 1.15)
			(stroke
				(width 0.05)
				(type solid)
			)
			(layer "F.CrtYd")
		)
		(fp_line
			(start -1.12 -1.16)
			(end -1.12 1.15)
			(stroke
				(width 0.05)
				(type solid)
			)
			(layer "F.CrtYd")
		)
		(fp_line
			(start -1.12 -1.16)
			(end 1.1 -1.16)
			(stroke
				(width 0.05)
				(type solid)
			)
			(layer "F.CrtYd")
		)
		(fp_line
			(start 1.1 -1.16)
			(end 1.1 1.15)
			(stroke
				(width 0.05)
				(type solid)
			)
			(layer "F.CrtYd")
		)
		(fp_line
			(start 0.8 0.424)
			(end -0.802 0.424)
			(stroke
				(width 0.15)
				(type solid)
			)
			(layer "F.Fab")
		)
		(fp_line
			(start -0.802 -0.276)
			(end -0.802 0.424)
			(stroke
				(width 0.15)
				(type solid)
			)
			(layer "F.Fab")
		)
		(fp_line
			(start -0.652 -0.425)
			(end -0.802 -0.276)
			(stroke
				(width 0.15)
				(type solid)
			)
			(layer "F.Fab")
		)
		(fp_line
			(start 0.8 -0.425)
			(end 0.8 0.424)
			(stroke
				(width 0.15)
				(type solid)
			)
			(layer "F.Fab")
		)
		(fp_line
			(start 0.8 -0.425)
			(end -0.652 -0.425)
			(stroke
				(width 0.15)
				(type solid)
			)
			(layer "F.Fab")
		)
		(fp_circle
			(center -0.9652 0.9652)
			(end -0.9144 0.9652)
			(stroke
				(width 0.15)
				(type solid)
			)
			(fill no)
			(layer "F.Fab")
		)
		(fp_text user "Author: Antmicro"
			(at -1.12 6.224 270)
			(layer "F.Fab")
			(effects
				(font
					(size 0.7 0.7)
					(thickness 0.15)
				)
				(justify left bottom)
			)
		)
		(fp_text user "${REFERENCE}"
			(at -1.12 3.824 270)
			(layer "F.Fab")
			(effects
				(font
					(size 0.7 0.7)
					(thickness 0.15)
				)
				(justify left bottom)
			)
		)
		(fp_text user "License: Apache-2.0"
			(at -1.12 5.024 270)
			(layer "F.Fab")
			(effects
				(font
					(size 0.7 0.7)
					(thickness 0.15)
				)
				(justify left bottom)
			)
		)
		(pad "1" smd rect
			(at -0.5 0.65 270)
			(size 0.4 0.51)
			(layers "F.Cu" "F.Mask" "F.Paste")
			(net 231 "/Compute module/PolarfireID")
			(pinfunction "G")
			(pintype "input")
		)
		(pad "2" smd rect
			(at 0.498 0.65 270)
			(size 0.4 0.51)
			(layers "F.Cu" "F.Mask" "F.Paste")
			(net 3 "GND")
			(pinfunction "S")
			(pintype "passive")
		)
		(pad "3" smd rect
			(at 0 -0.652 270)
			(size 0.4 0.51)
			(layers "F.Cu" "F.Mask" "F.Paste")
			(net 327 "Net-(Q201-D)")
			(pinfunction "D")
			(pintype "passive")
		)
	)
	(footprint "antmicro-footprints:R_0402_1005Metric"
		(layer "F.Cu")
		(at 83.187962 162.4815 180)
		(descr "Resistor SMD 0402")
		(tags "resistor SMD 0402")
		(property "Reference" "R202"
			(at -3.83 -0.475 0)
			(layer "F.SilkS")
			(effects
				(font
					(size 0.7 0.7)
					(thickness 0.15)
				)
				(justify right bottom)
			)
		)
		(property "Value" "R_0R_0402"
			(at -1.011843 1.772047 0)
			(layer "F.Fab")
			(effects
				(font
					(size 0.7 0.7)
					(thickness 0.15)
				)
				(justify right bottom)
			)
		)
		(property "Datasheet" "https://industrial.panasonic.com/cdbs/www-data/pdf/RDA0000/AOA0000C301.pdf"
			(at 0 0 180)
			(layer "F.Fab")
			(hide yes)
			(effects
				(font
					(size 1.27 1.27)
					(thickness 0.15)
				)
			)
		)
		(property "Manufacturer" "Panasonic"
			(at 0 0 180)
			(unlocked yes)
			(layer "F.Fab")
			(hide yes)
			(effects
				(font
					(size 1 1)
					(thickness 0.15)
				)
			)
		)
		(property "MPN" "ERJ2GE0R00X"
			(at 0 0 180)
			(unlocked yes)
			(layer "F.Fab")
			(hide yes)
			(effects
				(font
					(size 1 1)
					(thickness 0.15)
				)
			)
		)
		(property "Val" "0R"
			(at 0 0 180)
			(unlocked yes)
			(layer "F.Fab")
			(hide yes)
			(effects
				(font
					(size 1 1)
					(thickness 0.15)
				)
			)
		)
		(property "License" "Apache-2.0"
			(at 0 0 180)
			(unlocked yes)
			(layer "F.Fab")
			(hide yes)
			(effects
				(font
					(size 1 1)
					(thickness 0.15)
				)
			)
		)
		(property "Author" "Antmicro"
			(at 0 0 180)
			(unlocked yes)
			(layer "F.Fab")
			(hide yes)
			(effects
				(font
					(size 1 1)
					(thickness 0.15)
				)
			)
		)
		(property "Tolerance" "~"
			(at 0 0 180)
			(unlocked yes)
			(layer "F.Fab")
			(hide yes)
			(effects
				(font
					(size 1 1)
					(thickness 0.15)
				)
			)
		)
		(property "Current" "1A"
			(at 0 0 180)
			(unlocked yes)
			(layer "F.Fab")
			(hide yes)
			(effects
				(font
					(size 1 1)
					(thickness 0.15)
				)
			)
		)
		(sheetname "/Compute module/")
		(sheetfile "compute-module.kicad_sch")
		(attr smd exclude_from_pos_files exclude_from_bom dnp)
		(fp_rect
			(start -0.925 -0.47)
			(end 0.925 0.47)
			(stroke
				(width 0.05)
				(type default)
			)
			(fill no)
			(layer "F.CrtYd")
		)
		(fp_rect
			(start -0.5 -0.25)
			(end 0.5 0.25)
			(stroke
				(width 0.15)
				(type solid)
			)
			(fill no)
			(layer "F.Fab")
		)
		(fp_text user "License: Apache-2.0"
			(at -0.95 5.169 180)
			(layer "F.Fab")
			(effects
				(font
					(size 0.7 0.7)
					(thickness 0.15)
				)
				(justify left bottom)
			)
		)
		(fp_text user "${REFERENCE}"
			(at -0.95 3.168 180)
			(layer "F.Fab")
			(effects
				(font
					(size 0.7 0.7)
					(thickness 0.15)
				)
				(justify left bottom)
			)
		)
		(fp_text user "Author: Antmicro"
			(at -0.95 4.169 180)
			(layer "F.Fab")
			(effects
				(font
					(size 0.7 0.7)
					(thickness 0.15)
				)
				(justify left bottom)
			)
		)
		(pad "1" smd roundrect
			(at -0.48 0 180)
			(size 0.59 0.64)
			(layers "F.Cu" "F.Mask" "F.Paste")
			(roundrect_rratio 0.25)
			(net 18 "V_{IO}")
			(pintype "passive")
		)
		(pad "2" smd roundrect
			(at 0.48 0 180)
			(size 0.59 0.64)
			(layers "F.Cu" "F.Mask" "F.Paste")
			(roundrect_rratio 0.25)
			(net 22 "+1V8")
			(pintype "passive")
		)
	)
	(footprint "antmicro-footprints:XDFN-2_1x0.60mm"
		(layer "F.Cu")
		(at 139.016962 164.4165 180)
		(property "Reference" "D504"
			(at 1.749 -2.56 0)
			(layer "F.SilkS")
			(effects
				(font
					(size 0.7 0.7)
					(thickness 0.15)
				)
				(justify left bottom)
			)
		)
		(property "Value" "TPD1E0B04_XDFN-2"
			(at 0 1.5 0)
			(layer "F.Fab")
			(effects
				(font
					(size 0.7 0.7)
					(thickness 0.15)
				)
				(justify right bottom)
			)
		)
		(property "Datasheet" "https://www.ti.com/general/docs/suppproductinfo.tsp?distId=26&gotoUrl=https://www.ti.com/lit/gpn/tpd1e0b04"
			(at 0 0 180)
			(layer "F.Fab")
			(hide yes)
			(effects
				(font
					(size 1.27 1.27)
					(thickness 0.15)
				)
			)
		)
		(property "MPN" "TPD1E0B04DPYR"
			(at 278.033924 328.833 0)
			(layer "F.Fab")
			(hide yes)
			(effects
				(font
					(size 1 1)
					(thickness 0.15)
				)
			)
		)
		(property "Manufacturer" "Texas Instruments"
			(at 278.033924 328.833 0)
			(layer "F.Fab")
			(hide yes)
			(effects
				(font
					(size 1 1)
					(thickness 0.15)
				)
			)
		)
		(property "Author" "Antmicro"
			(at 0 0 180)
			(unlocked yes)
			(layer "F.Fab")
			(hide yes)
			(effects
				(font
					(size 1 1)
					(thickness 0.15)
				)
			)
		)
		(property "License" "Apache-2.0"
			(at 0 0 180)
			(unlocked yes)
			(layer "F.Fab")
			(hide yes)
			(effects
				(font
					(size 1 1)
					(thickness 0.15)
				)
			)
		)
		(sheetname "/NVMe & microSD/")
		(sheetfile "nvme-micro-sd.kicad_sch")
		(attr smd)
		(fp_rect
			(start -0.725 -0.475)
			(end 0.725 0.475)
			(stroke
				(width 0.05)
				(type solid)
			)
			(fill no)
			(layer "F.CrtYd")
		)
		(fp_rect
			(start -0.55 -0.35)
			(end 0.55 0.35)
			(stroke
				(width 0.15)
				(type solid)
			)
			(fill no)
			(layer "F.Fab")
		)
		(fp_text user "Author: Antmicro"
			(at -0.8 4.4 180)
			(layer "F.Fab")
			(effects
				(font
					(size 0.7 0.7)
					(thickness 0.15)
				)
				(justify left bottom)
			)
		)
		(fp_text user "${REFERENCE}"
			(at -0.8 3.2 180)
			(layer "F.Fab")
			(effects
				(font
					(size 0.7 0.7)
					(thickness 0.15)
				)
				(justify left bottom)
			)
		)
		(fp_text user "License: Apache-2.0"
			(at -0.8 5.6 180)
			(layer "F.Fab")
			(effects
				(font
					(size 0.7 0.7)
					(thickness 0.15)
				)
				(justify left bottom)
			)
		)
		(pad "1" smd roundrect
			(at -0.351 0 180)
			(size 0.3 0.5)
			(layers "F.Cu" "F.Mask" "F.Paste")
			(roundrect_rratio 0.25)
			(net 3 "GND")
			(pinfunction "C")
			(pintype "passive")
		)
		(pad "2" smd roundrect
			(at 0.349 0 180)
			(size 0.3 0.5)
			(layers "F.Cu" "F.Mask" "F.Paste")
			(roundrect_rratio 0.25)
			(net 9 "+3V3")
			(pinfunction "A")
			(pintype "passive")
		)
	)
	(footprint "antmicro-footprints:C_0402_1005Metric"
		(layer "F.Cu")
		(at 96.967962 124.8165 180)
		(descr "Capacitor SMD 0402")
		(tags "capacitor SMD 0402")
		(property "Reference" "C904"
			(at 2.717962 -1.6835 180)
			(layer "F.SilkS")
			(effects
				(font
					(size 0.7 0.7)
					(thickness 0.15)
					(bold yes)
				)
				(justify right bottom)
			)
		)
		(property "Value" "C_100n_0402"
			(at -1.022927 2.155213 0)
			(layer "F.Fab")
			(effects
				(font
					(size 0.7 0.7)
					(thickness 0.15)
				)
				(justify right bottom)
			)
		)
		(property "Datasheet" "https://www.murata.com/products/productdetail?partno=GRM155R61H104KE14%23"
			(at 0 0 180)
			(layer "F.Fab")
			(hide yes)
			(effects
				(font
					(size 1.27 1.27)
					(thickness 0.15)
				)
			)
		)
		(property "Manufacturer" "Murata"
			(at 0 0 180)
			(unlocked yes)
			(layer "F.Fab")
			(hide yes)
			(effects
				(font
					(size 1 1)
					(thickness 0.15)
				)
			)
		)
		(property "MPN" "GRM155R61H104KE14D"
			(at 0 0 180)
			(unlocked yes)
			(layer "F.Fab")
			(hide yes)
			(effects
				(font
					(size 1 1)
					(thickness 0.15)
				)
			)
		)
		(property "Val" "100n"
			(at 0 0 180)
			(unlocked yes)
			(layer "F.Fab")
			(hide yes)
			(effects
				(font
					(size 1 1)
					(thickness 0.15)
				)
			)
		)
		(property "License" "Apache-2.0"
			(at 0 0 180)
			(unlocked yes)
			(layer "F.Fab")
			(hide yes)
			(effects
				(font
					(size 1 1)
					(thickness 0.15)
				)
			)
		)
		(property "Author" "Antmicro"
			(at 0 0 180)
			(unlocked yes)
			(layer "F.Fab")
			(hide yes)
			(effects
				(font
					(size 1 1)
					(thickness 0.15)
				)
			)
		)
		(property "Voltage" "50V"
			(at 0 0 180)
			(unlocked yes)
			(layer "F.Fab")
			(hide yes)
			(effects
				(font
					(size 1 1)
					(thickness 0.15)
				)
			)
		)
		(property "Dielectric" "X5R"
			(at 0 0 180)
			(unlocked yes)
			(layer "F.Fab")
			(hide yes)
			(effects
				(font
					(size 1 1)
					(thickness 0.15)
				)
			)
		)
		(sheetname "/USB/")
		(sheetfile "usb.kicad_sch")
		(attr smd)
		(fp_rect
			(start -0.925 -0.47)
			(end 0.925 0.47)
			(stroke
				(width 0.05)
				(type default)
			)
			(fill no)
			(layer "F.CrtYd")
		)
		(fp_line
			(start 0.504 0.248)
			(end -0.494 0.248)
			(stroke
				(width 0.15)
				(type solid)
			)
			(layer "F.Fab")
		)
		(fp_line
			(start 0.504 -0.25)
			(end 0.504 0.248)
			(stroke
				(width 0.15)
				(type solid)
			)
			(layer "F.Fab")
		)
		(fp_line
			(start -0.494 0.248)
			(end -0.494 -0.25)
			(stroke
				(width 0.15)
				(type solid)
			)
			(layer "F.Fab")
		)
		(fp_line
			(start -0.494 -0.25)
			(end 0.504 -0.25)
			(stroke
				(width 0.15)
				(type solid)
			)
			(layer "F.Fab")
		)
		(fp_text user "${REFERENCE}"
			(at -0.939 4.599 180)
			(layer "F.Fab")
			(effects
				(font
					(size 0.7 0.7)
					(thickness 0.15)
				)
				(justify left bottom)
			)
		)
		(fp_text user "License: Apache-2.0"
			(at -0.939 5.799 180)
			(layer "F.Fab")
			(effects
				(font
					(size 0.7 0.7)
					(thickness 0.15)
				)
				(justify left bottom)
			)
		)
		(fp_text user "Author: Antmicro"
			(at -0.939 3.399 180)
			(layer "F.Fab")
			(effects
				(font
					(size 0.7 0.7)
					(thickness 0.15)
				)
				(justify left bottom)
			)
		)
		(pad "1" smd roundrect
			(at -0.48 0 180)
			(size 0.59 0.64)
			(layers "F.Cu" "F.Mask" "F.Paste")
			(roundrect_rratio 0.25)
			(net 28 "/USB/+5V_{CAP}")
			(pintype "passive")
		)
		(pad "2" smd roundrect
			(at 0.48 0 180)
			(size 0.59 0.64)
			(layers "F.Cu" "F.Mask" "F.Paste")
			(roundrect_rratio 0.25)
			(net 3 "GND")
			(pintype "passive")
		)
	)
	(footprint "antmicro-footprints:TP_SMD_0.75mm"
		(layer "F.Cu")
		(at 97.697962 120.5)
		(property "Reference" "TP910"
			(at 25.935 26.15 0)
			(layer "F.SilkS")
			(effects
				(font
					(size 0.7 0.7)
					(thickness 0.15)
				)
				(justify left bottom)
			)
		)
		(property "Value" "TP_0.75mm_SMD"
			(at 0 1.2 0)
			(layer "F.Fab")
			(effects
				(font
					(size 0.7 0.7)
					(thickness 0.15)
				)
				(justify left bottom)
			)
		)
		(property "MPN" ""
			(at 0 0 0)
			(unlocked yes)
			(layer "F.Fab")
			(hide yes)
			(effects
				(font
					(size 1 1)
					(thickness 0.15)
				)
			)
		)
		(property "Manufacturer" ""
			(at 0 0 0)
			(unlocked yes)
			(layer "F.Fab")
			(hide yes)
			(effects
				(font
					(size 1 1)
					(thickness 0.15)
				)
			)
		)
		(property "Author" "Antmicro"
			(at 0 0 0)
			(unlocked yes)
			(layer "F.Fab")
			(hide yes)
			(effects
				(font
					(size 1 1)
					(thickness 0.15)
				)
			)
		)
		(property "License" "Apache-2.0"
			(at 0 0 0)
			(unlocked yes)
			(layer "F.Fab")
			(hide yes)
			(effects
				(font
					(size 1 1)
					(thickness 0.15)
				)
			)
		)
		(sheetname "/USB/")
		(sheetfile "usb.kicad_sch")
		(attr exclude_from_pos_files exclude_from_bom)
		(fp_circle
			(center 0 0)
			(end 0.475 0)
			(stroke
				(width 0.05)
				(type default)
			)
			(fill no)
			(layer "F.CrtYd")
		)
		(fp_text user "Author: Antmicro"
			(at -0.4 3.901 0)
			(layer "F.Fab")
			(effects
				(font
					(size 0.7 0.7)
					(thickness 0.15)
				)
				(justify left bottom)
			)
		)
		(fp_text user "License: Apache-2.0"
			(at -0.4 5.101 0)
			(layer "F.Fab")
			(effects
				(font
					(size 0.7 0.7)
					(thickness 0.15)
				)
				(justify left bottom)
			)
		)
		(fp_text user "${REFERENCE}"
			(at -0.4 2.7 0)
			(layer "F.Fab")
			(effects
				(font
					(size 0.7 0.7)
					(thickness 0.15)
				)
				(justify left bottom)
			)
		)
		(pad "1" smd circle
			(at 0 0)
			(size 0.75 0.75)
			(layers "F.Cu" "F.Mask")
			(net 435 "Net-(U906-~{VCONN_FAULT})")
			(pinfunction "1")
			(pintype "passive")
		)
	)
	(footprint "antmicro-footprints:C_0402_1005Metric"
		(layer "F.Cu")
		(at 87.367962 153.2665 -90)
		(descr "Capacitor SMD 0402")
		(tags "capacitor SMD 0402")
		(property "Reference" "C203"
			(at 0.03 -1.42 90)
			(layer "F.SilkS")
			(effects
				(font
					(size 0.7 0.7)
					(thickness 0.15)
				)
				(justify right bottom)
			)
		)
		(property "Value" "C_100n_0402"
			(at -1.022927 2.155213 90)
			(layer "F.Fab")
			(effects
				(font
					(size 0.7 0.7)
					(thickness 0.15)
				)
				(justify right bottom)
			)
		)
		(property "Datasheet" "https://www.murata.com/products/productdetail?partno=GRM155R61H104KE14%23"
			(at 0 0 270)
			(layer "F.Fab")
			(hide yes)
			(effects
				(font
					(size 1.27 1.27)
					(thickness 0.15)
				)
			)
		)
		(property "MPN" "GRM155R61H104KE14D"
			(at 0 0 270)
			(unlocked yes)
			(layer "F.Fab")
			(hide yes)
			(effects
				(font
					(size 1 1)
					(thickness 0.15)
				)
			)
		)
		(property "Manufacturer" "Murata"
			(at 0 0 270)
			(unlocked yes)
			(layer "F.Fab")
			(hide yes)
			(effects
				(font
					(size 1 1)
					(thickness 0.15)
				)
			)
		)
		(property "License" "Apache-2.0"
			(at 0 0 270)
			(unlocked yes)
			(layer "F.Fab")
			(hide yes)
			(effects
				(font
					(size 1 1)
					(thickness 0.15)
				)
			)
		)
		(property "Author" "Antmicro"
			(at 0 0 270)
			(unlocked yes)
			(layer "F.Fab")
			(hide yes)
			(effects
				(font
					(size 1 1)
					(thickness 0.15)
				)
			)
		)
		(property "Val" "100n"
			(at 0 0 270)
			(unlocked yes)
			(layer "F.Fab")
			(hide yes)
			(effects
				(font
					(size 1 1)
					(thickness 0.15)
				)
			)
		)
		(property "Voltage" "50V"
			(at 0 0 270)
			(unlocked yes)
			(layer "F.Fab")
			(hide yes)
			(effects
				(font
					(size 1 1)
					(thickness 0.15)
				)
			)
		)
		(property "Dielectric" "X5R"
			(at 0 0 270)
			(unlocked yes)
			(layer "F.Fab")
			(hide yes)
			(effects
				(font
					(size 1 1)
					(thickness 0.15)
				)
			)
		)
		(sheetname "/Compute module/")
		(sheetfile "compute-module.kicad_sch")
		(attr smd)
		(fp_rect
			(start -0.925 -0.47)
			(end 0.925 0.47)
			(stroke
				(width 0.05)
				(type default)
			)
			(fill no)
			(layer "F.CrtYd")
		)
		(fp_line
			(start -0.494 0.248)
			(end -0.494 -0.25)
			(stroke
				(width 0.15)
				(type solid)
			)
			(layer "F.Fab")
		)
		(fp_line
			(start 0.504 0.248)
			(end -0.494 0.248)
			(stroke
				(width 0.15)
				(type solid)
			)
			(layer "F.Fab")
		)
		(fp_line
			(start -0.494 -0.25)
			(end 0.504 -0.25)
			(stroke
				(width 0.15)
				(type solid)
			)
			(layer "F.Fab")
		)
		(fp_line
			(start 0.504 -0.25)
			(end 0.504 0.248)
			(stroke
				(width 0.15)
				(type solid)
			)
			(layer "F.Fab")
		)
		(fp_text user "Author: Antmicro"
			(at -0.939 3.399 270)
			(layer "F.Fab")
			(effects
				(font
					(size 0.7 0.7)
					(thickness 0.15)
				)
				(justify left bottom)
			)
		)
		(fp_text user "License: Apache-2.0"
			(at -0.939 5.799 270)
			(layer "F.Fab")
			(effects
				(font
					(size 0.7 0.7)
					(thickness 0.15)
				)
				(justify left bottom)
			)
		)
		(fp_text user "${REFERENCE}"
			(at -0.939 4.599 270)
			(layer "F.Fab")
			(effects
				(font
					(size 0.7 0.7)
					(thickness 0.15)
				)
				(justify left bottom)
			)
		)
		(pad "1" smd roundrect
			(at -0.48 0 270)
			(size 0.59 0.64)
			(layers "F.Cu" "F.Mask" "F.Paste")
			(roundrect_rratio 0.25)
			(net 3 "GND")
			(pintype "passive")
		)
		(pad "2" smd roundrect
			(at 0.48 0 270)
			(size 0.59 0.64)
			(layers "F.Cu" "F.Mask" "F.Paste")
			(roundrect_rratio 0.25)
			(net 18 "V_{IO}")
			(pintype "passive")
		)
	)
	(footprint "antmicro-footprints:Nexperia_DFN-10_2.5x1mm_P0.5mm"
		(layer "F.Cu")
		(at 134.067962 150.1285 90)
		(property "Reference" "D807"
			(at -1.298 -1.562 90)
			(layer "F.SilkS")
			(effects
				(font
					(size 0.7 0.7)
					(thickness 0.15)
				)
				(justify left bottom)
			)
		)
		(property "Value" "PUSB3F96X_PASS"
			(at -0.016 1.705 90)
			(layer "F.Fab")
			(effects
				(font
					(size 0.7 0.7)
					(thickness 0.15)
				)
				(justify left bottom)
			)
		)
		(property "Datasheet" "https://mouser.com/datasheet/2/916/PUSB3F96-1600324.pdf"
			(at 0 0 90)
			(layer "F.Fab")
			(hide yes)
			(effects
				(font
					(size 1.27 1.27)
					(thickness 0.15)
				)
			)
		)
		(property "Manufacturer" "Nexperia"
			(at 0 0 90)
			(unlocked yes)
			(layer "F.Fab")
			(hide yes)
			(effects
				(font
					(size 1 1)
					(thickness 0.15)
				)
			)
		)
		(property "MPN" "PUSB3F96X"
			(at 0 0 90)
			(unlocked yes)
			(layer "F.Fab")
			(hide yes)
			(effects
				(font
					(size 1 1)
					(thickness 0.15)
				)
			)
		)
		(property "Author" "Antmicro"
			(at 0 0 90)
			(unlocked yes)
			(layer "F.Fab")
			(hide yes)
			(effects
				(font
					(size 1 1)
					(thickness 0.15)
				)
			)
		)
		(property "License" "Apache-2.0"
			(at 0 0 90)
			(unlocked yes)
			(layer "F.Fab")
			(hide yes)
			(effects
				(font
					(size 1 1)
					(thickness 0.15)
				)
			)
		)
		(sheetname "/Peripherals/")
		(sheetfile "peripherals.kicad_sch")
		(attr smd)
		(fp_line
			(start -1.375 -0.4)
			(end -1.375 0.4)
			(stroke
				(width 0.15)
				(type solid)
			)
			(layer "F.SilkS")
		)
		(fp_line
			(start 1.375 0.4)
			(end 1.375 -0.4)
			(stroke
				(width 0.15)
				(type solid)
			)
			(layer "F.SilkS")
		)
		(fp_circle
			(center -1.4 0.7)
			(end -1.349 0.7)
			(stroke
				(width 0.15)
				(type solid)
			)
			(fill yes)
			(layer "F.SilkS")
		)
		(fp_rect
			(start -1.4 -0.725)
			(end 1.4 0.725)
			(stroke
				(width 0.05)
				(type solid)
			)
			(fill no)
			(layer "F.CrtYd")
		)
		(fp_line
			(start 1.25 -0.5)
			(end -1.25 -0.5)
			(stroke
				(width 0.15)
				(type solid)
			)
			(layer "F.Fab")
		)
		(fp_line
			(start -1.25 -0.5)
			(end -1.25 0.15)
			(stroke
				(width 0.15)
				(type solid)
			)
			(layer "F.Fab")
		)
		(fp_line
			(start -1.25 0.15)
			(end -0.9 0.5)
			(stroke
				(width 0.15)
				(type solid)
			)
			(layer "F.Fab")
		)
		(fp_line
			(start 1.25 0.5)
			(end 1.25 -0.5)
			(stroke
				(width 0.15)
				(type solid)
			)
			(layer "F.Fab")
		)
		(fp_line
			(start -0.9 0.5)
			(end 1.25 0.5)
			(stroke
				(width 0.15)
				(type solid)
			)
			(layer "F.Fab")
		)
		(fp_text user "License: Apache-2.0"
			(at -1.367 6.105 90)
			(layer "F.Fab")
			(effects
				(font
					(size 0.7 0.7)
					(thickness 0.15)
				)
				(justify left bottom)
			)
		)
		(fp_text user "Author: Antmicro"
			(at -1.367 4.905 90)
			(layer "F.Fab")
			(effects
				(font
					(size 0.7 0.7)
					(thickness 0.15)
				)
				(justify left bottom)
			)
		)
		(fp_text user "${REFERENCE}"
			(at -1.367 3.704 90)
			(layer "F.Fab")
			(effects
				(font
					(size 0.7 0.7)
					(thickness 0.15)
				)
				(justify left bottom)
			)
		)
		(pad "1" smd rect
			(at -1 0.3875 90)
			(size 0.2 0.475)
			(layers "F.Cu" "F.Mask" "F.Paste")
			(net 10 "+5V")
			(pinfunction "CH1")
			(pintype "passive")
			(solder_mask_margin 0.05)
		)
		(pad "2" smd rect
			(at -0.5 0.3875 90)
			(size 0.2 0.475)
			(layers "F.Cu" "F.Mask" "F.Paste")
			(net 239 "/Compute module/GPIO.14{slash}RXD0")
			(pinfunction "CH2")
			(pintype "passive")
			(solder_mask_margin 0.05)
		)
		(pad "3" smd rect
			(at 0 0.3875 90)
			(size 0.2 0.475)
			(layers "F.Cu" "F.Mask" "F.Paste")
			(net 3 "GND")
			(pinfunction "GND")
			(pintype "passive")
			(solder_mask_margin 0.05)
		)
		(pad "4" smd rect
			(at 0.5 0.3875 90)
			(size 0.2 0.475)
			(layers "F.Cu" "F.Mask" "F.Paste")
			(net 241 "/Compute module/GPIO.15{slash}TXD0")
			(pinfunction "CH3")
			(pintype "passive")
			(solder_mask_margin 0.05)
		)
		(pad "5" smd rect
			(at 1 0.3875 90)
			(size 0.2 0.475)
			(layers "F.Cu" "F.Mask" "F.Paste")
			(net 237 "/Compute module/GPIO.18")
			(pinfunction "CH4")
			(pintype "passive")
			(solder_mask_margin 0.05)
		)
		(pad "6" smd rect
			(at 1 -0.3875 90)
			(size 0.2 0.475)
			(layers "F.Cu" "F.Mask" "F.Paste")
			(net 237 "/Compute module/GPIO.18")
			(pinfunction "CH4")
			(pintype "passive")
			(solder_mask_margin 0.05)
		)
		(pad "7" smd rect
			(at 0.5 -0.3875 90)
			(size 0.2 0.475)
			(layers "F.Cu" "F.Mask" "F.Paste")
			(net 241 "/Compute module/GPIO.15{slash}TXD0")
			(pinfunction "CH3")
			(pintype "passive")
			(solder_mask_margin 0.05)
		)
		(pad "8" smd rect
			(at 0 -0.3875 90)
			(size 0.2 0.475)
			(layers "F.Cu" "F.Mask" "F.Paste")
			(net 3 "GND")
			(pinfunction "GND")
			(pintype "passive")
			(solder_mask_margin 0.05)
		)
		(pad "9" smd rect
			(at -0.501 -0.3875 90)
			(size 0.2 0.475)
			(layers "F.Cu" "F.Mask" "F.Paste")
			(net 239 "/Compute module/GPIO.14{slash}RXD0")
			(pinfunction "CH2")
			(pintype "passive")
			(solder_mask_margin 0.05)
		)
		(pad "10" smd rect
			(at -1 -0.3875 90)
			(size 0.2 0.475)
			(layers "F.Cu" "F.Mask" "F.Paste")
			(net 10 "+5V")
			(pinfunction "CH1")
			(pintype "passive")
			(solder_mask_margin 0.05)
		)
	)
	(footprint "antmicro-footprints:R_0402_1005Metric"
		(layer "F.Cu")
		(at 66.925 167.275 180)
		(descr "Resistor SMD 0402")
		(tags "resistor SMD 0402")
		(property "Reference" "R3"
			(at 0.85 0.375 0)
			(layer "F.SilkS")
			(effects
				(font
					(size 0.7 0.7)
					(thickness 0.15)
				)
				(justify right top)
			)
		)
		(property "Value" "R_0R_0402"
			(at -1.011843 1.772047 0)
			(layer "F.Fab")
			(effects
				(font
					(size 0.7 0.7)
					(thickness 0.15)
				)
				(justify right top)
			)
		)
		(property "Datasheet" "https://industrial.panasonic.com/cdbs/www-data/pdf/RDA0000/AOA0000C301.pdf"
			(at 0 0 0)
			(layer "F.Fab")
			(hide yes)
			(effects
				(font
					(size 1.27 1.27)
					(thickness 0.15)
				)
			)
		)
		(property "Description" "SMD Chip Resistor, Jumper, 0 ohm, 100 mW, 0402 [1005 Metric], Thick Film, General Purpose"
			(at 0 0 0)
			(layer "F.Fab")
			(hide yes)
			(effects
				(font
					(size 1.27 1.27)
					(thickness 0.15)
				)
			)
		)
		(property "MPN" "ERJ2GE0R00X"
			(at 0 0 180)
			(unlocked yes)
			(layer "F.Fab")
			(hide yes)
			(effects
				(font
					(size 1 1)
					(thickness 0.15)
				)
			)
		)
		(property "Manufacturer" "Panasonic"
			(at 0 0 180)
			(unlocked yes)
			(layer "F.Fab")
			(hide yes)
			(effects
				(font
					(size 1 1)
					(thickness 0.15)
				)
			)
		)
		(property "License" "Apache-2.0"
			(at 0 0 180)
			(unlocked yes)
			(layer "F.Fab")
			(hide yes)
			(effects
				(font
					(size 1 1)
					(thickness 0.15)
				)
			)
		)
		(property "Author" "Antmicro"
			(at 0 0 180)
			(unlocked yes)
			(layer "F.Fab")
			(hide yes)
			(effects
				(font
					(size 1 1)
					(thickness 0.15)
				)
			)
		)
		(property "Val" "0R"
			(at 0 0 180)
			(unlocked yes)
			(layer "F.Fab")
			(hide yes)
			(effects
				(font
					(size 1 1)
					(thickness 0.15)
				)
			)
		)
		(property "Tolerance" "~"
			(at 0 0 180)
			(unlocked yes)
			(layer "F.Fab")
			(hide yes)
			(effects
				(font
					(size 1 1)
					(thickness 0.15)
				)
			)
		)
		(property "Current" "1A"
			(at 0 0 180)
			(unlocked yes)
			(layer "F.Fab")
			(hide yes)
			(effects
				(font
					(size 1 1)
					(thickness 0.15)
				)
			)
		)
		(sheetname "/Peripherals/")
		(sheetfile "peripherals.kicad_sch")
		(attr smd)
		(fp_rect
			(start -0.925 -0.47)
			(end 0.925 0.47)
			(stroke
				(width 0.05)
				(type default)
			)
			(fill no)
			(layer "F.CrtYd")
		)
		(fp_rect
			(start -0.5 -0.25)
			(end 0.5 0.25)
			(stroke
				(width 0.15)
				(type solid)
			)
			(fill no)
			(layer "F.Fab")
		)
		(fp_text user "Author: Antmicro"
			(at -0.95 4.169 0)
			(layer "F.Fab")
			(effects
				(font
					(size 0.7 0.7)
					(thickness 0.15)
				)
				(justify right top)
			)
		)
		(fp_text user "${REFERENCE}"
			(at -0.95 3.168 0)
			(layer "F.Fab")
			(effects
				(font
					(size 0.7 0.7)
					(thickness 0.15)
				)
				(justify right top)
			)
		)
		(fp_text user "License: Apache-2.0"
			(at -0.95 5.169 0)
			(layer "F.Fab")
			(effects
				(font
					(size 0.7 0.7)
					(thickness 0.15)
				)
				(justify right top)
			)
		)
		(pad "1" smd roundrect
			(at -0.48 0 180)
			(size 0.59 0.64)
			(layers "F.Cu" "F.Mask" "F.Paste")
			(roundrect_rratio 0.25)
			(net 501 "Net-(U801-V_{DD(UP)})")
			(pintype "passive")
		)
		(pad "2" smd roundrect
			(at 0.48 0 180)
			(size 0.59 0.64)
			(layers "F.Cu" "F.Mask" "F.Paste")
			(roundrect_rratio 0.25)
			(net 10 "+5V")
			(pintype "passive")
		)
	)
	(footprint "antmicro-footprints:C_0402_1005Metric"
		(layer "F.Cu")
		(at 83.442962 138.157236 180)
		(descr "Capacitor SMD 0402")
		(tags "capacitor SMD 0402")
		(property "Reference" "C923"
			(at 1.025 -0.779264 0)
			(layer "F.SilkS")
			(effects
				(font
					(size 0.7 0.7)
					(thickness 0.15)
				)
				(justify right bottom)
			)
		)
		(property "Value" "C_100n_0402"
			(at -1.022927 2.155213 0)
			(layer "F.Fab")
			(effects
				(font
					(size 0.7 0.7)
					(thickness 0.15)
				)
				(justify right bottom)
			)
		)
		(property "Datasheet" "https://www.murata.com/products/productdetail?partno=GRM155R61H104KE14%23"
			(at 0 0 180)
			(layer "F.Fab")
			(hide yes)
			(effects
				(font
					(size 1.27 1.27)
					(thickness 0.15)
				)
			)
		)
		(property "Manufacturer" "Murata"
			(at 0 0 180)
			(unlocked yes)
			(layer "F.Fab")
			(hide yes)
			(effects
				(font
					(size 1 1)
					(thickness 0.15)
				)
			)
		)
		(property "MPN" "GRM155R61H104KE14D"
			(at 0 0 180)
			(unlocked yes)
			(layer "F.Fab")
			(hide yes)
			(effects
				(font
					(size 1 1)
					(thickness 0.15)
				)
			)
		)
		(property "Val" "100n"
			(at 0 0 180)
			(unlocked yes)
			(layer "F.Fab")
			(hide yes)
			(effects
				(font
					(size 1 1)
					(thickness 0.15)
				)
			)
		)
		(property "License" "Apache-2.0"
			(at 0 0 180)
			(unlocked yes)
			(layer "F.Fab")
			(hide yes)
			(effects
				(font
					(size 1 1)
					(thickness 0.15)
				)
			)
		)
		(property "Author" "Antmicro"
			(at 0 0 180)
			(unlocked yes)
			(layer "F.Fab")
			(hide yes)
			(effects
				(font
					(size 1 1)
					(thickness 0.15)
				)
			)
		)
		(property "Voltage" "50V"
			(at 0 0 180)
			(unlocked yes)
			(layer "F.Fab")
			(hide yes)
			(effects
				(font
					(size 1 1)
					(thickness 0.15)
				)
			)
		)
		(property "Dielectric" "X5R"
			(at 0 0 180)
			(unlocked yes)
			(layer "F.Fab")
			(hide yes)
			(effects
				(font
					(size 1 1)
					(thickness 0.15)
				)
			)
		)
		(sheetname "/USB/")
		(sheetfile "usb.kicad_sch")
		(attr smd)
		(fp_rect
			(start -0.925 -0.47)
			(end 0.925 0.47)
			(stroke
				(width 0.05)
				(type default)
			)
			(fill no)
			(layer "F.CrtYd")
		)
		(fp_line
			(start 0.504 0.248)
			(end -0.494 0.248)
			(stroke
				(width 0.15)
				(type solid)
			)
			(layer "F.Fab")
		)
		(fp_line
			(start 0.504 -0.25)
			(end 0.504 0.248)
			(stroke
				(width 0.15)
				(type solid)
			)
			(layer "F.Fab")
		)
		(fp_line
			(start -0.494 0.248)
			(end -0.494 -0.25)
			(stroke
				(width 0.15)
				(type solid)
			)
			(layer "F.Fab")
		)
		(fp_line
			(start -0.494 -0.25)
			(end 0.504 -0.25)
			(stroke
				(width 0.15)
				(type solid)
			)
			(layer "F.Fab")
		)
		(fp_text user "Author: Antmicro"
			(at -0.939 3.399 180)
			(layer "F.Fab")
			(effects
				(font
					(size 0.7 0.7)
					(thickness 0.15)
				)
				(justify left bottom)
			)
		)
		(fp_text user "${REFERENCE}"
			(at -0.939 4.599 180)
			(layer "F.Fab")
			(effects
				(font
					(size 0.7 0.7)
					(thickness 0.15)
				)
				(justify left bottom)
			)
		)
		(fp_text user "License: Apache-2.0"
			(at -0.939 5.799 180)
			(layer "F.Fab")
			(effects
				(font
					(size 0.7 0.7)
					(thickness 0.15)
				)
				(justify left bottom)
			)
		)
		(pad "1" smd roundrect
			(at -0.48 0 180)
			(size 0.59 0.64)
			(layers "F.Cu" "F.Mask" "F.Paste")
			(roundrect_rratio 0.25)
			(net 30 "/USB/USB_1V2")
			(pintype "passive")
		)
		(pad "2" smd roundrect
			(at 0.48 0 180)
			(size 0.59 0.64)
			(layers "F.Cu" "F.Mask" "F.Paste")
			(roundrect_rratio 0.25)
			(net 3 "GND")
			(pintype "passive")
		)
	)
	(footprint "antmicro-footprints:TP_SMD_0.75mm"
		(layer "F.Cu")
		(at 76.967962 162.6915 180)
		(property "Reference" "TP205"
			(at 9.19 0.515 0)
			(layer "F.SilkS")
			(effects
				(font
					(size 0.7 0.7)
					(thickness 0.15)
				)
				(justify right bottom)
			)
		)
		(property "Value" "TP_0.75mm_SMD"
			(at 0 1.2 0)
			(layer "F.Fab")
			(effects
				(font
					(size 0.7 0.7)
					(thickness 0.15)
				)
				(justify right bottom)
			)
		)
		(property "Author" "Antmicro"
			(at 0 0 180)
			(unlocked yes)
			(layer "F.Fab")
			(hide yes)
			(effects
				(font
					(size 1 1)
					(thickness 0.15)
				)
			)
		)
		(property "License" "Apache-2.0"
			(at 0 0 180)
			(unlocked yes)
			(layer "F.Fab")
			(hide yes)
			(effects
				(font
					(size 1 1)
					(thickness 0.15)
				)
			)
		)
		(property "MPN" ""
			(at 0 0 180)
			(unlocked yes)
			(layer "F.Fab")
			(hide yes)
			(effects
				(font
					(size 1 1)
					(thickness 0.15)
				)
			)
		)
		(property "Manufacturer" ""
			(at 0 0 180)
			(unlocked yes)
			(layer "F.Fab")
			(hide yes)
			(effects
				(font
					(size 1 1)
					(thickness 0.15)
				)
			)
		)
		(sheetname "/Compute module/")
		(sheetfile "compute-module.kicad_sch")
		(attr exclude_from_pos_files exclude_from_bom)
		(fp_circle
			(center 0 0)
			(end 0.475 0)
			(stroke
				(width 0.05)
				(type default)
			)
			(fill no)
			(layer "F.CrtYd")
		)
		(fp_text user "${REFERENCE}"
			(at -0.4 2.7 180)
			(layer "F.Fab")
			(effects
				(font
					(size 0.7 0.7)
					(thickness 0.15)
				)
				(justify left bottom)
			)
		)
		(fp_text user "License: Apache-2.0"
			(at -0.4 5.101 180)
			(layer "F.Fab")
			(effects
				(font
					(size 0.7 0.7)
					(thickness 0.15)
				)
				(justify left bottom)
			)
		)
		(fp_text user "Author: Antmicro"
			(at -0.4 3.901 180)
			(layer "F.Fab")
			(effects
				(font
					(size 0.7 0.7)
					(thickness 0.15)
				)
				(justify left bottom)
			)
		)
		(pad "1" smd circle
			(at 0 0 180)
			(size 0.75 0.75)
			(layers "F.Cu" "F.Mask")
			(net 247 "/Compute module/WL_nDis")
			(pinfunction "1")
			(pintype "passive")
		)
	)
	(footprint "antmicro-footprints:SOT-523"
		(layer "F.Cu")
		(at 86.717962 156.6165)
		(property "Reference" "Q211"
			(at -1.2 2.13 0)
			(layer "F.SilkS")
			(effects
				(font
					(size 0.7 0.7)
					(thickness 0.15)
				)
				(justify left bottom)
			)
		)
		(property "Value" "PJE138K"
			(at 0.1 1.824 0)
			(layer "F.Fab")
			(effects
				(font
					(size 0.7 0.7)
					(thickness 0.15)
				)
				(justify left bottom)
			)
		)
		(property "Datasheet" "https://www.mouser.com/datasheet/2/1057/PJE138K-1876698.pdf"
			(at 0 0 0)
			(layer "F.Fab")
			(hide yes)
			(effects
				(font
					(size 1.27 1.27)
					(thickness 0.15)
				)
			)
		)
		(property "MPN" "PJE138K_R1_00001"
			(at 0 0 0)
			(unlocked yes)
			(layer "F.Fab")
			(hide yes)
			(effects
				(font
					(size 1 1)
					(thickness 0.15)
				)
			)
		)
		(property "Manufacturer" "PANJIT"
			(at 0 0 0)
			(unlocked yes)
			(layer "F.Fab")
			(hide yes)
			(effects
				(font
					(size 1 1)
					(thickness 0.15)
				)
			)
		)
		(property "Author" "Antmicro"
			(at 0 0 0)
			(unlocked yes)
			(layer "F.Fab")
			(hide yes)
			(effects
				(font
					(size 1 1)
					(thickness 0.15)
				)
			)
		)
		(property "License" "Apache-2.0"
			(at 0 0 0)
			(unlocked yes)
			(layer "F.Fab")
			(hide yes)
			(effects
				(font
					(size 1 1)
					(thickness 0.15)
				)
			)
		)
		(sheetname "/Compute module/")
		(sheetfile "compute-module.kicad_sch")
		(attr smd)
		(fp_line
			(start -0.927 -0.351)
			(end -0.725 -0.551)
			(stroke
				(width 0.15)
				(type solid)
			)
			(layer "F.SilkS")
		)
		(fp_line
			(start -0.927 -0.051)
			(end -0.927 -0.351)
			(stroke
				(width 0.15)
				(type solid)
			)
			(layer "F.SilkS")
		)
		(fp_line
			(start -0.725 -0.551)
			(end -0.277 -0.551)
			(stroke
				(width 0.15)
				(type solid)
			)
			(layer "F.SilkS")
		)
		(fp_line
			(start -0.277 -0.551)
			(end -0.277 -0.75)
			(stroke
				(width 0.15)
				(type solid)
			)
			(layer "F.SilkS")
		)
		(fp_circle
			(center -0.9652 0.9652)
			(end -0.9152 0.9652)
			(stroke
				(width 0.15)
				(type solid)
			)
			(fill yes)
			(layer "F.SilkS")
		)
		(fp_line
			(start -1.12 -1.16)
			(end -1.12 1.15)
			(stroke
				(width 0.05)
				(type solid)
			)
			(layer "F.CrtYd")
		)
		(fp_line
			(start -1.12 -1.16)
			(end 1.1 -1.16)
			(stroke
				(width 0.05)
				(type solid)
			)
			(layer "F.CrtYd")
		)
		(fp_line
			(start -1.12 1.15)
			(end 1.1 1.15)
			(stroke
				(width 0.05)
				(type solid)
			)
			(layer "F.CrtYd")
		)
		(fp_line
			(start 1.1 -1.16)
			(end 1.1 1.15)
			(stroke
				(width 0.05)
				(type solid)
			)
			(layer "F.CrtYd")
		)
		(fp_line
			(start -0.802 -0.276)
			(end -0.802 0.424)
			(stroke
				(width 0.15)
				(type solid)
			)
			(layer "F.Fab")
		)
		(fp_line
			(start -0.652 -0.425)
			(end -0.802 -0.276)
			(stroke
				(width 0.15)
				(type solid)
			)
			(layer "F.Fab")
		)
		(fp_line
			(start 0.8 -0.425)
			(end -0.652 -0.425)
			(stroke
				(width 0.15)
				(type solid)
			)
			(layer "F.Fab")
		)
		(fp_line
			(start 0.8 -0.425)
			(end 0.8 0.424)
			(stroke
				(width 0.15)
				(type solid)
			)
			(layer "F.Fab")
		)
		(fp_line
			(start 0.8 0.424)
			(end -0.802 0.424)
			(stroke
				(width 0.15)
				(type solid)
			)
			(layer "F.Fab")
		)
		(fp_circle
			(center -0.9652 0.9652)
			(end -0.9144 0.9652)
			(stroke
				(width 0.15)
				(type solid)
			)
			(fill no)
			(layer "F.Fab")
		)
		(fp_text user "Author: Antmicro"
			(at -1.12 6.224 0)
			(layer "F.Fab")
			(effects
				(font
					(size 0.7 0.7)
					(thickness 0.15)
				)
				(justify left bottom)
			)
		)
		(fp_text user "License: Apache-2.0"
			(at -1.12 5.024 0)
			(layer "F.Fab")
			(effects
				(font
					(size 0.7 0.7)
					(thickness 0.15)
				)
				(justify left bottom)
			)
		)
		(fp_text user "${REFERENCE}"
			(at -1.12 3.824 0)
			(layer "F.Fab")
			(effects
				(font
					(size 0.7 0.7)
					(thickness 0.15)
				)
				(justify left bottom)
			)
		)
		(pad "1" smd rect
			(at -0.5 0.65)
			(size 0.4 0.51)
			(layers "F.Cu" "F.Mask" "F.Paste")
			(net 231 "/Compute module/PolarfireID")
			(pinfunction "G")
			(pintype "input")
		)
		(pad "2" smd rect
			(at 0.498 0.65)
			(size 0.4 0.51)
			(layers "F.Cu" "F.Mask" "F.Paste")
			(net 3 "GND")
			(pinfunction "S")
			(pintype "passive")
		)
		(pad "3" smd rect
			(at 0 -0.652)
			(size 0.4 0.51)
			(layers "F.Cu" "F.Mask" "F.Paste")
			(net 444 "Net-(Q211-D)")
			(pinfunction "D")
			(pintype "passive")
		)
	)
	(footprint "antmicro-footprints:LED_0603_1608Metric_G"
		(layer "F.Cu")
		(at 75.517962 152.56 180)
		(descr "LED SMD 0603 Green")
		(tags "LED SMD 0603 Green")
		(property "Reference" "D206"
			(at -1.392038 7.46 0)
			(layer "F.SilkS")
			(effects
				(font
					(size 0.7 0.7)
					(thickness 0.15)
				)
				(justify right bottom)
			)
		)
		(property "Value" "LED_G_0603_KP-1608CGCK"
			(at -0.001 1.599 0)
			(layer "F.Fab")
			(effects
				(font
					(size 0.7 0.7)
					(thickness 0.15)
				)
				(justify right bottom)
			)
		)
		(property "Datasheet" "http://www.kingbright.com/attachments/file/psearch//000/00/00/KP-1608CGCK(Ver.23B).pdf"
			(at 0 0 180)
			(layer "F.Fab")
			(hide yes)
			(effects
				(font
					(size 1.27 1.27)
					(thickness 0.15)
				)
			)
		)
		(property "MPN" "KP-1608CGCK"
			(at 0 0 180)
			(unlocked yes)
			(layer "F.Fab")
			(hide yes)
			(effects
				(font
					(size 1 1)
					(thickness 0.15)
				)
			)
		)
		(property "Manufacturer" "Kingbright"
			(at 0 0 180)
			(unlocked yes)
			(layer "F.Fab")
			(hide yes)
			(effects
				(font
					(size 1 1)
					(thickness 0.15)
				)
			)
		)
		(property "Color" "Green"
			(at 0 0 180)
			(unlocked yes)
			(layer "F.Fab")
			(hide yes)
			(effects
				(font
					(size 1 1)
					(thickness 0.15)
				)
			)
		)
		(property "Author" "Antmicro"
			(at 0 0 180)
			(unlocked yes)
			(layer "F.Fab")
			(hide yes)
			(effects
				(font
					(size 1 1)
					(thickness 0.15)
				)
			)
		)
		(property "License" "Apache-2.0"
			(at 0 0 180)
			(unlocked yes)
			(layer "F.Fab")
			(hide yes)
			(effects
				(font
					(size 1 1)
					(thickness 0.15)
				)
			)
		)
		(sheetname "/Compute module/")
		(sheetfile "compute-module.kicad_sch")
		(attr smd)
		(fp_line
			(start 0.22 0.35)
			(end -0.22 0.35)
			(stroke
				(width 0.15)
				(type solid)
			)
			(layer "F.SilkS")
		)
		(fp_line
			(start 0.22 -0.35)
			(end -0.22 -0.35)
			(stroke
				(width 0.15)
				(type solid)
			)
			(layer "F.SilkS")
		)
		(fp_line
			(start 0.105328 0.201008)
			(end 0.105328 -0.198992)
			(stroke
				(width 0.1)
				(type solid)
			)
			(layer "F.SilkS")
		)
		(fp_line
			(start 0.105328 0.201008)
			(end -0.094672 0.001008)
			(stroke
				(width 0.1)
				(type solid)
			)
			(layer "F.SilkS")
		)
		(fp_line
			(start 0.105328 0.001008)
			(end 0.24 0.001)
			(stroke
				(width 0.1)
				(type solid)
			)
			(layer "F.SilkS")
		)
		(fp_line
			(start -0.094672 0.201008)
			(end -0.094672 -0.198992)
			(stroke
				(width 0.1)
				(type solid)
			)
			(layer "F.SilkS")
		)
		(fp_line
			(start -0.094672 0.001008)
			(end 0.105328 -0.198992)
			(stroke
				(width 0.1)
				(type solid)
			)
			(layer "F.SilkS")
		)
		(fp_line
			(start -0.094672 0.001008)
			(end -0.24 0.001008)
			(stroke
				(width 0.1)
				(type solid)
			)
			(layer "F.SilkS")
		)
		(fp_line
			(start -1.18 -0.319)
			(end -1.18 0.321)
			(stroke
				(width 0.15)
				(type solid)
			)
			(layer "F.SilkS")
		)
		(fp_rect
			(start 1.25 0.65)
			(end -1.25 -0.65)
			(stroke
				(width 0.05)
				(type solid)
			)
			(fill no)
			(layer "F.CrtYd")
		)
		(fp_line
			(start 0.599 0)
			(end 0.201 0)
			(stroke
				(width 0.15)
				(type solid)
			)
			(layer "F.Fab")
		)
		(fp_line
			(start 0.201 0.2)
			(end 0.201 0)
			(stroke
				(width 0.15)
				(type solid)
			)
			(layer "F.Fab")
		)
		(fp_line
			(start 0.201 0)
			(end 0.201 -0.202)
			(stroke
				(width 0.15)
				(type solid)
			)
			(layer "F.Fab")
		)
		(fp_line
			(start 0.201 -0.202)
			(end -0.101 0)
			(stroke
				(width 0.15)
				(type solid)
			)
			(layer "F.Fab")
		)
		(fp_line
			(start -0.101 0)
			(end 0.201 0.2)
			(stroke
				(width 0.15)
				(type solid)
			)
			(layer "F.Fab")
		)
		(fp_line
			(start -0.199 0.2)
			(end -0.199 0.1)
			(stroke
				(width 0.15)
				(type solid)
			)
			(layer "F.Fab")
		)
		(fp_line
			(start -0.199 0)
			(end -0.597 0)
			(stroke
				(width 0.15)
				(type solid)
			)
			(layer "F.Fab")
		)
		(fp_line
			(start -0.199 -0.202)
			(end -0.199 0.1)
			(stroke
				(width 0.15)
				(type solid)
			)
			(layer "F.Fab")
		)
		(fp_rect
			(start 0.848 0.4)
			(end -0.85 -0.402)
			(stroke
				(width 0.15)
				(type solid)
			)
			(fill no)
			(layer "F.Fab")
		)
		(fp_text user "${REFERENCE}"
			(at -1.4224 5.999 180)
			(layer "F.Fab")
			(effects
				(font
					(size 0.7 0.7)
					(thickness 0.15)
				)
				(justify left bottom)
			)
		)
		(fp_text user "License: Apache-2.0"
			(at -1.4224 3.599 180)
			(layer "F.Fab")
			(effects
				(font
					(size 0.7 0.7)
					(thickness 0.15)
				)
				(justify left bottom)
			)
		)
		(fp_text user "Author: Antmicro"
			(at -1.4224 4.799 180)
			(layer "F.Fab")
			(effects
				(font
					(size 0.7 0.7)
					(thickness 0.15)
				)
				(justify left bottom)
			)
		)
		(pad "1" smd roundrect
			(at -0.7 0)
			(size 0.8 1)
			(layers "F.Cu" "F.Mask" "F.Paste")
			(roundrect_rratio 0.2)
			(net 466 "Net-(D206-C)")
			(pinfunction "C")
			(pintype "passive")
		)
		(pad "2" smd roundrect
			(at 0.7 0)
			(size 0.8 1)
			(layers "F.Cu" "F.Mask" "F.Paste")
			(roundrect_rratio 0.2)
			(net 10 "+5V")
			(pinfunction "A")
			(pintype "passive")
		)
	)
	(footprint "antmicro-footprints:TP_SMD_0.75mm"
		(layer "F.Cu")
		(at 107.15 150.6)
		(property "Reference" "TP216"
			(at 0.3 0.35 0)
			(layer "F.SilkS")
			(effects
				(font
					(size 0.7 0.7)
					(thickness 0.15)
				)
				(justify left bottom)
			)
		)
		(property "Value" "TP_0.75mm_SMD"
			(at 0 1.2 0)
			(layer "F.Fab")
			(effects
				(font
					(size 0.7 0.7)
					(thickness 0.15)
				)
				(justify left bottom)
			)
		)
		(property "MPN" ""
			(at 0 0 0)
			(unlocked yes)
			(layer "F.Fab")
			(hide yes)
			(effects
				(font
					(size 1 1)
					(thickness 0.15)
				)
			)
		)
		(property "Manufacturer" ""
			(at 0 0 0)
			(unlocked yes)
			(layer "F.Fab")
			(hide yes)
			(effects
				(font
					(size 1 1)
					(thickness 0.15)
				)
			)
		)
		(property "Author" "Antmicro"
			(at 0 0 0)
			(unlocked yes)
			(layer "F.Fab")
			(hide yes)
			(effects
				(font
					(size 1 1)
					(thickness 0.15)
				)
			)
		)
		(property "License" "Apache-2.0"
			(at 0 0 0)
			(unlocked yes)
			(layer "F.Fab")
			(hide yes)
			(effects
				(font
					(size 1 1)
					(thickness 0.15)
				)
			)
		)
		(sheetname "/Compute module/")
		(sheetfile "compute-module.kicad_sch")
		(attr exclude_from_pos_files exclude_from_bom)
		(fp_circle
			(center 0 0)
			(end 0.475 0)
			(stroke
				(width 0.05)
				(type default)
			)
			(fill no)
			(layer "F.CrtYd")
		)
		(fp_text user "Author: Antmicro"
			(at -0.4 3.901 0)
			(layer "F.Fab")
			(effects
				(font
					(size 0.7 0.7)
					(thickness 0.15)
				)
				(justify left bottom)
			)
		)
		(fp_text user "${REFERENCE}"
			(at -0.4 2.7 0)
			(layer "F.Fab")
			(effects
				(font
					(size 0.7 0.7)
					(thickness 0.15)
				)
				(justify left bottom)
			)
		)
		(fp_text user "License: Apache-2.0"
			(at -0.4 5.101 0)
			(layer "F.Fab")
			(effects
				(font
					(size 0.7 0.7)
					(thickness 0.15)
				)
				(justify left bottom)
			)
		)
		(pad "1" smd circle
			(at 0 0)
			(size 0.75 0.75)
			(layers "F.Cu" "F.Mask")
			(net 259 "/Compute module/Pf_5V.SCL")
			(pinfunction "1")
			(pintype "passive")
		)
	)
	(footprint "antmicro-footprints:SOT-23-3"
		(layer "F.Cu")
		(at 67.857962 146.0765)
		(property "Reference" "Q206"
			(at -1.89 1.565 90)
			(layer "F.SilkS")
			(effects
				(font
					(size 0.7 0.7)
					(thickness 0.15)
				)
				(justify left bottom)
			)
		)
		(property "Value" "SSM3J332R"
			(at -1.9 2.7 0)
			(layer "F.Fab")
			(effects
				(font
					(size 0.7 0.7)
					(thickness 0.15)
				)
				(justify left bottom)
			)
		)
		(property "Datasheet" "https://www.mouser.com/datasheet/2/408/SSM3J332R_datasheet_en_20181015-1150575.pdf"
			(at 0 0 0)
			(layer "F.Fab")
			(hide yes)
			(effects
				(font
					(size 1.27 1.27)
					(thickness 0.15)
				)
			)
		)
		(property "MPN" "SSM3J332R,LF"
			(at 0 0 0)
			(unlocked yes)
			(layer "F.Fab")
			(hide yes)
			(effects
				(font
					(size 1 1)
					(thickness 0.15)
				)
			)
		)
		(property "Manufacturer" "Toshiba"
			(at 0 0 0)
			(unlocked yes)
			(layer "F.Fab")
			(hide yes)
			(effects
				(font
					(size 1 1)
					(thickness 0.15)
				)
			)
		)
		(property "Author" "Antmicro"
			(at 0 0 0)
			(unlocked yes)
			(layer "F.Fab")
			(hide yes)
			(effects
				(font
					(size 1 1)
					(thickness 0.15)
				)
			)
		)
		(property "License" "Apache-2.0"
			(at 0 0 0)
			(unlocked yes)
			(layer "F.Fab")
			(hide yes)
			(effects
				(font
					(size 1 1)
					(thickness 0.15)
				)
			)
		)
		(sheetname "/Compute module/")
		(sheetfile "compute-module.kicad_sch")
		(attr smd)
		(fp_line
			(start -1.45 -1.35)
			(end -0.85 -1.35)
			(stroke
				(width 0.15)
				(type solid)
			)
			(layer "F.SilkS")
		)
		(fp_line
			(start -0.85 -1.35)
			(end -0.7 -1.5)
			(stroke
				(width 0.15)
				(type solid)
			)
			(layer "F.SilkS")
		)
		(fp_line
			(start -0.7 1.5)
			(end -0.7 1.35)
			(stroke
				(width 0.15)
				(type solid)
			)
			(layer "F.SilkS")
		)
		(fp_line
			(start 0.7 -1.5)
			(end -0.7 -1.5)
			(stroke
				(width 0.15)
				(type solid)
			)
			(layer "F.SilkS")
		)
		(fp_line
			(start 0.7 -0.4)
			(end 0.7 -1.5)
			(stroke
				(width 0.15)
				(type solid)
			)
			(layer "F.SilkS")
		)
		(fp_line
			(start 0.7 0.4)
			(end 0.7 1.5)
			(stroke
				(width 0.15)
				(type solid)
			)
			(layer "F.SilkS")
		)
		(fp_line
			(start 0.7 1.5)
			(end -0.7 1.5)
			(stroke
				(width 0.15)
				(type solid)
			)
			(layer "F.SilkS")
		)
		(fp_line
			(start -1.75 -0.5)
			(end -1.75 -1.4)
			(stroke
				(width 0.05)
				(type solid)
			)
			(layer "F.CrtYd")
		)
		(fp_line
			(start -1.75 0.5)
			(end -0.85 0.5)
			(stroke
				(width 0.05)
				(type solid)
			)
			(layer "F.CrtYd")
		)
		(fp_line
			(start -1.75 1.4)
			(end -1.75 0.5)
			(stroke
				(width 0.05)
				(type solid)
			)
			(layer "F.CrtYd")
		)
		(fp_line
			(start -0.9 -1.6)
			(end -0.9 -1.4)
			(stroke
				(width 0.05)
				(type solid)
			)
			(layer "F.CrtYd")
		)
		(fp_line
			(start -0.9 -1.6)
			(end 0.825 -1.6)
			(stroke
				(width 0.05)
				(type solid)
			)
			(layer "F.CrtYd")
		)
		(fp_line
			(start -0.9 -1.4)
			(end -1.75 -1.4)
			(stroke
				(width 0.05)
				(type solid)
			)
			(layer "F.CrtYd")
		)
		(fp_line
			(start -0.85 -0.5)
			(end -1.75 -0.5)
			(stroke
				(width 0.05)
				(type solid)
			)
			(layer "F.CrtYd")
		)
		(fp_line
			(start -0.85 0.5)
			(end -0.85 -0.5)
			(stroke
				(width 0.05)
				(type solid)
			)
			(layer "F.CrtYd")
		)
		(fp_line
			(start -0.85 1.4)
			(end -1.75 1.4)
			(stroke
				(width 0.05)
				(type solid)
			)
			(layer "F.CrtYd")
		)
		(fp_line
			(start -0.85 1.65)
			(end -0.85 1.4)
			(stroke
				(width 0.05)
				(type solid)
			)
			(layer "F.CrtYd")
		)
		(fp_line
			(start 0.825 -1.6)
			(end 0.825 -0.45)
			(stroke
				(width 0.05)
				(type solid)
			)
			(layer "F.CrtYd")
		)
		(fp_line
			(start 0.825 -0.45)
			(end 1.75 -0.45)
			(stroke
				(width 0.05)
				(type solid)
			)
			(layer "F.CrtYd")
		)
		(fp_line
			(start 0.85 0.45)
			(end 0.85 1.65)
			(stroke
				(width 0.05)
				(type solid)
			)
			(layer "F.CrtYd")
		)
		(fp_line
			(start 0.85 1.65)
			(end -0.85 1.65)
			(stroke
				(width 0.05)
				(type solid)
			)
			(layer "F.CrtYd")
		)
		(fp_line
			(start 1.75 -0.45)
			(end 1.75 0.45)
			(stroke
				(width 0.05)
				(type solid)
			)
			(layer "F.CrtYd")
		)
		(fp_line
			(start 1.75 0.45)
			(end 0.85 0.45)
			(stroke
				(width 0.05)
				(type solid)
			)
			(layer "F.CrtYd")
		)
		(fp_line
			(start -0.712 -1.325)
			(end -0.712 1.523)
			(stroke
				(width 0.15)
				(type solid)
			)
			(layer "F.Fab")
		)
		(fp_line
			(start -0.712 1.519)
			(end 0.688 1.519)
			(stroke
				(width 0.15)
				(type solid)
			)
			(layer "F.Fab")
		)
		(fp_line
			(start -0.437 -1.526)
			(end -0.712 -1.325)
			(stroke
				(width 0.15)
				(type solid)
			)
			(layer "F.Fab")
		)
		(fp_line
			(start -0.437 -1.526)
			(end 0.688 -1.526)
			(stroke
				(width 0.15)
				(type solid)
			)
			(layer "F.Fab")
		)
		(fp_line
			(start 0.688 1.519)
			(end 0.688 -1.52)
			(stroke
				(width 0.15)
				(type solid)
			)
			(layer "F.Fab")
		)
		(fp_text user "${REFERENCE}"
			(at -1.837 4 0)
			(layer "F.Fab")
			(effects
				(font
					(size 0.7 0.7)
					(thickness 0.15)
				)
				(justify left bottom)
			)
		)
		(fp_text user "License: Apache-2.0"
			(at -1.8 6.8 0)
			(layer "F.Fab")
			(effects
				(font
					(size 0.7 0.7)
					(thickness 0.15)
				)
				(justify left bottom)
			)
		)
		(fp_text user "Author: Antmicro"
			(at -1.837 5.3 0)
			(layer "F.Fab")
			(effects
				(font
					(size 0.7 0.7)
					(thickness 0.15)
				)
				(justify left bottom)
			)
		)
		(pad "1" smd roundrect
			(at -1.1 -0.951)
			(size 1 0.6)
			(layers "F.Cu" "F.Mask" "F.Paste")
			(roundrect_rratio 0.15)
			(net 491 "Net-(Q206-G)")
			(pinfunction "G")
			(pintype "input")
		)
		(pad "2" smd roundrect
			(at -1.1 0.949)
			(size 1 0.6)
			(layers "F.Cu" "F.Mask" "F.Paste")
			(roundrect_rratio 0.15)
			(net 9 "+3V3")
			(pinfunction "S")
			(pintype "passive")
		)
		(pad "3" smd roundrect
			(at 1.1 -0.0005)
			(size 1 0.6)
			(layers "F.Cu" "F.Mask" "F.Paste")
			(roundrect_rratio 0.15)
			(net 468 "Net-(D202-A)")
			(pinfunction "D")
			(pintype "passive")
		)
	)
	(footprint "antmicro-footprints:R_0402_1005Metric"
		(layer "F.Cu")
		(at 77.317962 148.6915 90)
		(descr "Resistor SMD 0402")
		(tags "resistor SMD 0402")
		(property "Reference" "R207"
			(at -3.585 0.66 90)
			(layer "F.SilkS")
			(effects
				(font
					(size 0.7 0.7)
					(thickness 0.15)
				)
				(justify left bottom)
			)
		)
		(property "Value" "R_1k_0402"
			(at -1.011843 1.772047 90)
			(layer "F.Fab")
			(effects
				(font
					(size 0.7 0.7)
					(thickness 0.15)
				)
				(justify left bottom)
			)
		)
		(property "Datasheet" "https://www.bourns.com/docs/product-datasheets/cr.pdf"
			(at 0 0 90)
			(layer "F.Fab")
			(hide yes)
			(effects
				(font
					(size 1.27 1.27)
					(thickness 0.15)
				)
			)
		)
		(property "MPN" "CR0402-FX-1001GLF"
			(at 0 0 90)
			(unlocked yes)
			(layer "F.Fab")
			(hide yes)
			(effects
				(font
					(size 1 1)
					(thickness 0.15)
				)
			)
		)
		(property "Manufacturer" "Bourns"
			(at 0 0 90)
			(unlocked yes)
			(layer "F.Fab")
			(hide yes)
			(effects
				(font
					(size 1 1)
					(thickness 0.15)
				)
			)
		)
		(property "License" "Apache-2.0"
			(at 0 0 90)
			(unlocked yes)
			(layer "F.Fab")
			(hide yes)
			(effects
				(font
					(size 1 1)
					(thickness 0.15)
				)
			)
		)
		(property "Author" "Antmicro"
			(at 0 0 90)
			(unlocked yes)
			(layer "F.Fab")
			(hide yes)
			(effects
				(font
					(size 1 1)
					(thickness 0.15)
				)
			)
		)
		(property "Val" "1k"
			(at 0 0 90)
			(unlocked yes)
			(layer "F.Fab")
			(hide yes)
			(effects
				(font
					(size 1 1)
					(thickness 0.15)
				)
			)
		)
		(property "Tolerance" "1%"
			(at 0 0 90)
			(unlocked yes)
			(layer "F.Fab")
			(hide yes)
			(effects
				(font
					(size 1 1)
					(thickness 0.15)
				)
			)
		)
		(sheetname "/Compute module/")
		(sheetfile "compute-module.kicad_sch")
		(attr smd)
		(fp_rect
			(start -0.925 -0.47)
			(end 0.925 0.47)
			(stroke
				(width 0.05)
				(type default)
			)
			(fill no)
			(layer "F.CrtYd")
		)
		(fp_rect
			(start -0.5 -0.25)
			(end 0.5 0.25)
			(stroke
				(width 0.15)
				(type solid)
			)
			(fill no)
			(layer "F.Fab")
		)
		(fp_text user "Author: Antmicro"
			(at -0.95 4.169 90)
			(layer "F.Fab")
			(effects
				(font
					(size 0.7 0.7)
					(thickness 0.15)
				)
				(justify left bottom)
			)
		)
		(fp_text user "License: Apache-2.0"
			(at -0.95 5.169 90)
			(layer "F.Fab")
			(effects
				(font
					(size 0.7 0.7)
					(thickness 0.15)
				)
				(justify left bottom)
			)
		)
		(fp_text user "${REFERENCE}"
			(at -0.95 3.168 90)
			(layer "F.Fab")
			(effects
				(font
					(size 0.7 0.7)
					(thickness 0.15)
				)
				(justify left bottom)
			)
		)
		(pad "1" smd roundrect
			(at -0.48 0 90)
			(size 0.59 0.64)
			(layers "F.Cu" "F.Mask" "F.Paste")
			(roundrect_rratio 0.25)
			(net 137 "Net-(J201-Pad21)")
			(pintype "passive")
		)
		(pad "2" smd roundrect
			(at 0.48 0 90)
			(size 0.59 0.64)
			(layers "F.Cu" "F.Mask" "F.Paste")
			(roundrect_rratio 0.25)
			(net 445 "Net-(D201-C)")
			(pintype "passive")
		)
	)
	(footprint "antmicro-footprints:R_0402_1005Metric"
		(layer "F.Cu")
		(at 82.667962 120.7415 180)
		(descr "Resistor SMD 0402")
		(tags "resistor SMD 0402")
		(property "Reference" "R902"
			(at -1.03 -1.205 0)
			(layer "F.SilkS")
			(effects
				(font
					(size 0.7 0.7)
					(thickness 0.15)
				)
				(justify right bottom)
			)
		)
		(property "Value" "R_1k_0402"
			(at -1.011843 1.772047 0)
			(layer "F.Fab")
			(effects
				(font
					(size 0.7 0.7)
					(thickness 0.15)
				)
				(justify right bottom)
			)
		)
		(property "Datasheet" "https://www.bourns.com/docs/product-datasheets/cr.pdf"
			(at 0 0 180)
			(layer "F.Fab")
			(hide yes)
			(effects
				(font
					(size 1.27 1.27)
					(thickness 0.15)
				)
			)
		)
		(property "MPN" "CR0402-FX-1001GLF"
			(at 0 0 180)
			(unlocked yes)
			(layer "F.Fab")
			(hide yes)
			(effects
				(font
					(size 1 1)
					(thickness 0.15)
				)
			)
		)
		(property "Manufacturer" "Bourns"
			(at 0 0 180)
			(unlocked yes)
			(layer "F.Fab")
			(hide yes)
			(effects
				(font
					(size 1 1)
					(thickness 0.15)
				)
			)
		)
		(property "License" "Apache-2.0"
			(at 0 0 180)
			(unlocked yes)
			(layer "F.Fab")
			(hide yes)
			(effects
				(font
					(size 1 1)
					(thickness 0.15)
				)
			)
		)
		(property "Author" "Antmicro"
			(at 0 0 180)
			(unlocked yes)
			(layer "F.Fab")
			(hide yes)
			(effects
				(font
					(size 1 1)
					(thickness 0.15)
				)
			)
		)
		(property "Val" "1k"
			(at 0 0 180)
			(unlocked yes)
			(layer "F.Fab")
			(hide yes)
			(effects
				(font
					(size 1 1)
					(thickness 0.15)
				)
			)
		)
		(property "Tolerance" "1%"
			(at 0 0 180)
			(unlocked yes)
			(layer "F.Fab")
			(hide yes)
			(effects
				(font
					(size 1 1)
					(thickness 0.15)
				)
			)
		)
		(sheetname "/USB/")
		(sheetfile "usb.kicad_sch")
		(attr smd)
		(fp_rect
			(start -0.925 -0.47)
			(end 0.925 0.47)
			(stroke
				(width 0.05)
				(type default)
			)
			(fill no)
			(layer "F.CrtYd")
		)
		(fp_rect
			(start -0.5 -0.25)
			(end 0.5 0.25)
			(stroke
				(width 0.15)
				(type solid)
			)
			(fill no)
			(layer "F.Fab")
		)
		(fp_text user "License: Apache-2.0"
			(at -0.95 5.169 180)
			(layer "F.Fab")
			(effects
				(font
					(size 0.7 0.7)
					(thickness 0.15)
				)
				(justify left bottom)
			)
		)
		(fp_text user "Author: Antmicro"
			(at -0.95 4.169 180)
			(layer "F.Fab")
			(effects
				(font
					(size 0.7 0.7)
					(thickness 0.15)
				)
				(justify left bottom)
			)
		)
		(fp_text user "${REFERENCE}"
			(at -0.95 3.168 180)
			(layer "F.Fab")
			(effects
				(font
					(size 0.7 0.7)
					(thickness 0.15)
				)
				(justify left bottom)
			)
		)
		(pad "1" smd roundrect
			(at -0.48 0 180)
			(size 0.59 0.64)
			(layers "F.Cu" "F.Mask" "F.Paste")
			(roundrect_rratio 0.25)
			(net 483 "Net-(D906-A)")
			(pintype "passive")
		)
		(pad "2" smd roundrect
			(at 0.48 0 180)
			(size 0.59 0.64)
			(layers "F.Cu" "F.Mask" "F.Paste")
			(roundrect_rratio 0.25)
			(net 10 "+5V")
			(pintype "passive")
		)
	)
	(footprint "antmicro-footprints:TP_SMD_0.75mm"
		(layer "F.Cu")
		(at 130.39 156.3)
		(property "Reference" "TP602"
			(at -2.85 -0.425 180)
			(layer "F.SilkS")
			(effects
				(font
					(size 0.7 0.7)
					(thickness 0.15)
				)
				(justify left bottom)
			)
		)
		(property "Value" "TP_0.75mm_SMD"
			(at 0 1.2 0)
			(layer "F.Fab")
			(effects
				(font
					(size 0.7 0.7)
					(thickness 0.15)
				)
				(justify left bottom)
			)
		)
		(property "MPN" ""
			(at 0 0 0)
			(unlocked yes)
			(layer "F.Fab")
			(hide yes)
			(effects
				(font
					(size 1 1)
					(thickness 0.15)
				)
			)
		)
		(property "Manufacturer" ""
			(at 0 0 0)
			(unlocked yes)
			(layer "F.Fab")
			(hide yes)
			(effects
				(font
					(size 1 1)
					(thickness 0.15)
				)
			)
		)
		(property "Author" "Antmicro"
			(at 0 0 0)
			(unlocked yes)
			(layer "F.Fab")
			(hide yes)
			(effects
				(font
					(size 1 1)
					(thickness 0.15)
				)
			)
		)
		(property "License" "Apache-2.0"
			(at 0 0 0)
			(unlocked yes)
			(layer "F.Fab")
			(hide yes)
			(effects
				(font
					(size 1 1)
					(thickness 0.15)
				)
			)
		)
		(sheetname "/CSI/")
		(sheetfile "csi.kicad_sch")
		(attr exclude_from_pos_files exclude_from_bom)
		(fp_circle
			(center 0 0)
			(end 0.475 0)
			(stroke
				(width 0.05)
				(type default)
			)
			(fill no)
			(layer "F.CrtYd")
		)
		(fp_text user "${REFERENCE}"
			(at -0.4 2.7 0)
			(layer "F.Fab")
			(effects
				(font
					(size 0.7 0.7)
					(thickness 0.15)
				)
				(justify left bottom)
			)
		)
		(fp_text user "Author: Antmicro"
			(at -0.4 3.901 0)
			(layer "F.Fab")
			(effects
				(font
					(size 0.7 0.7)
					(thickness 0.15)
				)
				(justify left bottom)
			)
		)
		(fp_text user "License: Apache-2.0"
			(at -0.4 5.101 0)
			(layer "F.Fab")
			(effects
				(font
					(size 0.7 0.7)
					(thickness 0.15)
				)
				(justify left bottom)
			)
		)
		(pad "1" smd circle
			(at 0 0)
			(size 0.75 0.75)
			(layers "F.Cu" "F.Mask")
			(net 371 "Net-(U602-FLG)")
			(pinfunction "1")
			(pintype "passive")
		)
	)
	(footprint "antmicro-footprints:R_0402_1005Metric"
		(layer "F.Cu")
		(at 51.097962 134.8565 180)
		(descr "Resistor SMD 0402")
		(tags "resistor SMD 0402")
		(property "Reference" "R408"
			(at -0.743438 -1.3891 0)
			(layer "F.SilkS")
			(effects
				(font
					(size 0.7 0.7)
					(thickness 0.15)
				)
				(justify right bottom)
			)
		)
		(property "Value" "R_10k_0402"
			(at -1.011843 1.772047 0)
			(layer "F.Fab")
			(effects
				(font
					(size 0.7 0.7)
					(thickness 0.15)
				)
				(justify right bottom)
			)
		)
		(property "Datasheet" "https://www.bourns.com/docs/product-datasheets/cr.pdf"
			(at 0 0 180)
			(layer "F.Fab")
			(hide yes)
			(effects
				(font
					(size 1.27 1.27)
					(thickness 0.15)
				)
			)
		)
		(property "Manufacturer" "Bourns"
			(at 0 0 180)
			(unlocked yes)
			(layer "F.Fab")
			(hide yes)
			(effects
				(font
					(size 1 1)
					(thickness 0.15)
				)
			)
		)
		(property "MPN" "CR0402-FX-1002GLF"
			(at 0 0 180)
			(unlocked yes)
			(layer "F.Fab")
			(hide yes)
			(effects
				(font
					(size 1 1)
					(thickness 0.15)
				)
			)
		)
		(property "Val" "10k"
			(at 0 0 180)
			(unlocked yes)
			(layer "F.Fab")
			(hide yes)
			(effects
				(font
					(size 1 1)
					(thickness 0.15)
				)
			)
		)
		(property "License" "Apache-2.0"
			(at 0 0 180)
			(unlocked yes)
			(layer "F.Fab")
			(hide yes)
			(effects
				(font
					(size 1 1)
					(thickness 0.15)
				)
			)
		)
		(property "Author" "Antmicro"
			(at 0 0 180)
			(unlocked yes)
			(layer "F.Fab")
			(hide yes)
			(effects
				(font
					(size 1 1)
					(thickness 0.15)
				)
			)
		)
		(property "Tolerance" "1%"
			(at 0 0 180)
			(unlocked yes)
			(layer "F.Fab")
			(hide yes)
			(effects
				(font
					(size 1 1)
					(thickness 0.15)
				)
			)
		)
		(sheetname "/Ethernet/")
		(sheetfile "ethernet.kicad_sch")
		(attr smd)
		(fp_rect
			(start -0.925 -0.47)
			(end 0.925 0.47)
			(stroke
				(width 0.05)
				(type default)
			)
			(fill no)
			(layer "F.CrtYd")
		)
		(fp_rect
			(start -0.5 -0.25)
			(end 0.5 0.25)
			(stroke
				(width 0.15)
				(type solid)
			)
			(fill no)
			(layer "F.Fab")
		)
		(fp_text user "Author: Antmicro"
			(at -0.95 4.169 180)
			(layer "F.Fab")
			(effects
				(font
					(size 0.7 0.7)
					(thickness 0.15)
				)
				(justify left bottom)
			)
		)
		(fp_text user "${REFERENCE}"
			(at -0.95 3.168 180)
			(layer "F.Fab")
			(effects
				(font
					(size 0.7 0.7)
					(thickness 0.15)
				)
				(justify left bottom)
			)
		)
		(fp_text user "License: Apache-2.0"
			(at -0.95 5.169 180)
			(layer "F.Fab")
			(effects
				(font
					(size 0.7 0.7)
					(thickness 0.15)
				)
				(justify left bottom)
			)
		)
		(pad "1" smd roundrect
			(at -0.48 0 180)
			(size 0.59 0.64)
			(layers "F.Cu" "F.Mask" "F.Paste")
			(roundrect_rratio 0.25)
			(net 339 "/Ethernet/POE_ACTIVE")
			(pintype "passive")
		)
		(pad "2" smd roundrect
			(at 0.48 0 180)
			(size 0.59 0.64)
			(layers "F.Cu" "F.Mask" "F.Paste")
			(roundrect_rratio 0.25)
			(net 363 "/Ethernet/PG")
			(pintype "passive")
		)
	)
	(footprint "antmicro-footprints:LED_0603_1608Metric_G"
		(layer "F.Cu")
		(at 79.617962 124.5765)
		(descr "LED SMD 0603 Green")
		(tags "LED SMD 0603 Green")
		(property "Reference" "D907"
			(at -0.5 -0.66 0)
			(layer "F.SilkS")
			(effects
				(font
					(size 0.7 0.7)
					(thickness 0.15)
				)
				(justify left bottom)
			)
		)
		(property "Value" "LED_G_0603_KP-1608CGCK"
			(at -0.001 1.599 0)
			(layer "F.Fab")
			(effects
				(font
					(size 0.7 0.7)
					(thickness 0.15)
				)
				(justify left bottom)
			)
		)
		(property "Datasheet" "http://www.kingbright.com/attachments/file/psearch//000/00/00/KP-1608CGCK(Ver.23B).pdf"
			(at 0 0 0)
			(layer "F.Fab")
			(hide yes)
			(effects
				(font
					(size 1.27 1.27)
					(thickness 0.15)
				)
			)
		)
		(property "MPN" "KP-1608CGCK"
			(at 0 0 0)
			(unlocked yes)
			(layer "F.Fab")
			(hide yes)
			(effects
				(font
					(size 1 1)
					(thickness 0.15)
				)
			)
		)
		(property "Manufacturer" "Kingbright"
			(at 0 0 0)
			(unlocked yes)
			(layer "F.Fab")
			(hide yes)
			(effects
				(font
					(size 1 1)
					(thickness 0.15)
				)
			)
		)
		(property "Color" "Green"
			(at 0 0 0)
			(unlocked yes)
			(layer "F.Fab")
			(hide yes)
			(effects
				(font
					(size 1 1)
					(thickness 0.15)
				)
			)
		)
		(property "Author" "Antmicro"
			(at 0 0 0)
			(unlocked yes)
			(layer "F.Fab")
			(hide yes)
			(effects
				(font
					(size 1 1)
					(thickness 0.15)
				)
			)
		)
		(property "License" "Apache-2.0"
			(at 0 0 0)
			(unlocked yes)
			(layer "F.Fab")
			(hide yes)
			(effects
				(font
					(size 1 1)
					(thickness 0.15)
				)
			)
		)
		(sheetname "/USB/")
		(sheetfile "usb.kicad_sch")
		(attr smd)
		(fp_line
			(start -1.18 -0.319)
			(end -1.18 0.321)
			(stroke
				(width 0.15)
				(type solid)
			)
			(layer "F.SilkS")
		)
		(fp_line
			(start -0.094672 0.001008)
			(end -0.24 0.001008)
			(stroke
				(width 0.1)
				(type solid)
			)
			(layer "F.SilkS")
		)
		(fp_line
			(start -0.094672 0.001008)
			(end 0.105328 -0.198992)
			(stroke
				(width 0.1)
				(type solid)
			)
			(layer "F.SilkS")
		)
		(fp_line
			(start -0.094672 0.201008)
			(end -0.094672 -0.198992)
			(stroke
				(width 0.1)
				(type solid)
			)
			(layer "F.SilkS")
		)
		(fp_line
			(start 0.105328 0.001008)
			(end 0.24 0.001)
			(stroke
				(width 0.1)
				(type solid)
			)
			(layer "F.SilkS")
		)
		(fp_line
			(start 0.105328 0.201008)
			(end -0.094672 0.001008)
			(stroke
				(width 0.1)
				(type solid)
			)
			(layer "F.SilkS")
		)
		(fp_line
			(start 0.105328 0.201008)
			(end 0.105328 -0.198992)
			(stroke
				(width 0.1)
				(type solid)
			)
			(layer "F.SilkS")
		)
		(fp_line
			(start 0.22 -0.35)
			(end -0.22 -0.35)
			(stroke
				(width 0.15)
				(type solid)
			)
			(layer "F.SilkS")
		)
		(fp_line
			(start 0.22 0.35)
			(end -0.22 0.35)
			(stroke
				(width 0.15)
				(type solid)
			)
			(layer "F.SilkS")
		)
		(fp_rect
			(start 1.25 0.65)
			(end -1.25 -0.65)
			(stroke
				(width 0.05)
				(type solid)
			)
			(fill no)
			(layer "F.CrtYd")
		)
		(fp_line
			(start -0.199 -0.202)
			(end -0.199 0.1)
			(stroke
				(width 0.15)
				(type solid)
			)
			(layer "F.Fab")
		)
		(fp_line
			(start -0.199 0)
			(end -0.597 0)
			(stroke
				(width 0.15)
				(type solid)
			)
			(layer "F.Fab")
		)
		(fp_line
			(start -0.199 0.2)
			(end -0.199 0.1)
			(stroke
				(width 0.15)
				(type solid)
			)
			(layer "F.Fab")
		)
		(fp_line
			(start -0.101 0)
			(end 0.201 0.2)
			(stroke
				(width 0.15)
				(type solid)
			)
			(layer "F.Fab")
		)
		(fp_line
			(start 0.201 -0.202)
			(end -0.101 0)
			(stroke
				(width 0.15)
				(type solid)
			)
			(layer "F.Fab")
		)
		(fp_line
			(start 0.201 0)
			(end 0.201 -0.202)
			(stroke
				(width 0.15)
				(type solid)
			)
			(layer "F.Fab")
		)
		(fp_line
			(start 0.201 0.2)
			(end 0.201 0)
			(stroke
				(width 0.15)
				(type solid)
			)
			(layer "F.Fab")
		)
		(fp_line
			(start 0.599 0)
			(end 0.201 0)
			(stroke
				(width 0.15)
				(type solid)
			)
			(layer "F.Fab")
		)
		(fp_rect
			(start 0.848 0.4)
			(end -0.85 -0.402)
			(stroke
				(width 0.15)
				(type solid)
			)
			(fill no)
			(layer "F.Fab")
		)
		(fp_text user "License: Apache-2.0"
			(at -1.4224 3.599 0)
			(layer "F.Fab")
			(effects
				(font
					(size 0.7 0.7)
					(thickness 0.15)
				)
				(justify left bottom)
			)
		)
		(fp_text user "Author: Antmicro"
			(at -1.4224 4.799 0)
			(layer "F.Fab")
			(effects
				(font
					(size 0.7 0.7)
					(thickness 0.15)
				)
				(justify left bottom)
			)
		)
		(fp_text user "${REFERENCE}"
			(at -1.4224 5.999 0)
			(layer "F.Fab")
			(effects
				(font
					(size 0.7 0.7)
					(thickness 0.15)
				)
				(justify left bottom)
			)
		)
		(pad "1" smd roundrect
			(at -0.7 0 180)
			(size 0.8 1)
			(layers "F.Cu" "F.Mask" "F.Paste")
			(roundrect_rratio 0.2)
			(net 3 "GND")
			(pinfunction "C")
			(pintype "passive")
		)
		(pad "2" smd roundrect
			(at 0.7 0 180)
			(size 0.8 1)
			(layers "F.Cu" "F.Mask" "F.Paste")
			(roundrect_rratio 0.2)
			(net 484 "Net-(D907-A)")
			(pinfunction "A")
			(pintype "passive")
		)
	)
	(footprint "antmicro-footprints:R_0402_1005Metric"
		(layer "F.Cu")
		(at 117.88 154.3915 180)
		(descr "Resistor SMD 0402")
		(tags "resistor SMD 0402")
		(property "Reference" "R217"
			(at -3.525 -0.325 180)
			(layer "F.SilkS")
			(effects
				(font
					(size 0.7 0.7)
					(thickness 0.15)
				)
				(justify left bottom)
			)
		)
		(property "Value" "R_0R_0402"
			(at -1.011843 1.772047 180)
			(layer "F.Fab")
			(effects
				(font
					(size 0.7 0.7)
					(thickness 0.15)
				)
				(justify left bottom)
			)
		)
		(property "Datasheet" "https://industrial.panasonic.com/cdbs/www-data/pdf/RDA0000/AOA0000C301.pdf"
			(at 0 0 180)
			(layer "F.Fab")
			(hide yes)
			(effects
				(font
					(size 1.27 1.27)
					(thickness 0.15)
				)
			)
		)
		(property "Manufacturer" "Panasonic"
			(at 0 0 180)
			(unlocked yes)
			(layer "F.Fab")
			(hide yes)
			(effects
				(font
					(size 1 1)
					(thickness 0.15)
				)
			)
		)
		(property "MPN" "ERJ2GE0R00X"
			(at 0 0 180)
			(unlocked yes)
			(layer "F.Fab")
			(hide yes)
			(effects
				(font
					(size 1 1)
					(thickness 0.15)
				)
			)
		)
		(property "Val" "0R"
			(at 0 0 180)
			(unlocked yes)
			(layer "F.Fab")
			(hide yes)
			(effects
				(font
					(size 1 1)
					(thickness 0.15)
				)
			)
		)
		(property "License" "Apache-2.0"
			(at 0 0 180)
			(unlocked yes)
			(layer "F.Fab")
			(hide yes)
			(effects
				(font
					(size 1 1)
					(thickness 0.15)
				)
			)
		)
		(property "Author" "Antmicro"
			(at 0 0 180)
			(unlocked yes)
			(layer "F.Fab")
			(hide yes)
			(effects
				(font
					(size 1 1)
					(thickness 0.15)
				)
			)
		)
		(property "Tolerance" "~"
			(at 0 0 180)
			(unlocked yes)
			(layer "F.Fab")
			(hide yes)
			(effects
				(font
					(size 1 1)
					(thickness 0.15)
				)
			)
		)
		(property "Current" "1A"
			(at 0 0 180)
			(unlocked yes)
			(layer "F.Fab")
			(hide yes)
			(effects
				(font
					(size 1 1)
					(thickness 0.15)
				)
			)
		)
		(sheetname "/Compute module/")
		(sheetfile "compute-module.kicad_sch")
		(attr smd)
		(fp_rect
			(start -0.925 -0.47)
			(end 0.925 0.47)
			(stroke
				(width 0.05)
				(type default)
			)
			(fill no)
			(layer "F.CrtYd")
		)
		(fp_rect
			(start -0.5 -0.25)
			(end 0.5 0.25)
			(stroke
				(width 0.15)
				(type solid)
			)
			(fill no)
			(layer "F.Fab")
		)
		(fp_text user "${REFERENCE}"
			(at -0.95 3.168 180)
			(layer "F.Fab")
			(effects
				(font
					(size 0.7 0.7)
					(thickness 0.15)
				)
				(justify left bottom)
			)
		)
		(fp_text user "License: Apache-2.0"
			(at -0.95 5.169 180)
			(layer "F.Fab")
			(effects
				(font
					(size 0.7 0.7)
					(thickness 0.15)
				)
				(justify left bottom)
			)
		)
		(fp_text user "Author: Antmicro"
			(at -0.95 4.169 180)
			(layer "F.Fab")
			(effects
				(font
					(size 0.7 0.7)
					(thickness 0.15)
				)
				(justify left bottom)
			)
		)
		(pad "1" smd roundrect
			(at -0.48 0 180)
			(size 0.59 0.64)
			(layers "F.Cu" "F.Mask" "F.Paste")
			(roundrect_rratio 0.25)
			(net 168 "/Compute module/NVMe.TX1_N")
			(pintype "passive")
		)
		(pad "2" smd roundrect
			(at 0.48 0 180)
			(size 0.59 0.64)
			(layers "F.Cu" "F.Mask" "F.Paste")
			(roundrect_rratio 0.25)
			(net 146 "/Compute module/T1_N")
			(pintype "passive")
		)
	)
	(footprint "antmicro-footprints:R_0402_1005Metric"
		(layer "F.Cu")
		(at 140.132962 131.7365)
		(descr "Resistor SMD 0402")
		(tags "resistor SMD 0402")
		(property "Reference" "R259"
			(at -3.665 0.38 0)
			(layer "F.SilkS")
			(effects
				(font
					(size 0.7 0.7)
					(thickness 0.15)
				)
				(justify left bottom)
			)
		)
		(property "Value" "R_0R_0402"
			(at -1.011843 1.772047 0)
			(layer "F.Fab")
			(effects
				(font
					(size 0.7 0.7)
					(thickness 0.15)
				)
				(justify left bottom)
			)
		)
		(property "Datasheet" "https://industrial.panasonic.com/cdbs/www-data/pdf/RDA0000/AOA0000C301.pdf"
			(at 0 0 0)
			(layer "F.Fab")
			(hide yes)
			(effects
				(font
					(size 1.27 1.27)
					(thickness 0.15)
				)
			)
		)
		(property "Manufacturer" "Panasonic"
			(at 0 0 0)
			(unlocked yes)
			(layer "F.Fab")
			(hide yes)
			(effects
				(font
					(size 1 1)
					(thickness 0.15)
				)
			)
		)
		(property "MPN" "ERJ2GE0R00X"
			(at 0 0 0)
			(unlocked yes)
			(layer "F.Fab")
			(hide yes)
			(effects
				(font
					(size 1 1)
					(thickness 0.15)
				)
			)
		)
		(property "Val" "0R"
			(at 0 0 0)
			(unlocked yes)
			(layer "F.Fab")
			(hide yes)
			(effects
				(font
					(size 1 1)
					(thickness 0.15)
				)
			)
		)
		(property "License" "Apache-2.0"
			(at 0 0 0)
			(unlocked yes)
			(layer "F.Fab")
			(hide yes)
			(effects
				(font
					(size 1 1)
					(thickness 0.15)
				)
			)
		)
		(property "Author" "Antmicro"
			(at 0 0 0)
			(unlocked yes)
			(layer "F.Fab")
			(hide yes)
			(effects
				(font
					(size 1 1)
					(thickness 0.15)
				)
			)
		)
		(property "Tolerance" "~"
			(at 0 0 0)
			(unlocked yes)
			(layer "F.Fab")
			(hide yes)
			(effects
				(font
					(size 1 1)
					(thickness 0.15)
				)
			)
		)
		(property "Current" "1A"
			(at 0 0 0)
			(unlocked yes)
			(layer "F.Fab")
			(hide yes)
			(effects
				(font
					(size 1 1)
					(thickness 0.15)
				)
			)
		)
		(sheetname "/Compute module/")
		(sheetfile "compute-module.kicad_sch")
		(attr smd)
		(fp_rect
			(start -0.925 -0.47)
			(end 0.925 0.47)
			(stroke
				(width 0.05)
				(type default)
			)
			(fill no)
			(layer "F.CrtYd")
		)
		(fp_rect
			(start -0.5 -0.25)
			(end 0.5 0.25)
			(stroke
				(width 0.15)
				(type solid)
			)
			(fill no)
			(layer "F.Fab")
		)
		(fp_text user "License: Apache-2.0"
			(at -0.95 5.169 0)
			(layer "F.Fab")
			(effects
				(font
					(size 0.7 0.7)
					(thickness 0.15)
				)
				(justify left bottom)
			)
		)
		(fp_text user "Author: Antmicro"
			(at -0.95 4.169 0)
			(layer "F.Fab")
			(effects
				(font
					(size 0.7 0.7)
					(thickness 0.15)
				)
				(justify left bottom)
			)
		)
		(fp_text user "${REFERENCE}"
			(at -0.95 3.168 0)
			(layer "F.Fab")
			(effects
				(font
					(size 0.7 0.7)
					(thickness 0.15)
				)
				(justify left bottom)
			)
		)
		(pad "1" smd roundrect
			(at -0.48 0)
			(size 0.59 0.64)
			(layers "F.Cu" "F.Mask" "F.Paste")
			(roundrect_rratio 0.25)
			(net 446 "/Compute module/GPIO.1{slash}SCL0")
			(pintype "passive")
		)
		(pad "2" smd roundrect
			(at 0.48 0)
			(size 0.59 0.64)
			(layers "F.Cu" "F.Mask" "F.Paste")
			(roundrect_rratio 0.25)
			(net 140 "/CSI/I_{2}C_CSI0.SCL")
			(pintype "passive")
		)
	)
	(footprint "antmicro-footprints:R_0402_1005Metric"
		(layer "F.Cu")
		(at 108.1 155.8415 180)
		(descr "Resistor SMD 0402")
		(tags "resistor SMD 0402")
		(property "Reference" "R225"
			(at 1.91 -2.495 180)
			(layer "F.SilkS")
			(effects
				(font
					(size 0.7 0.7)
					(thickness 0.15)
				)
				(justify left bottom)
			)
		)
		(property "Value" "R_0R_0402"
			(at -1.011843 1.772047 180)
			(layer "F.Fab")
			(effects
				(font
					(size 0.7 0.7)
					(thickness 0.15)
				)
				(justify left bottom)
			)
		)
		(property "Datasheet" "https://industrial.panasonic.com/cdbs/www-data/pdf/RDA0000/AOA0000C301.pdf"
			(at 0 0 180)
			(layer "F.Fab")
			(hide yes)
			(effects
				(font
					(size 1.27 1.27)
					(thickness 0.15)
				)
			)
		)
		(property "Manufacturer" "Panasonic"
			(at 0 0 180)
			(unlocked yes)
			(layer "F.Fab")
			(hide yes)
			(effects
				(font
					(size 1 1)
					(thickness 0.15)
				)
			)
		)
		(property "MPN" "ERJ2GE0R00X"
			(at 0 0 180)
			(unlocked yes)
			(layer "F.Fab")
			(hide yes)
			(effects
				(font
					(size 1 1)
					(thickness 0.15)
				)
			)
		)
		(property "Val" "0R"
			(at 0 0 180)
			(unlocked yes)
			(layer "F.Fab")
			(hide yes)
			(effects
				(font
					(size 1 1)
					(thickness 0.15)
				)
			)
		)
		(property "License" "Apache-2.0"
			(at 0 0 180)
			(unlocked yes)
			(layer "F.Fab")
			(hide yes)
			(effects
				(font
					(size 1 1)
					(thickness 0.15)
				)
			)
		)
		(property "Author" "Antmicro"
			(at 0 0 180)
			(unlocked yes)
			(layer "F.Fab")
			(hide yes)
			(effects
				(font
					(size 1 1)
					(thickness 0.15)
				)
			)
		)
		(property "Tolerance" "~"
			(at 0 0 180)
			(unlocked yes)
			(layer "F.Fab")
			(hide yes)
			(effects
				(font
					(size 1 1)
					(thickness 0.15)
				)
			)
		)
		(property "Current" "1A"
			(at 0 0 180)
			(unlocked yes)
			(layer "F.Fab")
			(hide yes)
			(effects
				(font
					(size 1 1)
					(thickness 0.15)
				)
			)
		)
		(sheetname "/Compute module/")
		(sheetfile "compute-module.kicad_sch")
		(attr smd)
		(fp_rect
			(start -0.925 -0.47)
			(end 0.925 0.47)
			(stroke
				(width 0.05)
				(type default)
			)
			(fill no)
			(layer "F.CrtYd")
		)
		(fp_rect
			(start -0.5 -0.25)
			(end 0.5 0.25)
			(stroke
				(width 0.15)
				(type solid)
			)
			(fill no)
			(layer "F.Fab")
		)
		(fp_text user "License: Apache-2.0"
			(at -0.95 5.169 180)
			(layer "F.Fab")
			(effects
				(font
					(size 0.7 0.7)
					(thickness 0.15)
				)
				(justify left bottom)
			)
		)
		(fp_text user "Author: Antmicro"
			(at -0.95 4.169 180)
			(layer "F.Fab")
			(effects
				(font
					(size 0.7 0.7)
					(thickness 0.15)
				)
				(justify left bottom)
			)
		)
		(fp_text user "${REFERENCE}"
			(at -0.95 3.168 180)
			(layer "F.Fab")
			(effects
				(font
					(size 0.7 0.7)
					(thickness 0.15)
				)
				(justify left bottom)
			)
		)
		(pad "1" smd roundrect
			(at -0.48 0 180)
			(size 0.59 0.64)
			(layers "F.Cu" "F.Mask" "F.Paste")
			(roundrect_rratio 0.25)
			(net 149 "/Compute module/R2_N")
			(pintype "passive")
		)
		(pad "2" smd roundrect
			(at 0.48 0 180)
			(size 0.59 0.64)
			(layers "F.Cu" "F.Mask" "F.Paste")
			(roundrect_rratio 0.25)
			(net 162 "/Compute module/NVMe.RX2_N")
			(pintype "passive")
		)
	)
	(footprint "antmicro-footprints:UQFN-12_2x1.7mm_P0.4mm_Texas_RUT"
		(layer "F.Cu")
		(at 85.517962 146.6165 -90)
		(descr "Texas_R_PUQFN-N12")
		(tags "Texas_R_PUQFN-N12")
		(property "Reference" "U907"
			(at -0.85 0.6 180)
			(layer "F.SilkS")
			(effects
				(font
					(size 0.7 0.7)
					(thickness 0.15)
				)
				(justify right bottom)
			)
		)
		(property "Value" "TXB0104_UQFN"
			(at 0 2.35 90)
			(layer "F.Fab")
			(effects
				(font
					(size 0.7 0.7)
					(thickness 0.15)
				)
				(justify right bottom)
			)
		)
		(property "Datasheet" "http://www.ti.com/lit/ds/symlink/txb0104.pdf"
			(at 0 0 270)
			(layer "F.Fab")
			(hide yes)
			(effects
				(font
					(size 1.27 1.27)
					(thickness 0.15)
				)
			)
		)
		(property "Manufacturer" "Texas Instruments"
			(at 0 0 270)
			(unlocked yes)
			(layer "F.Fab")
			(hide yes)
			(effects
				(font
					(size 1 1)
					(thickness 0.15)
				)
			)
		)
		(property "MPN" "TXB0104RUTR"
			(at 0 0 270)
			(unlocked yes)
			(layer "F.Fab")
			(hide yes)
			(effects
				(font
					(size 1 1)
					(thickness 0.15)
				)
			)
		)
		(property "Author" "Antmicro"
			(at 0 0 270)
			(unlocked yes)
			(layer "F.Fab")
			(hide yes)
			(effects
				(font
					(size 1 1)
					(thickness 0.15)
				)
			)
		)
		(property "License" "Apache-2.0"
			(at 0 0 270)
			(unlocked yes)
			(layer "F.Fab")
			(hide yes)
			(effects
				(font
					(size 1 1)
					(thickness 0.15)
				)
			)
		)
		(property ki_fp_filters "Texas*R*PUQFN*N12*")
		(sheetname "/USB/")
		(sheetfile "usb.kicad_sch")
		(attr smd)
		(fp_line
			(start 0.497 1.3)
			(end -0.5 1.3)
			(stroke
				(width 0.15)
				(type solid)
			)
			(layer "F.SilkS")
		)
		(fp_line
			(start 0.597 -1.301)
			(end -0.55 -1.301)
			(stroke
				(width 0.15)
				(type solid)
			)
			(layer "F.SilkS")
		)
		(fp_circle
			(center -0.85 -1.2)
			(end -0.8 -1.2)
			(stroke
				(width 0.15)
				(type solid)
			)
			(fill yes)
			(layer "F.SilkS")
		)
		(fp_rect
			(start -1.1 -1.3)
			(end 1.1 1.3)
			(stroke
				(width 0.05)
				(type solid)
			)
			(fill no)
			(layer "F.CrtYd")
		)
		(fp_line
			(start -0.85 0.997)
			(end -0.85 -0.5)
			(stroke
				(width 0.15)
				(type solid)
			)
			(layer "F.Fab")
		)
		(fp_line
			(start 0.847 0.997)
			(end -0.85 0.997)
			(stroke
				(width 0.15)
				(type solid)
			)
			(layer "F.Fab")
		)
		(fp_line
			(start -0.5 -1)
			(end -0.85 -0.5)
			(stroke
				(width 0.15)
				(type solid)
			)
			(layer "F.Fab")
		)
		(fp_line
			(start -0.5 -1)
			(end 0.847 -1)
			(stroke
				(width 0.15)
				(type solid)
			)
			(layer "F.Fab")
		)
		(fp_line
			(start 0.847 -1)
			(end 0.847 0.997)
			(stroke
				(width 0.15)
				(type solid)
			)
			(layer "F.Fab")
		)
		(fp_text user "License: Apache-2.0"
			(at -1.1 6.75 270)
			(layer "F.Fab")
			(effects
				(font
					(size 0.7 0.7)
					(thickness 0.15)
				)
				(justify left bottom)
			)
		)
		(fp_text user "Author: Antmicro"
			(at -1.1 4.35 270)
			(layer "F.Fab")
			(effects
				(font
					(size 0.7 0.7)
					(thickness 0.15)
				)
				(justify left bottom)
			)
		)
		(fp_text user "${REFERENCE}"
			(at -1.1 5.55 270)
			(layer "F.Fab")
			(effects
				(font
					(size 0.7 0.7)
					(thickness 0.15)
				)
				(justify left bottom)
			)
		)
		(pad "1" smd rect
			(at -0.653 -0.803 180)
			(size 0.2 0.6)
			(layers "F.Cu" "F.Mask" "F.Paste")
			(net 27 "/USB/USB_3V3")
			(pinfunction "VCCA")
			(pintype "power_in")
		)
		(pad "1" smd rect
			(at -0.425 -0.975 270)
			(size 0.15 0.25)
			(layers "F.Cu" "F.Mask" "F.Paste")
			(net 27 "/USB/USB_3V3")
			(pinfunction "VCCA")
			(pintype "power_in")
		)
		(pad "2" smd rect
			(at -0.653 -0.403 180)
			(size 0.2 0.6)
			(layers "F.Cu" "F.Mask" "F.Paste")
			(net 3 "GND")
			(pinfunction "A1")
			(pintype "tri_state")
		)
		(pad "3" smd rect
			(at -0.653 0 180)
			(size 0.2 0.6)
			(layers "F.Cu" "F.Mask" "F.Paste")
			(net 3 "GND")
			(pinfunction "A2")
			(pintype "tri_state")
		)
		(pad "4" smd rect
			(at -0.653 0.4 180)
			(size 0.2 0.6)
			(layers "F.Cu" "F.Mask" "F.Paste")
			(net 457 "/USB/BDBUS1")
			(pinfunction "A3")
			(pintype "tri_state")
		)
		(pad "5" smd rect
			(at -0.653 0.8 180)
			(size 0.2 0.6)
			(layers "F.Cu" "F.Mask" "F.Paste")
			(net 456 "/USB/BDBUS0")
			(pinfunction "A4")
			(pintype "tri_state")
		)
		(pad "6" smd rect
			(at 0 0.8 180)
			(size 0.6 0.2)
			(layers "F.Cu" "F.Mask" "F.Paste")
			(net 3 "GND")
			(pinfunction "GND")
			(pintype "power_in")
		)
		(pad "7" smd rect
			(at 0.65 0.8 180)
			(size 0.2 0.6)
			(layers "F.Cu" "F.Mask" "F.Paste")
			(net 187 "/Compute module/UART.1.RX")
			(pinfunction "B4")
			(pintype "tri_state")
		)
		(pad "8" smd rect
			(at 0.65 0.4 180)
			(size 0.2 0.6)
			(layers "F.Cu" "F.Mask" "F.Paste")
			(net 186 "/Compute module/UART.1.TX")
			(pinfunction "B3")
			(pintype "tri_state")
		)
		(pad "9" smd rect
			(at 0.65 0 180)
			(size 0.2 0.6)
			(layers "F.Cu" "F.Mask" "F.Paste")
			(net 3 "GND")
			(pinfunction "B2")
			(pintype "tri_state")
		)
		(pad "10" smd rect
			(at 0.65 -0.403 180)
			(size 0.2 0.6)
			(layers "F.Cu" "F.Mask" "F.Paste")
			(net 3 "GND")
			(pinfunction "B1")
			(pintype "tri_state")
		)
		(pad "11" smd rect
			(at 0.65 -0.803 180)
			(size 0.2 0.6)
			(layers "F.Cu" "F.Mask" "F.Paste")
			(net 9 "+3V3")
			(pinfunction "VCCB")
			(pintype "power_in")
		)
		(pad "12" smd rect
			(at 0 -0.803 180)
			(size 0.6 0.2)
			(layers "F.Cu" "F.Mask" "F.Paste")
			(net 455 "Net-(Q905-D)")
			(pinfunction "OE")
			(pintype "input")
		)
	)
	(footprint "antmicro-footprints:TP_SMD_0.75mm"
		(layer "F.Cu")
		(at 97.697962 122.434)
		(property "Reference" "TP912"
			(at 25.935 26.15 0)
			(layer "F.SilkS")
			(effects
				(font
					(size 0.7 0.7)
					(thickness 0.15)
				)
				(justify left bottom)
			)
		)
		(property "Value" "TP_0.75mm_SMD"
			(at 0 1.2 0)
			(layer "F.Fab")
			(effects
				(font
					(size 0.7 0.7)
					(thickness 0.15)
				)
				(justify left bottom)
			)
		)
		(property "MPN" ""
			(at 0 0 0)
			(unlocked yes)
			(layer "F.Fab")
			(hide yes)
			(effects
				(font
					(size 1 1)
					(thickness 0.15)
				)
			)
		)
		(property "Manufacturer" ""
			(at 0 0 0)
			(unlocked yes)
			(layer "F.Fab")
			(hide yes)
			(effects
				(font
					(size 1 1)
					(thickness 0.15)
				)
			)
		)
		(property "Author" "Antmicro"
			(at 0 0 0)
			(unlocked yes)
			(layer "F.Fab")
			(hide yes)
			(effects
				(font
					(size 1 1)
					(thickness 0.15)
				)
			)
		)
		(property "License" "Apache-2.0"
			(at 0 0 0)
			(unlocked yes)
			(layer "F.Fab")
			(hide yes)
			(effects
				(font
					(size 1 1)
					(thickness 0.15)
				)
			)
		)
		(sheetname "/USB/")
		(sheetfile "usb.kicad_sch")
		(attr exclude_from_pos_files exclude_from_bom)
		(fp_circle
			(center 0 0)
			(end 0.475 0)
			(stroke
				(width 0.05)
				(type default)
			)
			(fill no)
			(layer "F.CrtYd")
		)
		(fp_text user "Author: Antmicro"
			(at -0.4 3.901 0)
			(layer "F.Fab")
			(effects
				(font
					(size 0.7 0.7)
					(thickness 0.15)
				)
				(justify left bottom)
			)
		)
		(fp_text user "${REFERENCE}"
			(at -0.4 2.7 0)
			(layer "F.Fab")
			(effects
				(font
					(size 0.7 0.7)
					(thickness 0.15)
				)
				(justify left bottom)
			)
		)
		(fp_text user "License: Apache-2.0"
			(at -0.4 5.101 0)
			(layer "F.Fab")
			(effects
				(font
					(size 0.7 0.7)
					(thickness 0.15)
				)
				(justify left bottom)
			)
		)
		(pad "1" smd circle
			(at 0 0)
			(size 0.75 0.75)
			(layers "F.Cu" "F.Mask")
			(net 437 "Net-(U906-OUT2)")
			(pinfunction "1")
			(pintype "passive")
		)
	)
	(footprint "antmicro-footprints:L_TE_0603_1811Metric"
		(layer "F.Cu")
		(at 68.35 176.79 -90)
		(property "Reference" "L801"
			(at -1.39 1.45 90)
			(layer "F.SilkS")
			(effects
				(font
					(size 0.7 0.7)
					(thickness 0.15)
				)
				(justify right top)
			)
		)
		(property "Value" "L_160n_0.28A_0603"
			(at -1.41 1.759999 90)
			(layer "F.Fab")
			(effects
				(font
					(size 0.7 0.7)
					(thickness 0.15)
				)
				(justify right top)
			)
		)
		(property "Datasheet" "https://www.te.com/commerce/DocumentDelivery/DDEController?Action=showdoc&DocId=Data+Sheet%7F1773163%7FE%7Fpdf%7FEnglish%7FENG_DS_1773163_E.pdf"
			(at 0 0 90)
			(layer "F.Fab")
			(effects
				(font
					(size 0.7 0.7)
					(thickness 0.15)
				)
				(justify right top)
			)
		)
		(property "Description" "RF Inductor - 160 nH, 5%, 280 mA, 0603"
			(at 0 0 90)
			(layer "F.Fab")
			(effects
				(font
					(size 0.7 0.7)
					(thickness 0.15)
				)
				(justify right top)
			)
		)
		(property "Val" "160 nH"
			(at 0 0 270)
			(unlocked yes)
			(layer "F.Fab")
			(hide yes)
			(effects
				(font
					(size 1 1)
					(thickness 0.15)
				)
			)
		)
		(property "Manufacturer" "TE Connectivity"
			(at 0 0 270)
			(unlocked yes)
			(layer "F.Fab")
			(hide yes)
			(effects
				(font
					(size 1 1)
					(thickness 0.15)
				)
			)
		)
		(property "MPN" "36501JR16JTDG"
			(at 0 0 270)
			(unlocked yes)
			(layer "F.Fab")
			(hide yes)
			(effects
				(font
					(size 1 1)
					(thickness 0.15)
				)
			)
		)
		(property "ISat" ""
			(at 0 0 270)
			(unlocked yes)
			(layer "F.Fab")
			(hide yes)
			(effects
				(font
					(size 1 1)
					(thickness 0.15)
				)
			)
		)
		(property "IMax" "0.28 A"
			(at 0 0 270)
			(unlocked yes)
			(layer "F.Fab")
			(hide yes)
			(effects
				(font
					(size 1 1)
					(thickness 0.15)
				)
			)
		)
		(property "Size" "1.8 x 1.12"
			(at 0 0 270)
			(unlocked yes)
			(layer "F.Fab")
			(hide yes)
			(effects
				(font
					(size 1 1)
					(thickness 0.15)
				)
			)
		)
		(property "Author" "Antmicro"
			(at 0 0 270)
			(unlocked yes)
			(layer "F.Fab")
			(hide yes)
			(effects
				(font
					(size 1 1)
					(thickness 0.15)
				)
			)
		)
		(property "License" "Apache-2.0"
			(at 0 0 270)
			(unlocked yes)
			(layer "F.Fab")
			(hide yes)
			(effects
				(font
					(size 1 1)
					(thickness 0.15)
				)
			)
		)
		(sheetname "/Peripherals/")
		(sheetfile "peripherals.kicad_sch")
		(attr smd)
		(fp_line
			(start -0.15 0.4)
			(end 0.15 0.4)
			(stroke
				(width 0.15)
				(type solid)
			)
			(layer "F.SilkS")
		)
		(fp_line
			(start -0.15 -0.4)
			(end 0.15 -0.4)
			(stroke
				(width 0.15)
				(type solid)
			)
			(layer "F.SilkS")
		)
		(fp_poly
			(pts
				(xy -1.06 -0.66) (xy 1.06 -0.66) (xy 1.06 0.66) (xy -1.06 0.66)
			)
			(stroke
				(width 0.05)
				(type solid)
			)
			(fill no)
			(layer "F.CrtYd")
		)
		(fp_poly
			(pts
				(xy -0.8 -0.4) (xy 0.8 -0.4) (xy 0.8 0.4) (xy -0.8 0.4)
			)
			(stroke
				(width 0.15)
				(type solid)
			)
			(fill no)
			(layer "F.Fab")
		)
		(fp_text user "${REFERENCE}"
			(at -1.41 2.960001 90)
			(layer "F.Fab")
			(effects
				(font
					(size 0.7 0.7)
					(thickness 0.15)
				)
				(justify right top)
			)
		)
		(fp_text user "Author: Antmicro"
			(at -1.41 4.16 90)
			(layer "F.Fab")
			(effects
				(font
					(size 0.7 0.7)
					(thickness 0.15)
				)
				(justify right top)
			)
		)
		(fp_text user "License: Apache-2.0"
			(at -1.41 5.36 90)
			(layer "F.Fab")
			(effects
				(font
					(size 0.7 0.7)
					(thickness 0.15)
				)
				(justify right top)
			)
		)
		(pad "1" smd roundrect
			(at -0.64 0 270)
			(size 0.64 1.02)
			(layers "F.Cu" "F.Mask" "F.Paste")
			(roundrect_rratio 0.2)
			(net 325 "Net-(U801-TX1)")
			(pintype "passive")
		)
		(pad "2" smd roundrect
			(at 0.64 0 270)
			(size 0.64 1.02)
			(layers "F.Cu" "F.Mask" "F.Paste")
			(roundrect_rratio 0.2)
			(net 109 "Net-(C816-Pad2)")
			(pintype "passive")
		)
	)
	(footprint "antmicro-footprints:TP_SMD_0.75mm"
		(layer "F.Cu")
		(at 134.65 153.65)
		(property "Reference" "TP604"
			(at -2.95 -0.7 0)
			(layer "F.SilkS")
			(effects
				(font
					(size 0.7 0.7)
					(thickness 0.15)
				)
				(justify left bottom)
			)
		)
		(property "Value" "TP_0.75mm_SMD"
			(at 0 1.2 0)
			(layer "F.Fab")
			(effects
				(font
					(size 0.7 0.7)
					(thickness 0.15)
				)
				(justify left bottom)
			)
		)
		(property "MPN" ""
			(at 0 0 0)
			(unlocked yes)
			(layer "F.Fab")
			(hide yes)
			(effects
				(font
					(size 1 1)
					(thickness 0.15)
				)
			)
		)
		(property "Manufacturer" ""
			(at 0 0 0)
			(unlocked yes)
			(layer "F.Fab")
			(hide yes)
			(effects
				(font
					(size 1 1)
					(thickness 0.15)
				)
			)
		)
		(property "Author" "Antmicro"
			(at 0 0 0)
			(unlocked yes)
			(layer "F.Fab")
			(hide yes)
			(effects
				(font
					(size 1 1)
					(thickness 0.15)
				)
			)
		)
		(property "License" "Apache-2.0"
			(at 0 0 0)
			(unlocked yes)
			(layer "F.Fab")
			(hide yes)
			(effects
				(font
					(size 1 1)
					(thickness 0.15)
				)
			)
		)
		(sheetname "/CSI/")
		(sheetfile "csi.kicad_sch")
		(attr exclude_from_pos_files exclude_from_bom)
		(fp_circle
			(center 0 0)
			(end 0.475 0)
			(stroke
				(width 0.05)
				(type default)
			)
			(fill no)
			(layer "F.CrtYd")
		)
		(fp_text user "License: Apache-2.0"
			(at -0.4 5.101 0)
			(layer "F.Fab")
			(effects
				(font
					(size 0.7 0.7)
					(thickness 0.15)
				)
				(justify left bottom)
			)
		)
		(fp_text user "${REFERENCE}"
			(at -0.4 2.7 0)
			(layer "F.Fab")
			(effects
				(font
					(size 0.7 0.7)
					(thickness 0.15)
				)
				(justify left bottom)
			)
		)
		(fp_text user "Author: Antmicro"
			(at -0.4 3.901 0)
			(layer "F.Fab")
			(effects
				(font
					(size 0.7 0.7)
					(thickness 0.15)
				)
				(justify left bottom)
			)
		)
		(pad "1" smd circle
			(at 0 0)
			(size 0.75 0.75)
			(layers "F.Cu" "F.Mask")
			(net 19 "/CSI/CSI_3V3")
			(pinfunction "1")
			(pintype "passive")
		)
	)
	(footprint "antmicro-footprints:R_0402_1005Metric"
		(layer "F.Cu")
		(at 117.88 156.7915 180)
		(descr "Resistor SMD 0402")
		(tags "resistor SMD 0402")
		(property "Reference" "R221"
			(at -3.5 -0.325 180)
			(layer "F.SilkS")
			(effects
				(font
					(size 0.7 0.7)
					(thickness 0.15)
				)
				(justify left bottom)
			)
		)
		(property "Value" "R_0R_0402"
			(at -1.011843 1.772047 180)
			(layer "F.Fab")
			(effects
				(font
					(size 0.7 0.7)
					(thickness 0.15)
				)
				(justify left bottom)
			)
		)
		(property "Datasheet" "https://industrial.panasonic.com/cdbs/www-data/pdf/RDA0000/AOA0000C301.pdf"
			(at 0 0 180)
			(layer "F.Fab")
			(hide yes)
			(effects
				(font
					(size 1.27 1.27)
					(thickness 0.15)
				)
			)
		)
		(property "Manufacturer" "Panasonic"
			(at 0 0 180)
			(unlocked yes)
			(layer "F.Fab")
			(hide yes)
			(effects
				(font
					(size 1 1)
					(thickness 0.15)
				)
			)
		)
		(property "MPN" "ERJ2GE0R00X"
			(at 0 0 180)
			(unlocked yes)
			(layer "F.Fab")
			(hide yes)
			(effects
				(font
					(size 1 1)
					(thickness 0.15)
				)
			)
		)
		(property "Val" "0R"
			(at 0 0 180)
			(unlocked yes)
			(layer "F.Fab")
			(hide yes)
			(effects
				(font
					(size 1 1)
					(thickness 0.15)
				)
			)
		)
		(property "License" "Apache-2.0"
			(at 0 0 180)
			(unlocked yes)
			(layer "F.Fab")
			(hide yes)
			(effects
				(font
					(size 1 1)
					(thickness 0.15)
				)
			)
		)
		(property "Author" "Antmicro"
			(at 0 0 180)
			(unlocked yes)
			(layer "F.Fab")
			(hide yes)
			(effects
				(font
					(size 1 1)
					(thickness 0.15)
				)
			)
		)
		(property "Tolerance" "~"
			(at 0 0 180)
			(unlocked yes)
			(layer "F.Fab")
			(hide yes)
			(effects
				(font
					(size 1 1)
					(thickness 0.15)
				)
			)
		)
		(property "Current" "1A"
			(at 0 0 180)
			(unlocked yes)
			(layer "F.Fab")
			(hide yes)
			(effects
				(font
					(size 1 1)
					(thickness 0.15)
				)
			)
		)
		(sheetname "/Compute module/")
		(sheetfile "compute-module.kicad_sch")
		(attr smd)
		(fp_rect
			(start -0.925 -0.47)
			(end 0.925 0.47)
			(stroke
				(width 0.05)
				(type default)
			)
			(fill no)
			(layer "F.CrtYd")
		)
		(fp_rect
			(start -0.5 -0.25)
			(end 0.5 0.25)
			(stroke
				(width 0.15)
				(type solid)
			)
			(fill no)
			(layer "F.Fab")
		)
		(fp_text user "Author: Antmicro"
			(at -0.95 4.169 180)
			(layer "F.Fab")
			(effects
				(font
					(size 0.7 0.7)
					(thickness 0.15)
				)
				(justify left bottom)
			)
		)
		(fp_text user "License: Apache-2.0"
			(at -0.95 5.169 180)
			(layer "F.Fab")
			(effects
				(font
					(size 0.7 0.7)
					(thickness 0.15)
				)
				(justify left bottom)
			)
		)
		(fp_text user "${REFERENCE}"
			(at -0.95 3.168 180)
			(layer "F.Fab")
			(effects
				(font
					(size 0.7 0.7)
					(thickness 0.15)
				)
				(justify left bottom)
			)
		)
		(pad "1" smd roundrect
			(at -0.48 0 180)
			(size 0.59 0.64)
			(layers "F.Cu" "F.Mask" "F.Paste")
			(roundrect_rratio 0.25)
			(net 164 "/Compute module/NVMe.TX2_N")
			(pintype "passive")
		)
		(pad "2" smd roundrect
			(at 0.48 0 180)
			(size 0.59 0.64)
			(layers "F.Cu" "F.Mask" "F.Paste")
			(roundrect_rratio 0.25)
			(net 152 "/Compute module/T2_N")
			(pintype "passive")
		)
	)
	(footprint "antmicro-footprints:R_0402_1005Metric"
		(layer "F.Cu")
		(at 56.392962 134.3665 90)
		(descr "Resistor SMD 0402")
		(tags "resistor SMD 0402")
		(property "Reference" "R419"
			(at -1.985 3.495 90)
			(layer "F.SilkS")
			(effects
				(font
					(size 0.7 0.7)
					(thickness 0.15)
				)
				(justify left bottom)
			)
		)
		(property "Value" "R_470k_0402"
			(at -1.011843 1.772047 90)
			(layer "F.Fab")
			(effects
				(font
					(size 0.7 0.7)
					(thickness 0.15)
				)
				(justify left bottom)
			)
		)
		(property "Datasheet" "https://www.bourns.com/docs/product-datasheets/cr.pdf"
			(at 0 0 90)
			(layer "F.Fab")
			(hide yes)
			(effects
				(font
					(size 1.27 1.27)
					(thickness 0.15)
				)
			)
		)
		(property "Manufacturer" "Bourns"
			(at 0 0 90)
			(unlocked yes)
			(layer "F.Fab")
			(hide yes)
			(effects
				(font
					(size 1 1)
					(thickness 0.15)
				)
			)
		)
		(property "MPN" "CR0402-FX-4703GLF"
			(at 0 0 90)
			(unlocked yes)
			(layer "F.Fab")
			(hide yes)
			(effects
				(font
					(size 1 1)
					(thickness 0.15)
				)
			)
		)
		(property "Val" "470k"
			(at 0 0 90)
			(unlocked yes)
			(layer "F.Fab")
			(hide yes)
			(effects
				(font
					(size 1 1)
					(thickness 0.15)
				)
			)
		)
		(property "License" "Apache-2.0"
			(at 0 0 90)
			(unlocked yes)
			(layer "F.Fab")
			(hide yes)
			(effects
				(font
					(size 1 1)
					(thickness 0.15)
				)
			)
		)
		(property "Author" "Antmicro"
			(at 0 0 90)
			(unlocked yes)
			(layer "F.Fab")
			(hide yes)
			(effects
				(font
					(size 1 1)
					(thickness 0.15)
				)
			)
		)
		(property "Tolerance" "1%"
			(at 0 0 90)
			(unlocked yes)
			(layer "F.Fab")
			(hide yes)
			(effects
				(font
					(size 1 1)
					(thickness 0.15)
				)
			)
		)
		(sheetname "/Ethernet/")
		(sheetfile "ethernet.kicad_sch")
		(attr smd exclude_from_pos_files exclude_from_bom dnp)
		(fp_rect
			(start -0.925 -0.47)
			(end 0.925 0.47)
			(stroke
				(width 0.05)
				(type default)
			)
			(fill no)
			(layer "F.CrtYd")
		)
		(fp_rect
			(start -0.5 -0.25)
			(end 0.5 0.25)
			(stroke
				(width 0.15)
				(type solid)
			)
			(fill no)
			(layer "F.Fab")
		)
		(fp_text user "Author: Antmicro"
			(at -0.95 4.169 90)
			(layer "F.Fab")
			(effects
				(font
					(size 0.7 0.7)
					(thickness 0.15)
				)
				(justify left bottom)
			)
		)
		(fp_text user "License: Apache-2.0"
			(at -0.95 5.169 90)
			(layer "F.Fab")
			(effects
				(font
					(size 0.7 0.7)
					(thickness 0.15)
				)
				(justify left bottom)
			)
		)
		(fp_text user "${REFERENCE}"
			(at -0.95 3.168 90)
			(layer "F.Fab")
			(effects
				(font
					(size 0.7 0.7)
					(thickness 0.15)
				)
				(justify left bottom)
			)
		)
		(pad "1" smd roundrect
			(at -0.48 0 90)
			(size 0.59 0.64)
			(layers "F.Cu" "F.Mask" "F.Paste")
			(roundrect_rratio 0.25)
			(net 126 "/Ethernet/ULS-12_CTRL")
			(pintype "passive")
		)
		(pad "2" smd roundrect
			(at 0.48 0 90)
			(size 0.59 0.64)
			(layers "F.Cu" "F.Mask" "F.Paste")
			(roundrect_rratio 0.25)
			(net 33 "/Ethernet/VDD")
			(pintype "passive")
		)
	)
	(footprint "antmicro-footprints:C_0402_1005Metric"
		(layer "F.Cu")
		(at 94.092962 147.8415)
		(descr "Capacitor SMD 0402")
		(tags "capacitor SMD 0402")
		(property "Reference" "C209"
			(at 2.025 0.525 0)
			(layer "F.SilkS")
			(effects
				(font
					(size 0.7 0.7)
					(thickness 0.15)
				)
				(justify left bottom)
			)
		)
		(property "Value" "C_10u_0402"
			(at -1.022927 2.155213 0)
			(layer "F.Fab")
			(effects
				(font
					(size 0.7 0.7)
					(thickness 0.15)
				)
				(justify left bottom)
			)
		)
		(property "Datasheet" "https://www.yageo.com/en/Chart/Download/pdf/CC0402MRX5R5BB106"
			(at 0 0 0)
			(layer "F.Fab")
			(hide yes)
			(effects
				(font
					(size 1.27 1.27)
					(thickness 0.15)
				)
			)
		)
		(property "MPN" "CC0402MRX5R5BB106"
			(at 0 0 0)
			(unlocked yes)
			(layer "F.Fab")
			(hide yes)
			(effects
				(font
					(size 1 1)
					(thickness 0.15)
				)
			)
		)
		(property "Manufacturer" "YAGEO"
			(at 0 0 0)
			(unlocked yes)
			(layer "F.Fab")
			(hide yes)
			(effects
				(font
					(size 1 1)
					(thickness 0.15)
				)
			)
		)
		(property "License" "Apache-2.0"
			(at 0 0 0)
			(unlocked yes)
			(layer "F.Fab")
			(hide yes)
			(effects
				(font
					(size 1 1)
					(thickness 0.15)
				)
			)
		)
		(property "Author" "Antmicro"
			(at 0 0 0)
			(unlocked yes)
			(layer "F.Fab")
			(hide yes)
			(effects
				(font
					(size 1 1)
					(thickness 0.15)
				)
			)
		)
		(property "Val" "10u"
			(at 0 0 0)
			(unlocked yes)
			(layer "F.Fab")
			(hide yes)
			(effects
				(font
					(size 1 1)
					(thickness 0.15)
				)
			)
		)
		(property "Voltage" ""
			(at 0 0 0)
			(unlocked yes)
			(layer "F.Fab")
			(hide yes)
			(effects
				(font
					(size 1 1)
					(thickness 0.15)
				)
			)
		)
		(property "Dielectric" ""
			(at 0 0 0)
			(unlocked yes)
			(layer "F.Fab")
			(hide yes)
			(effects
				(font
					(size 1 1)
					(thickness 0.15)
				)
			)
		)
		(sheetname "/Compute module/")
		(sheetfile "compute-module.kicad_sch")
		(attr smd)
		(fp_rect
			(start -0.925 -0.47)
			(end 0.925 0.47)
			(stroke
				(width 0.05)
				(type default)
			)
			(fill no)
			(layer "F.CrtYd")
		)
		(fp_line
			(start -0.494 -0.25)
			(end 0.504 -0.25)
			(stroke
				(width 0.15)
				(type solid)
			)
			(layer "F.Fab")
		)
		(fp_line
			(start -0.494 0.248)
			(end -0.494 -0.25)
			(stroke
				(width 0.15)
				(type solid)
			)
			(layer "F.Fab")
		)
		(fp_line
			(start 0.504 -0.25)
			(end 0.504 0.248)
			(stroke
				(width 0.15)
				(type solid)
			)
			(layer "F.Fab")
		)
		(fp_line
			(start 0.504 0.248)
			(end -0.494 0.248)
			(stroke
				(width 0.15)
				(type solid)
			)
			(layer "F.Fab")
		)
		(fp_text user "Author: Antmicro"
			(at -0.939 3.399 0)
			(layer "F.Fab")
			(effects
				(font
					(size 0.7 0.7)
					(thickness 0.15)
				)
				(justify left bottom)
			)
		)
		(fp_text user "${REFERENCE}"
			(at -0.939 4.599 0)
			(layer "F.Fab")
			(effects
				(font
					(size 0.7 0.7)
					(thickness 0.15)
				)
				(justify left bottom)
			)
		)
		(fp_text user "License: Apache-2.0"
			(at -0.939 5.799 0)
			(layer "F.Fab")
			(effects
				(font
					(size 0.7 0.7)
					(thickness 0.15)
				)
				(justify left bottom)
			)
		)
		(pad "1" smd roundrect
			(at -0.48 0)
			(size 0.59 0.64)
			(layers "F.Cu" "F.Mask" "F.Paste")
			(roundrect_rratio 0.25)
			(net 3 "GND")
			(pintype "passive")
		)
		(pad "2" smd roundrect
			(at 0.48 0)
			(size 0.59 0.64)
			(layers "F.Cu" "F.Mask" "F.Paste")
			(roundrect_rratio 0.25)
			(net 9 "+3V3")
			(pintype "passive")
		)
	)
	(footprint "antmicro-footprints:DHVQFN-14-1EP_2.5x3mm"
		(layer "F.Cu")
		(at 96.717962 145.2665)
		(property "Reference" "U904"
			(at 2.8 -0.2 90)
			(layer "F.SilkS")
			(effects
				(font
					(size 0.7 0.7)
					(thickness 0.15)
				)
				(justify left bottom)
			)
		)
		(property "Value" "NTS0104_DHVQFN"
			(at 0 2.898 0)
			(layer "F.Fab")
			(effects
				(font
					(size 0.7 0.7)
					(thickness 0.15)
				)
				(justify left bottom)
			)
		)
		(property "Datasheet" "https://www.nxp.com/docs/en/data-sheet/NTS0104.pdf"
			(at 0 0 0)
			(layer "F.Fab")
			(hide yes)
			(effects
				(font
					(size 1.27 1.27)
					(thickness 0.15)
				)
			)
		)
		(property "MPN" "NTS0104BQ"
			(at 0 0 0)
			(unlocked yes)
			(layer "F.Fab")
			(hide yes)
			(effects
				(font
					(size 1 1)
					(thickness 0.15)
				)
			)
		)
		(property "Manufacturer" "NXP"
			(at 0 0 0)
			(unlocked yes)
			(layer "F.Fab")
			(hide yes)
			(effects
				(font
					(size 1 1)
					(thickness 0.15)
				)
			)
		)
		(property "Author" "Antmicro"
			(at 0 0 0)
			(unlocked yes)
			(layer "F.Fab")
			(hide yes)
			(effects
				(font
					(size 1 1)
					(thickness 0.15)
				)
			)
		)
		(property "License" "Apache-2.0"
			(at 0 0 0)
			(unlocked yes)
			(layer "F.Fab")
			(hide yes)
			(effects
				(font
					(size 1 1)
					(thickness 0.15)
				)
			)
		)
		(sheetname "/USB/")
		(sheetfile "usb.kicad_sch")
		(attr smd)
		(fp_line
			(start -1.351 -1.601)
			(end -0.5 -1.601)
			(stroke
				(width 0.15)
				(type solid)
			)
			(layer "F.SilkS")
		)
		(fp_line
			(start -1.351 1.6)
			(end -1.351 1.249)
			(stroke
				(width 0.15)
				(type solid)
			)
			(layer "F.SilkS")
		)
		(fp_line
			(start -1.351 1.6)
			(end -0.5 1.6)
			(stroke
				(width 0.15)
				(type solid)
			)
			(layer "F.SilkS")
		)
		(fp_line
			(start -1.35 -1.601)
			(end -1.35 -1.25)
			(stroke
				(width 0.15)
				(type solid)
			)
			(layer "F.SilkS")
		)
		(fp_line
			(start 0.494 1.6)
			(end 1.35 1.6)
			(stroke
				(width 0.15)
				(type solid)
			)
			(layer "F.SilkS")
		)
		(fp_line
			(start 1.35 -1.601)
			(end 0.494 -1.601)
			(stroke
				(width 0.15)
				(type solid)
			)
			(layer "F.SilkS")
		)
		(fp_line
			(start 1.35 -1.601)
			(end 1.35 -1.25)
			(stroke
				(width 0.15)
				(type solid)
			)
			(layer "F.SilkS")
		)
		(fp_line
			(start 1.35 1.6)
			(end 1.35 1.249)
			(stroke
				(width 0.15)
				(type solid)
			)
			(layer "F.SilkS")
		)
		(fp_circle
			(center -0.7 -1.85)
			(end -0.653 -1.85)
			(stroke
				(width 0.15)
				(type solid)
			)
			(fill yes)
			(layer "F.SilkS")
		)
		(fp_rect
			(start -1.85 -2)
			(end 1.8 1.95)
			(stroke
				(width 0.05)
				(type solid)
			)
			(fill no)
			(layer "F.CrtYd")
		)
		(fp_line
			(start -1.25 -1.25)
			(end -1 -1.5)
			(stroke
				(width 0.15)
				(type solid)
			)
			(layer "F.Fab")
		)
		(fp_line
			(start -1.25 1.499)
			(end -1.25 -1.25)
			(stroke
				(width 0.15)
				(type solid)
			)
			(layer "F.Fab")
		)
		(fp_line
			(start -1 -1.5)
			(end 1.249 -1.5)
			(stroke
				(width 0.15)
				(type solid)
			)
			(layer "F.Fab")
		)
		(fp_line
			(start 1.249 -1.5)
			(end 1.249 1.499)
			(stroke
				(width 0.15)
				(type solid)
			)
			(layer "F.Fab")
		)
		(fp_line
			(start 1.249 1.499)
			(end -1.25 1.499)
			(stroke
				(width 0.15)
				(type solid)
			)
			(layer "F.Fab")
		)
		(fp_text user "Author: Antmicro"
			(at -1.841 7.296 0)
			(layer "F.Fab")
			(effects
				(font
					(size 0.7 0.7)
					(thickness 0.15)
				)
				(justify left bottom)
			)
		)
		(fp_text user "${REFERENCE}"
			(at -1.841 4.897 0)
			(layer "F.Fab")
			(effects
				(font
					(size 0.7 0.7)
					(thickness 0.15)
				)
				(justify left bottom)
			)
		)
		(fp_text user "License: Apache-2.0"
			(at -1.841 6.097 0)
			(layer "F.Fab")
			(effects
				(font
					(size 0.7 0.7)
					(thickness 0.15)
				)
				(justify left bottom)
			)
		)
		(pad "1" smd oval
			(at -0.25 -1.5)
			(size 0.3 0.8)
			(layers "F.Cu" "F.Mask" "F.Paste")
			(net 27 "/USB/USB_3V3")
			(pinfunction "VCC_A")
			(pintype "power_in")
		)
		(pad "2" smd oval
			(at -1.25 -1 90)
			(size 0.3 0.8)
			(layers "F.Cu" "F.Mask" "F.Paste")
			(net 456 "/USB/BDBUS0")
			(pinfunction "A1")
			(pintype "passive")
		)
		(pad "3" smd oval
			(at -1.25 -0.5 90)
			(size 0.3 0.8)
			(layers "F.Cu" "F.Mask" "F.Paste")
			(net 457 "/USB/BDBUS1")
			(pinfunction "A2")
			(pintype "passive")
		)
		(pad "4" smd oval
			(at -1.25 0 90)
			(size 0.3 0.8)
			(layers "F.Cu" "F.Mask" "F.Paste")
			(net 458 "/USB/BDBUS2")
			(pinfunction "A3")
			(pintype "passive")
		)
		(pad "5" smd oval
			(at -1.25 0.494 90)
			(size 0.3 0.8)
			(layers "F.Cu" "F.Mask" "F.Paste")
			(net 459 "unconnected-(U904-A4-Pad5)")
			(pinfunction "A4")
			(pintype "passive+no_connect")
		)
		(pad "6" smd oval
			(at -1.25 0.994 90)
			(size 0.3 0.8)
			(layers "F.Cu" "F.Mask" "F.Paste")
			(net 460 "unconnected-(U904-NC-Pad6)")
			(pinfunction "NC")
			(pintype "no_connect")
		)
		(pad "7" smd oval
			(at -0.25 1.499)
			(size 0.3 0.8)
			(layers "F.Cu" "F.Mask" "F.Paste")
			(net 3 "GND")
			(pinfunction "GND")
			(pintype "power_in")
		)
		(pad "8" smd oval
			(at 0.244 1.499)
			(size 0.3 0.8)
			(layers "F.Cu" "F.Mask" "F.Paste")
			(net 490 "Net-(Q905-G)")
			(pinfunction "OE")
			(pintype "passive")
		)
		(pad "9" smd oval
			(at 1.249 0.994 90)
			(size 0.3 0.8)
			(layers "F.Cu" "F.Mask" "F.Paste")
			(net 461 "unconnected-(U904-NC-Pad9)")
			(pinfunction "NC")
			(pintype "no_connect")
		)
		(pad "10" smd oval
			(at 1.249 0.494 90)
			(size 0.3 0.8)
			(layers "F.Cu" "F.Mask" "F.Paste")
			(net 462 "unconnected-(U904-B4-Pad10)")
			(pinfunction "B4")
			(pintype "passive+no_connect")
		)
		(pad "11" smd oval
			(at 1.249 0 90)
			(size 0.3 0.8)
			(layers "F.Cu" "F.Mask" "F.Paste")
			(net 143 "/CSI/I_{2}C1.SDA")
			(pinfunction "B3")
			(pintype "passive")
		)
		(pad "12" smd oval
			(at 1.249 -0.5 90)
			(size 0.3 0.8)
			(layers "F.Cu" "F.Mask" "F.Paste")
			(net 485 "Net-(D908-C)")
			(pinfunction "B2")
			(pintype "passive")
		)
		(pad "13" smd oval
			(at 1.249 -1 90)
			(size 0.3 0.8)
			(layers "F.Cu" "F.Mask" "F.Paste")
			(net 142 "/CSI/I_{2}C1.SCL")
			(pinfunction "B1")
			(pintype "passive")
		)
		(pad "14" smd oval
			(at 0.244 -1.5)
			(size 0.3 0.8)
			(layers "F.Cu" "F.Mask" "F.Paste")
			(net 9 "+3V3")
			(pinfunction "VCC_B")
			(pintype "power_in")
		)
		(pad "15" smd rect
			(at 0 0)
			(size 1 1.5)
			(layers "F.Cu" "F.Mask" "F.Paste")
			(net 3 "GND")
			(pinfunction "GNDPAD")
			(pintype "power_in")
		)
	)
	(footprint "antmicro-footprints:VQFN-20_5x5x1mm_P0.65mm"
		(layer "F.Cu")
		(at 50.561962 131.4165 -90)
		(property "Reference" "U401"
			(at 1.7535 3.551962 90)
			(layer "F.SilkS")
			(effects
				(font
					(size 0.7 0.7)
					(thickness 0.15)
				)
				(justify right bottom)
			)
		)
		(property "Value" "TPS2372-3RGWR"
			(at 0 3.883 90)
			(layer "F.Fab")
			(effects
				(font
					(size 0.7 0.7)
					(thickness 0.15)
				)
				(justify right bottom)
			)
		)
		(property "Datasheet" "https://www.ti.com/lit/ds/symlink/tps2372.pdf?ts=1679042478513&ref_url=https%253A%252F%252Fwww.google.com%252F"
			(at 0 0 270)
			(layer "F.Fab")
			(hide yes)
			(effects
				(font
					(size 1.27 1.27)
					(thickness 0.15)
				)
			)
		)
		(property "MPN" "TPS2372-3RGWR"
			(at 0 0 270)
			(unlocked yes)
			(layer "F.Fab")
			(hide yes)
			(effects
				(font
					(size 1 1)
					(thickness 0.15)
				)
			)
		)
		(property "Manufacturer" "Texas Instruments"
			(at 0 0 270)
			(unlocked yes)
			(layer "F.Fab")
			(hide yes)
			(effects
				(font
					(size 1 1)
					(thickness 0.15)
				)
			)
		)
		(property "Author" "Antmicro"
			(at 0 0 270)
			(unlocked yes)
			(layer "F.Fab")
			(hide yes)
			(effects
				(font
					(size 1 1)
					(thickness 0.15)
				)
			)
		)
		(property "License" "Apache-2.0"
			(at 0 0 270)
			(unlocked yes)
			(layer "F.Fab")
			(hide yes)
			(effects
				(font
					(size 1 1)
					(thickness 0.15)
				)
			)
		)
		(sheetname "/Ethernet/")
		(sheetfile "ethernet.kicad_sch")
		(attr smd)
		(fp_line
			(start -2.5 2.499)
			(end -1.79 2.499)
			(stroke
				(width 0.15)
				(type solid)
			)
			(layer "F.SilkS")
		)
		(fp_line
			(start -2.5 2.499)
			(end -2.5 1.789)
			(stroke
				(width 0.15)
				(type solid)
			)
			(layer "F.SilkS")
		)
		(fp_line
			(start 2.499 2.499)
			(end 1.789 2.499)
			(stroke
				(width 0.15)
				(type solid)
			)
			(layer "F.SilkS")
		)
		(fp_line
			(start 2.499 2.499)
			(end 2.499 1.789)
			(stroke
				(width 0.15)
				(type solid)
			)
			(layer "F.SilkS")
		)
		(fp_line
			(start -1.625 -2.5)
			(end -2.5 -2.5)
			(stroke
				(width 0.15)
				(type solid)
			)
			(layer "F.SilkS")
		)
		(fp_line
			(start 2.499 -2.5)
			(end 2.499 -1.79)
			(stroke
				(width 0.15)
				(type solid)
			)
			(layer "F.SilkS")
		)
		(fp_line
			(start 2.499 -2.5)
			(end 1.789 -2.5)
			(stroke
				(width 0.15)
				(type solid)
			)
			(layer "F.SilkS")
		)
		(fp_circle
			(center -2.775 -1.875)
			(end -2.725 -1.825)
			(stroke
				(width 0.15)
				(type solid)
			)
			(fill yes)
			(layer "F.SilkS")
		)
		(fp_poly
			(pts
				(xy -1.081 0.088) (xy -0.11 0.088) (xy -0.11 1.08) (xy -1.081 1.08)
			)
			(stroke
				(width 0.01)
				(type solid)
			)
			(fill yes)
			(layer "F.Paste")
		)
		(fp_poly
			(pts
				(xy 0.108 0.088) (xy 1.08 0.088) (xy 1.08 1.08) (xy 0.108 1.08)
			)
			(stroke
				(width 0.01)
				(type solid)
			)
			(fill yes)
			(layer "F.Paste")
		)
		(fp_poly
			(pts
				(xy -1.081 -1.081) (xy -0.11 -1.081) (xy -0.11 -0.09) (xy -1.081 -0.09)
			)
			(stroke
				(width 0.01)
				(type solid)
			)
			(fill yes)
			(layer "F.Paste")
		)
		(fp_poly
			(pts
				(xy 0.108 -1.081) (xy 1.08 -1.081) (xy 1.08 -0.09) (xy 0.108 -0.09)
			)
			(stroke
				(width 0.01)
				(type solid)
			)
			(fill yes)
			(layer "F.Paste")
		)
		(fp_rect
			(start -2.95 -2.95)
			(end 2.95 2.95)
			(stroke
				(width 0.05)
				(type solid)
			)
			(fill no)
			(layer "F.CrtYd")
		)
		(fp_line
			(start -2.5 2.499)
			(end -2.5 -1.65)
			(stroke
				(width 0.15)
				(type solid)
			)
			(layer "F.Fab")
		)
		(fp_line
			(start 2.499 2.499)
			(end -2.5 2.499)
			(stroke
				(width 0.15)
				(type solid)
			)
			(layer "F.Fab")
		)
		(fp_line
			(start 2.499 2.499)
			(end 2.499 -2.5)
			(stroke
				(width 0.15)
				(type solid)
			)
			(layer "F.Fab")
		)
		(fp_line
			(start -2.5 -1.65)
			(end -1.65 -2.5)
			(stroke
				(width 0.15)
				(type solid)
			)
			(layer "F.Fab")
		)
		(fp_line
			(start 2.499 -2.5)
			(end -1.65 -2.5)
			(stroke
				(width 0.15)
				(type solid)
			)
			(layer "F.Fab")
		)
		(fp_text user "Author: Antmicro"
			(at -2.5 6.884 270)
			(layer "F.Fab")
			(effects
				(font
					(size 0.7 0.7)
					(thickness 0.15)
				)
				(justify left bottom)
			)
		)
		(fp_text user "${REFERENCE}"
			(at -2.5 5.884 270)
			(layer "F.Fab")
			(effects
				(font
					(size 0.7 0.7)
					(thickness 0.15)
				)
				(justify left bottom)
			)
		)
		(fp_text user "License: Apache-2.0"
			(at -2.5 7.884 270)
			(layer "F.Fab")
			(effects
				(font
					(size 0.7 0.7)
					(thickness 0.15)
				)
				(justify left bottom)
			)
		)
		(pad "1" smd roundrect
			(at -2.327 -1.301 270)
			(size 0.75 0.31)
			(layers "F.Cu" "F.Mask" "F.Paste")
			(roundrect_rratio 0.25)
			(net 33 "/Ethernet/VDD")
			(pinfunction "VDD")
			(pintype "power_in")
		)
		(pad "2" smd roundrect
			(at -2.327 -0.652 270)
			(size 0.75 0.31)
			(layers "F.Cu" "F.Mask" "F.Paste")
			(roundrect_rratio 0.25)
			(net 361 "/Ethernet/DEN")
			(pinfunction "DEN")
			(pintype "input")
		)
		(pad "3" smd roundrect
			(at -2.327 0 270)
			(size 0.75 0.31)
			(layers "F.Cu" "F.Mask" "F.Paste")
			(roundrect_rratio 0.25)
			(net 359 "/Ethernet/CLSA")
			(pinfunction "CLSA")
			(pintype "input")
		)
		(pad "4" smd roundrect
			(at -2.327 0.65 270)
			(size 0.75 0.31)
			(layers "F.Cu" "F.Mask" "F.Paste")
			(roundrect_rratio 0.25)
			(net 90 "/Ethernet/VSS")
			(pinfunction "VSSA")
			(pintype "power_in")
		)
		(pad "5" smd roundrect
			(at -2.327 1.3 270)
			(size 0.75 0.31)
			(layers "F.Cu" "F.Mask" "F.Paste")
			(roundrect_rratio 0.25)
			(net 90 "/Ethernet/VSS")
			(pinfunction "VSSB")
			(pintype "power_in")
		)
		(pad "6" smd roundrect
			(at -1.301 2.325 270)
			(size 0.31 0.75)
			(layers "F.Cu" "F.Mask" "F.Paste")
			(roundrect_rratio 0.25)
			(net 360 "/Ethernet/CLSB")
			(pinfunction "CLSB")
			(pintype "input")
		)
		(pad "7" smd roundrect
			(at -0.652 2.325 270)
			(size 0.31 0.75)
			(layers "F.Cu" "F.Mask" "F.Paste")
			(roundrect_rratio 0.25)
			(net 357 "/Ethernet/REF")
			(pinfunction "REF")
			(pintype "input")
		)
		(pad "8" smd roundrect
			(at 0 2.325 270)
			(size 0.31 0.75)
			(layers "F.Cu" "F.Mask" "F.Paste")
			(roundrect_rratio 0.25)
			(net 356 "/Ethernet/AMPS_CTL")
			(pinfunction "AMPS_CTL")
			(pintype "input")
		)
		(pad "9" smd roundrect
			(at 0.65 2.325 270)
			(size 0.31 0.75)
			(layers "F.Cu" "F.Mask" "F.Paste")
			(roundrect_rratio 0.25)
			(net 358 "/Ethernet/MPS_DUTY")
			(pinfunction "MPS_DUTY")
			(pintype "input")
		)
		(pad "10" smd roundrect
			(at 1.3 2.325 270)
			(size 0.31 0.75)
			(layers "F.Cu" "F.Mask" "F.Paste")
			(roundrect_rratio 0.25)
			(net 393 "unconnected-(U401-~{AUTCLS}-Pad10)")
			(pinfunction "~{AUTCLS}")
			(pintype "input+no_connect")
		)
		(pad "11" smd roundrect
			(at 2.325 1.3 270)
			(size 0.75 0.31)
			(layers "F.Cu" "F.Mask" "F.Paste")
			(roundrect_rratio 0.25)
			(net 1 "GNDD")
			(pinfunction "RTNA")
			(pintype "power_out")
		)
		(pad "12" smd roundrect
			(at 2.325 0.65 270)
			(size 0.75 0.31)
			(layers "F.Cu" "F.Mask" "F.Paste")
			(roundrect_rratio 0.25)
			(net 1 "GNDD")
			(pinfunction "RTNB")
			(pintype "power_out")
		)
		(pad "13" smd roundrect
			(at 2.325 0 270)
			(size 0.75 0.31)
			(layers "F.Cu" "F.Mask" "F.Paste")
			(roundrect_rratio 0.25)
			(net 363 "/Ethernet/PG")
			(pinfunction "PG")
			(pintype "output")
		)
		(pad "14" smd roundrect
			(at 2.325 -0.652 270)
			(size 0.75 0.31)
			(layers "F.Cu" "F.Mask" "F.Paste")
			(roundrect_rratio 0.25)
			(net 394 "unconnected-(U401-NC-Pad14)")
			(pinfunction "NC")
			(pintype "no_connect")
		)
		(pad "15" smd roundrect
			(at 2.325 -1.301 270)
			(size 0.75 0.31)
			(layers "F.Cu" "F.Mask" "F.Paste")
			(roundrect_rratio 0.25)
			(net 395 "unconnected-(U401-NC-Pad15)")
			(pinfunction "NC")
			(pintype "no_connect")
		)
		(pad "16" smd roundrect
			(at 1.3 -2.327 270)
			(size 0.31 0.75)
			(layers "F.Cu" "F.Mask" "F.Paste")
			(roundrect_rratio 0.25)
			(net 396 "unconnected-(U401-IRSHDL_EN-Pad16)")
			(pinfunction "IRSHDL_EN")
			(pintype "output+no_connect")
		)
		(pad "17" smd roundrect
			(at 0.65 -2.327 270)
			(size 0.31 0.75)
			(layers "F.Cu" "F.Mask" "F.Paste")
			(roundrect_rratio 0.25)
			(net 364 "/Ethernet/TPL")
			(pinfunction "TPL")
			(pintype "output")
		)
		(pad "18" smd roundrect
			(at 0 -2.327 270)
			(size 0.31 0.75)
			(layers "F.Cu" "F.Mask" "F.Paste")
			(roundrect_rratio 0.25)
			(net 362 "/Ethernet/TPH")
			(pinfunction "TPH")
			(pintype "output")
		)
		(pad "19" smd roundrect
			(at -0.652 -2.327 270)
			(size 0.31 0.75)
			(layers "F.Cu" "F.Mask" "F.Paste")
			(roundrect_rratio 0.25)
			(net 365 "/Ethernet/~{BT}")
			(pinfunction "~{BT}")
			(pintype "output")
		)
		(pad "20" smd roundrect
			(at -1.301 -2.327 270)
			(size 0.31 0.75)
			(layers "F.Cu" "F.Mask" "F.Paste")
			(roundrect_rratio 0.25)
			(net 397 "unconnected-(U401-NC-Pad20)")
			(pinfunction "NC")
			(pintype "no_connect")
		)
		(pad "21" smd rect
			(at 0 0 270)
			(size 2.2 2.2)
			(layers "F.Cu" "F.Mask")
			(net 90 "/Ethernet/VSS")
			(pinfunction "PAD_VSSC")
			(pintype "power_in")
		)
	)
	(footprint "antmicro-footprints:C_0402_1005Metric"
		(layer "F.Cu")
		(at 86.642962 143.557236 180)
		(descr "Capacitor SMD 0402")
		(tags "capacitor SMD 0402")
		(property "Reference" "C912"
			(at 0.875 -0.419264 0)
			(layer "F.SilkS")
			(effects
				(font
					(size 0.7 0.7)
					(thickness 0.15)
				)
				(justify right bottom)
			)
		)
		(property "Value" "C_100n_0402"
			(at -1.022927 2.155213 0)
			(layer "F.Fab")
			(effects
				(font
					(size 0.7 0.7)
					(thickness 0.15)
				)
				(justify right bottom)
			)
		)
		(property "Datasheet" "https://www.murata.com/products/productdetail?partno=GRM155R61H104KE14%23"
			(at 0 0 180)
			(layer "F.Fab")
			(hide yes)
			(effects
				(font
					(size 1.27 1.27)
					(thickness 0.15)
				)
			)
		)
		(property "Manufacturer" "Murata"
			(at 0 0 180)
			(unlocked yes)
			(layer "F.Fab")
			(hide yes)
			(effects
				(font
					(size 1 1)
					(thickness 0.15)
				)
			)
		)
		(property "MPN" "GRM155R61H104KE14D"
			(at 0 0 180)
			(unlocked yes)
			(layer "F.Fab")
			(hide yes)
			(effects
				(font
					(size 1 1)
					(thickness 0.15)
				)
			)
		)
		(property "Val" "100n"
			(at 0 0 180)
			(unlocked yes)
			(layer "F.Fab")
			(hide yes)
			(effects
				(font
					(size 1 1)
					(thickness 0.15)
				)
			)
		)
		(property "License" "Apache-2.0"
			(at 0 0 180)
			(unlocked yes)
			(layer "F.Fab")
			(hide yes)
			(effects
				(font
					(size 1 1)
					(thickness 0.15)
				)
			)
		)
		(property "Author" "Antmicro"
			(at 0 0 180)
			(unlocked yes)
			(layer "F.Fab")
			(hide yes)
			(effects
				(font
					(size 1 1)
					(thickness 0.15)
				)
			)
		)
		(property "Voltage" "50V"
			(at 0 0 180)
			(unlocked yes)
			(layer "F.Fab")
			(hide yes)
			(effects
				(font
					(size 1 1)
					(thickness 0.15)
				)
			)
		)
		(property "Dielectric" "X5R"
			(at 0 0 180)
			(unlocked yes)
			(layer "F.Fab")
			(hide yes)
			(effects
				(font
					(size 1 1)
					(thickness 0.15)
				)
			)
		)
		(sheetname "/USB/")
		(sheetfile "usb.kicad_sch")
		(attr smd)
		(fp_rect
			(start -0.925 -0.47)
			(end 0.925 0.47)
			(stroke
				(width 0.05)
				(type default)
			)
			(fill no)
			(layer "F.CrtYd")
		)
		(fp_line
			(start 0.504 0.248)
			(end -0.494 0.248)
			(stroke
				(width 0.15)
				(type solid)
			)
			(layer "F.Fab")
		)
		(fp_line
			(start 0.504 -0.25)
			(end 0.504 0.248)
			(stroke
				(width 0.15)
				(type solid)
			)
			(layer "F.Fab")
		)
		(fp_line
			(start -0.494 0.248)
			(end -0.494 -0.25)
			(stroke
				(width 0.15)
				(type solid)
			)
			(layer "F.Fab")
		)
		(fp_line
			(start -0.494 -0.25)
			(end 0.504 -0.25)
			(stroke
				(width 0.15)
				(type solid)
			)
			(layer "F.Fab")
		)
		(fp_text user "Author: Antmicro"
			(at -0.939 3.399 180)
			(layer "F.Fab")
			(effects
				(font
					(size 0.7 0.7)
					(thickness 0.15)
				)
				(justify left bottom)
			)
		)
		(fp_text user "License: Apache-2.0"
			(at -0.939 5.799 180)
			(layer "F.Fab")
			(effects
				(font
					(size 0.7 0.7)
					(thickness 0.15)
				)
				(justify left bottom)
			)
		)
		(fp_text user "${REFERENCE}"
			(at -0.939 4.599 180)
			(layer "F.Fab")
			(effects
				(font
					(size 0.7 0.7)
					(thickness 0.15)
				)
				(justify left bottom)
			)
		)
		(pad "1" smd roundrect
			(at -0.48 0 180)
			(size 0.59 0.64)
			(layers "F.Cu" "F.Mask" "F.Paste")
			(roundrect_rratio 0.25)
			(net 30 "/USB/USB_1V2")
			(pintype "passive")
		)
		(pad "2" smd roundrect
			(at 0.48 0 180)
			(size 0.59 0.64)
			(layers "F.Cu" "F.Mask" "F.Paste")
			(roundrect_rratio 0.25)
			(net 3 "GND")
			(pintype "passive")
		)
	)
	(footprint "antmicro-footprints:TP_SMD_0.75mm"
		(layer "F.Cu")
		(at 90.75 121.65)
		(property "Reference" "TP921"
			(at 0.5 3.625 90)
			(layer "F.SilkS")
			(effects
				(font
					(size 0.7 0.7)
					(thickness 0.15)
				)
				(justify left bottom)
			)
		)
		(property "Value" "TP_0.75mm_SMD"
			(at 0 1.2 0)
			(layer "F.Fab")
			(effects
				(font
					(size 0.7 0.7)
					(thickness 0.15)
				)
				(justify left bottom)
			)
		)
		(property "MPN" ""
			(at 0 0 0)
			(unlocked yes)
			(layer "F.Fab")
			(hide yes)
			(effects
				(font
					(size 1 1)
					(thickness 0.15)
				)
			)
		)
		(property "Manufacturer" ""
			(at 0 0 0)
			(unlocked yes)
			(layer "F.Fab")
			(hide yes)
			(effects
				(font
					(size 1 1)
					(thickness 0.15)
				)
			)
		)
		(property "Author" "Antmicro"
			(at 0 0 0)
			(unlocked yes)
			(layer "F.Fab")
			(hide yes)
			(effects
				(font
					(size 1 1)
					(thickness 0.15)
				)
			)
		)
		(property "License" "Apache-2.0"
			(at 0 0 0)
			(unlocked yes)
			(layer "F.Fab")
			(hide yes)
			(effects
				(font
					(size 1 1)
					(thickness 0.15)
				)
			)
		)
		(sheetname "/USB/")
		(sheetfile "usb.kicad_sch")
		(attr exclude_from_pos_files exclude_from_bom)
		(fp_circle
			(center 0 0)
			(end 0.475 0)
			(stroke
				(width 0.05)
				(type default)
			)
			(fill no)
			(layer "F.CrtYd")
		)
		(fp_text user "License: Apache-2.0"
			(at -0.4 5.101 0)
			(layer "F.Fab")
			(effects
				(font
					(size 0.7 0.7)
					(thickness 0.15)
				)
				(justify left bottom)
			)
		)
		(fp_text user "Author: Antmicro"
			(at -0.4 3.901 0)
			(layer "F.Fab")
			(effects
				(font
					(size 0.7 0.7)
					(thickness 0.15)
				)
				(justify left bottom)
			)
		)
		(fp_text user "${REFERENCE}"
			(at -0.4 2.7 0)
			(layer "F.Fab")
			(effects
				(font
					(size 0.7 0.7)
					(thickness 0.15)
				)
				(justify left bottom)
			)
		)
		(pad "1" smd circle
			(at 0 0)
			(size 0.75 0.75)
			(layers "F.Cu" "F.Mask")
			(net 24 "/Compute module/USBA_VBUS")
			(pinfunction "1")
			(pintype "passive")
		)
	)
	(footprint "antmicro-footprints:TP_SMD_0.75mm"
		(layer "F.Cu")
		(at 81.3 137.65)
		(property "Reference" "TP917"
			(at -1.725 3.92 90)
			(layer "F.SilkS")
			(effects
				(font
					(size 0.7 0.7)
					(thickness 0.15)
				)
				(justify left bottom)
			)
		)
		(property "Value" "TP_0.75mm_SMD"
			(at 0 1.2 0)
			(layer "F.Fab")
			(effects
				(font
					(size 0.7 0.7)
					(thickness 0.15)
				)
				(justify left bottom)
			)
		)
		(property "MPN" ""
			(at 0 0 0)
			(unlocked yes)
			(layer "F.Fab")
			(hide yes)
			(effects
				(font
					(size 1 1)
					(thickness 0.15)
				)
			)
		)
		(property "Manufacturer" ""
			(at 0 0 0)
			(unlocked yes)
			(layer "F.Fab")
			(hide yes)
			(effects
				(font
					(size 1 1)
					(thickness 0.15)
				)
			)
		)
		(property "Author" "Antmicro"
			(at 0 0 0)
			(unlocked yes)
			(layer "F.Fab")
			(hide yes)
			(effects
				(font
					(size 1 1)
					(thickness 0.15)
				)
			)
		)
		(property "License" "Apache-2.0"
			(at 0 0 0)
			(unlocked yes)
			(layer "F.Fab")
			(hide yes)
			(effects
				(font
					(size 1 1)
					(thickness 0.15)
				)
			)
		)
		(sheetname "/USB/")
		(sheetfile "usb.kicad_sch")
		(attr exclude_from_pos_files exclude_from_bom)
		(fp_circle
			(center 0 0)
			(end 0.475 0)
			(stroke
				(width 0.05)
				(type default)
			)
			(fill no)
			(layer "F.CrtYd")
		)
		(fp_text user "Author: Antmicro"
			(at -0.4 3.901 0)
			(layer "F.Fab")
			(effects
				(font
					(size 0.7 0.7)
					(thickness 0.15)
				)
				(justify left bottom)
			)
		)
		(fp_text user "License: Apache-2.0"
			(at -0.4 5.101 0)
			(layer "F.Fab")
			(effects
				(font
					(size 0.7 0.7)
					(thickness 0.15)
				)
				(justify left bottom)
			)
		)
		(fp_text user "${REFERENCE}"
			(at -0.4 2.7 0)
			(layer "F.Fab")
			(effects
				(font
					(size 0.7 0.7)
					(thickness 0.15)
				)
				(justify left bottom)
			)
		)
		(pad "1" smd circle
			(at 0 0)
			(size 0.75 0.75)
			(layers "F.Cu" "F.Mask")
			(net 442 "Net-(U905-GPIO5)")
			(pinfunction "1")
			(pintype "passive")
		)
	)
	(footprint "antmicro-footprints:Resonator_SMD_Abracon_ABM8G_3.2x2.5mm"
		(layer "F.Cu")
		(at 89.642962 147.1665 -90)
		(property "Reference" "Y901"
			(at 2.85 1.425 180)
			(layer "F.SilkS")
			(effects
				(font
					(size 0.7 0.7)
					(thickness 0.15)
				)
				(justify left bottom)
			)
		)
		(property "Value" "Resonator_12MHz_ABM8G"
			(at -1.75 2.548 270)
			(layer "F.Fab")
			(effects
				(font
					(size 0.7 0.7)
					(thickness 0.15)
				)
				(justify left bottom)
			)
		)
		(property "Datasheet" "https://abracon.com/Resonators/ABM8G.pdf"
			(at 0 0 270)
			(layer "F.Fab")
			(hide yes)
			(effects
				(font
					(size 1.27 1.27)
					(thickness 0.15)
				)
			)
		)
		(property "MPN" "ABM8G-12.000MHZ-18-D2Y-T"
			(at 0 0 270)
			(unlocked yes)
			(layer "F.Fab")
			(hide yes)
			(effects
				(font
					(size 1 1)
					(thickness 0.15)
				)
			)
		)
		(property "Manufacturer" "Abracon"
			(at 0 0 270)
			(unlocked yes)
			(layer "F.Fab")
			(hide yes)
			(effects
				(font
					(size 1 1)
					(thickness 0.15)
				)
			)
		)
		(property "Val" "12 MHz"
			(at 0 0 270)
			(unlocked yes)
			(layer "F.Fab")
			(hide yes)
			(effects
				(font
					(size 1 1)
					(thickness 0.15)
				)
			)
		)
		(property "Author" "Antmicro"
			(at 0 0 270)
			(unlocked yes)
			(layer "F.Fab")
			(hide yes)
			(effects
				(font
					(size 1 1)
					(thickness 0.15)
				)
			)
		)
		(property "License" "Apache-2.0"
			(at 0 0 270)
			(unlocked yes)
			(layer "F.Fab")
			(hide yes)
			(effects
				(font
					(size 1 1)
					(thickness 0.15)
				)
			)
		)
		(sheetname "/USB/")
		(sheetfile "usb.kicad_sch")
		(attr smd)
		(fp_line
			(start -0.35 1.25)
			(end 0.45 1.25)
			(stroke
				(width 0.15)
				(type solid)
			)
			(layer "F.SilkS")
		)
		(fp_line
			(start -1.6 0.3)
			(end -1.6 -0.2)
			(stroke
				(width 0.15)
				(type solid)
			)
			(layer "F.SilkS")
		)
		(fp_line
			(start 1.6 0.3)
			(end 1.6 -0.2)
			(stroke
				(width 0.15)
				(type solid)
			)
			(layer "F.SilkS")
		)
		(fp_line
			(start -0.35 -1.25)
			(end 0.45 -1.25)
			(stroke
				(width 0.15)
				(type solid)
			)
			(layer "F.SilkS")
		)
		(fp_circle
			(center -1.75 1.5)
			(end -1.7 1.5)
			(stroke
				(width 0.15)
				(type solid)
			)
			(fill no)
			(layer "F.SilkS")
		)
		(fp_rect
			(start -1.907 -1.55)
			(end 2.006 1.649)
			(stroke
				(width 0.05)
				(type solid)
			)
			(fill no)
			(layer "F.CrtYd")
		)
		(fp_text user "${REFERENCE}"
			(at -1.75 3.75 270)
			(layer "F.Fab")
			(effects
				(font
					(size 0.7 0.7)
					(thickness 0.15)
				)
				(justify left bottom)
			)
		)
		(fp_text user "License: Apache-2.0"
			(at -1.75 6.5 270)
			(layer "F.Fab")
			(effects
				(font
					(size 0.7 0.7)
					(thickness 0.15)
				)
				(justify left bottom)
			)
		)
		(fp_text user "Author: Antmicro"
			(at -1.75 5 270)
			(layer "F.Fab")
			(effects
				(font
					(size 0.7 0.7)
					(thickness 0.15)
				)
				(justify left bottom)
			)
		)
		(pad "1" smd roundrect
			(at -1.101 0.949 270)
			(size 1.3 1.1)
			(layers "F.Cu" "F.Mask" "F.Paste")
			(roundrect_rratio 0)
			(chamfer_ratio 0.2)
			(chamfer bottom_left)
			(net 114 "Net-(U905-OSCI)")
			(pintype "passive")
		)
		(pad "2" smd rect
			(at 1.199 0.949 270)
			(size 1.3 1.1)
			(layers "F.Cu" "F.Mask" "F.Paste")
			(net 3 "GND")
			(pinfunction "SH")
			(pintype "passive")
		)
		(pad "3" smd rect
			(at 1.199 -0.85 270)
			(size 1.3 1.1)
			(layers "F.Cu" "F.Mask" "F.Paste")
			(net 115 "Net-(U905-OSCO)")
			(pintype "passive")
		)
		(pad "4" smd rect
			(at -1.101 -0.85 270)
			(size 1.3 1.1)
			(layers "F.Cu" "F.Mask" "F.Paste")
			(net 3 "GND")
			(pinfunction "SH")
			(pintype "passive")
		)
	)
	(footprint "antmicro-footprints:SOT-523"
		(layer "F.Cu")
		(at 102.467962 146.2665 -90)
		(property "Reference" "Q905"
			(at -1.2 -2 90)
			(layer "F.SilkS")
			(effects
				(font
					(size 0.7 0.7)
					(thickness 0.15)
				)
				(justify right bottom)
			)
		)
		(property "Value" "PJE138K"
			(at 0.1 1.824 90)
			(layer "F.Fab")
			(effects
				(font
					(size 0.7 0.7)
					(thickness 0.15)
				)
				(justify right bottom)
			)
		)
		(property "Datasheet" "https://www.mouser.com/datasheet/2/1057/PJE138K-1876698.pdf"
			(at 0 0 270)
			(layer "F.Fab")
			(hide yes)
			(effects
				(font
					(size 1.27 1.27)
					(thickness 0.15)
				)
			)
		)
		(property "MPN" "PJE138K_R1_00001"
			(at 0 0 270)
			(unlocked yes)
			(layer "F.Fab")
			(hide yes)
			(effects
				(font
					(size 1 1)
					(thickness 0.15)
				)
			)
		)
		(property "Manufacturer" "PANJIT"
			(at 0 0 270)
			(unlocked yes)
			(layer "F.Fab")
			(hide yes)
			(effects
				(font
					(size 1 1)
					(thickness 0.15)
				)
			)
		)
		(property "Author" "Antmicro"
			(at 0 0 270)
			(unlocked yes)
			(layer "F.Fab")
			(hide yes)
			(effects
				(font
					(size 1 1)
					(thickness 0.15)
				)
			)
		)
		(property "License" "Apache-2.0"
			(at 0 0 270)
			(unlocked yes)
			(layer "F.Fab")
			(hide yes)
			(effects
				(font
					(size 1 1)
					(thickness 0.15)
				)
			)
		)
		(sheetname "/USB/")
		(sheetfile "usb.kicad_sch")
		(attr smd)
		(fp_line
			(start -0.927 -0.051)
			(end -0.927 -0.351)
			(stroke
				(width 0.15)
				(type solid)
			)
			(layer "F.SilkS")
		)
		(fp_line
			(start -0.927 -0.351)
			(end -0.725 -0.551)
			(stroke
				(width 0.15)
				(type solid)
			)
			(layer "F.SilkS")
		)
		(fp_line
			(start -0.725 -0.551)
			(end -0.277 -0.551)
			(stroke
				(width 0.15)
				(type solid)
			)
			(layer "F.SilkS")
		)
		(fp_line
			(start -0.277 -0.551)
			(end -0.277 -0.75)
			(stroke
				(width 0.15)
				(type solid)
			)
			(layer "F.SilkS")
		)
		(fp_circle
			(center -0.9652 0.9652)
			(end -0.9152 0.9652)
			(stroke
				(width 0.15)
				(type solid)
			)
			(fill yes)
			(layer "F.SilkS")
		)
		(fp_line
			(start -1.12 1.15)
			(end 1.1 1.15)
			(stroke
				(width 0.05)
				(type solid)
			)
			(layer "F.CrtYd")
		)
		(fp_line
			(start -1.12 -1.16)
			(end -1.12 1.15)
			(stroke
				(width 0.05)
				(type solid)
			)
			(layer "F.CrtYd")
		)
		(fp_line
			(start -1.12 -1.16)
			(end 1.1 -1.16)
			(stroke
				(width 0.05)
				(type solid)
			)
			(layer "F.CrtYd")
		)
		(fp_line
			(start 1.1 -1.16)
			(end 1.1 1.15)
			(stroke
				(width 0.05)
				(type solid)
			)
			(layer "F.CrtYd")
		)
		(fp_line
			(start 0.8 0.424)
			(end -0.802 0.424)
			(stroke
				(width 0.15)
				(type solid)
			)
			(layer "F.Fab")
		)
		(fp_line
			(start -0.802 -0.276)
			(end -0.802 0.424)
			(stroke
				(width 0.15)
				(type solid)
			)
			(layer "F.Fab")
		)
		(fp_line
			(start -0.652 -0.425)
			(end -0.802 -0.276)
			(stroke
				(width 0.15)
				(type solid)
			)
			(layer "F.Fab")
		)
		(fp_line
			(start 0.8 -0.425)
			(end 0.8 0.424)
			(stroke
				(width 0.15)
				(type solid)
			)
			(layer "F.Fab")
		)
		(fp_line
			(start 0.8 -0.425)
			(end -0.652 -0.425)
			(stroke
				(width 0.15)
				(type solid)
			)
			(layer "F.Fab")
		)
		(fp_circle
			(center -0.9652 0.9652)
			(end -0.9144 0.9652)
			(stroke
				(width 0.15)
				(type solid)
			)
			(fill no)
			(layer "F.Fab")
		)
		(fp_text user "${REFERENCE}"
			(at -1.12 3.824 270)
			(layer "F.Fab")
			(effects
				(font
					(size 0.7 0.7)
					(thickness 0.15)
				)
				(justify left bottom)
			)
		)
		(fp_text user "Author: Antmicro"
			(at -1.12 6.224 270)
			(layer "F.Fab")
			(effects
				(font
					(size 0.7 0.7)
					(thickness 0.15)
				)
				(justify left bottom)
			)
		)
		(fp_text user "License: Apache-2.0"
			(at -1.12 5.024 270)
			(layer "F.Fab")
			(effects
				(font
					(size 0.7 0.7)
					(thickness 0.15)
				)
				(justify left bottom)
			)
		)
		(pad "1" smd rect
			(at -0.5 0.65 270)
			(size 0.4 0.51)
			(layers "F.Cu" "F.Mask" "F.Paste")
			(net 490 "Net-(Q905-G)")
			(pinfunction "G")
			(pintype "input")
		)
		(pad "2" smd rect
			(at 0.498 0.65 270)
			(size 0.4 0.51)
			(layers "F.Cu" "F.Mask" "F.Paste")
			(net 3 "GND")
			(pinfunction "S")
			(pintype "passive")
		)
		(pad "3" smd rect
			(at 0 -0.652 270)
			(size 0.4 0.51)
			(layers "F.Cu" "F.Mask" "F.Paste")
			(net 455 "Net-(Q905-D)")
			(pinfunction "D")
			(pintype "passive")
		)
	)
	(footprint "antmicro-footprints:C_0402_1005Metric"
		(layer "F.Cu")
		(at 95.867962 142.7165)
		(descr "Capacitor SMD 0402")
		(tags "capacitor SMD 0402")
		(property "Reference" "C933"
			(at 0.5 -0.4 0)
			(layer "F.SilkS")
			(effects
				(font
					(size 0.7 0.7)
					(thickness 0.15)
				)
				(justify left bottom)
			)
		)
		(property "Value" "C_100n_0402"
			(at -1.022927 2.155213 0)
			(layer "F.Fab")
			(effects
				(font
					(size 0.7 0.7)
					(thickness 0.15)
				)
				(justify left bottom)
			)
		)
		(property "Datasheet" "https://www.murata.com/products/productdetail?partno=GRM155R61H104KE14%23"
			(at 0 0 0)
			(layer "F.Fab")
			(hide yes)
			(effects
				(font
					(size 1.27 1.27)
					(thickness 0.15)
				)
			)
		)
		(property "MPN" "GRM155R61H104KE14D"
			(at 0 0 0)
			(unlocked yes)
			(layer "F.Fab")
			(hide yes)
			(effects
				(font
					(size 1 1)
					(thickness 0.15)
				)
			)
		)
		(property "Manufacturer" "Murata"
			(at 0 0 0)
			(unlocked yes)
			(layer "F.Fab")
			(hide yes)
			(effects
				(font
					(size 1 1)
					(thickness 0.15)
				)
			)
		)
		(property "License" "Apache-2.0"
			(at 0 0 0)
			(unlocked yes)
			(layer "F.Fab")
			(hide yes)
			(effects
				(font
					(size 1 1)
					(thickness 0.15)
				)
			)
		)
		(property "Author" "Antmicro"
			(at 0 0 0)
			(unlocked yes)
			(layer "F.Fab")
			(hide yes)
			(effects
				(font
					(size 1 1)
					(thickness 0.15)
				)
			)
		)
		(property "Val" "100n"
			(at 0 0 0)
			(unlocked yes)
			(layer "F.Fab")
			(hide yes)
			(effects
				(font
					(size 1 1)
					(thickness 0.15)
				)
			)
		)
		(property "Voltage" "50V"
			(at 0 0 0)
			(unlocked yes)
			(layer "F.Fab")
			(hide yes)
			(effects
				(font
					(size 1 1)
					(thickness 0.15)
				)
			)
		)
		(property "Dielectric" "X5R"
			(at 0 0 0)
			(unlocked yes)
			(layer "F.Fab")
			(hide yes)
			(effects
				(font
					(size 1 1)
					(thickness 0.15)
				)
			)
		)
		(sheetname "/USB/")
		(sheetfile "usb.kicad_sch")
		(attr smd)
		(fp_rect
			(start -0.925 -0.47)
			(end 0.925 0.47)
			(stroke
				(width 0.05)
				(type default)
			)
			(fill no)
			(layer "F.CrtYd")
		)
		(fp_line
			(start -0.494 -0.25)
			(end 0.504 -0.25)
			(stroke
				(width 0.15)
				(type solid)
			)
			(layer "F.Fab")
		)
		(fp_line
			(start -0.494 0.248)
			(end -0.494 -0.25)
			(stroke
				(width 0.15)
				(type solid)
			)
			(layer "F.Fab")
		)
		(fp_line
			(start 0.504 -0.25)
			(end 0.504 0.248)
			(stroke
				(width 0.15)
				(type solid)
			)
			(layer "F.Fab")
		)
		(fp_line
			(start 0.504 0.248)
			(end -0.494 0.248)
			(stroke
				(width 0.15)
				(type solid)
			)
			(layer "F.Fab")
		)
		(fp_text user "Author: Antmicro"
			(at -0.939 3.399 0)
			(layer "F.Fab")
			(effects
				(font
					(size 0.7 0.7)
					(thickness 0.15)
				)
				(justify left bottom)
			)
		)
		(fp_text user "${REFERENCE}"
			(at -0.939 4.599 0)
			(layer "F.Fab")
			(effects
				(font
					(size 0.7 0.7)
					(thickness 0.15)
				)
				(justify left bottom)
			)
		)
		(fp_text user "License: Apache-2.0"
			(at -0.939 5.799 0)
			(layer "F.Fab")
			(effects
				(font
					(size 0.7 0.7)
					(thickness 0.15)
				)
				(justify left bottom)
			)
		)
		(pad "1" smd roundrect
			(at -0.48 0)
			(size 0.59 0.64)
			(layers "F.Cu" "F.Mask" "F.Paste")
			(roundrect_rratio 0.25)
			(net 3 "GND")
			(pintype "passive")
		)
		(pad "2" smd roundrect
			(at 0.48 0)
			(size 0.59 0.64)
			(layers "F.Cu" "F.Mask" "F.Paste")
			(roundrect_rratio 0.25)
			(net 27 "/USB/USB_3V3")
			(pintype "passive")
		)
	)
	(footprint "antmicro-footprints:Nexperia_DFN-10_2.5x1mm_P0.5mm"
		(layer "F.Cu")
		(at 142.292962 144.3915 90)
		(property "Reference" "D803"
			(at 4.365 1.175 90)
			(layer "F.SilkS")
			(effects
				(font
					(size 0.7 0.7)
					(thickness 0.15)
				)
				(justify left bottom)
			)
		)
		(property "Value" "PUSB3F96X_PASS"
			(at -0.016 1.705 90)
			(layer "F.Fab")
			(effects
				(font
					(size 0.7 0.7)
					(thickness 0.15)
				)
				(justify left bottom)
			)
		)
		(property "Datasheet" "https://mouser.com/datasheet/2/916/PUSB3F96-1600324.pdf"
			(at 0 0 90)
			(layer "F.Fab")
			(hide yes)
			(effects
				(font
					(size 1.27 1.27)
					(thickness 0.15)
				)
			)
		)
		(property "Manufacturer" "Nexperia"
			(at 0 0 90)
			(unlocked yes)
			(layer "F.Fab")
			(hide yes)
			(effects
				(font
					(size 1 1)
					(thickness 0.15)
				)
			)
		)
		(property "MPN" "PUSB3F96X"
			(at 0 0 90)
			(unlocked yes)
			(layer "F.Fab")
			(hide yes)
			(effects
				(font
					(size 1 1)
					(thickness 0.15)
				)
			)
		)
		(property "Author" "Antmicro"
			(at 0 0 90)
			(unlocked yes)
			(layer "F.Fab")
			(hide yes)
			(effects
				(font
					(size 1 1)
					(thickness 0.15)
				)
			)
		)
		(property "License" "Apache-2.0"
			(at 0 0 90)
			(unlocked yes)
			(layer "F.Fab")
			(hide yes)
			(effects
				(font
					(size 1 1)
					(thickness 0.15)
				)
			)
		)
		(sheetname "/Peripherals/")
		(sheetfile "peripherals.kicad_sch")
		(attr smd)
		(fp_line
			(start -1.375 -0.4)
			(end -1.375 0.4)
			(stroke
				(width 0.15)
				(type solid)
			)
			(layer "F.SilkS")
		)
		(fp_line
			(start 1.375 0.4)
			(end 1.375 -0.4)
			(stroke
				(width 0.15)
				(type solid)
			)
			(layer "F.SilkS")
		)
		(fp_circle
			(center -1.4 0.7)
			(end -1.349 0.7)
			(stroke
				(width 0.15)
				(type solid)
			)
			(fill yes)
			(layer "F.SilkS")
		)
		(fp_rect
			(start -1.4 -0.725)
			(end 1.4 0.725)
			(stroke
				(width 0.05)
				(type solid)
			)
			(fill no)
			(layer "F.CrtYd")
		)
		(fp_line
			(start 1.25 -0.5)
			(end -1.25 -0.5)
			(stroke
				(width 0.15)
				(type solid)
			)
			(layer "F.Fab")
		)
		(fp_line
			(start -1.25 -0.5)
			(end -1.25 0.15)
			(stroke
				(width 0.15)
				(type solid)
			)
			(layer "F.Fab")
		)
		(fp_line
			(start -1.25 0.15)
			(end -0.9 0.5)
			(stroke
				(width 0.15)
				(type solid)
			)
			(layer "F.Fab")
		)
		(fp_line
			(start 1.25 0.5)
			(end 1.25 -0.5)
			(stroke
				(width 0.15)
				(type solid)
			)
			(layer "F.Fab")
		)
		(fp_line
			(start -0.9 0.5)
			(end 1.25 0.5)
			(stroke
				(width 0.15)
				(type solid)
			)
			(layer "F.Fab")
		)
		(fp_text user "${REFERENCE}"
			(at -1.367 3.704 90)
			(layer "F.Fab")
			(effects
				(font
					(size 0.7 0.7)
					(thickness 0.15)
				)
				(justify left bottom)
			)
		)
		(fp_text user "Author: Antmicro"
			(at -1.367 4.905 90)
			(layer "F.Fab")
			(effects
				(font
					(size 0.7 0.7)
					(thickness 0.15)
				)
				(justify left bottom)
			)
		)
		(fp_text user "License: Apache-2.0"
			(at -1.367 6.105 90)
			(layer "F.Fab")
			(effects
				(font
					(size 0.7 0.7)
					(thickness 0.15)
				)
				(justify left bottom)
			)
		)
		(pad "1" smd rect
			(at -1 0.3875 90)
			(size 0.2 0.475)
			(layers "F.Cu" "F.Mask" "F.Paste")
			(net 229 "/Compute module/GPIO.9{slash}RXD4")
			(pinfunction "CH1")
			(pintype "passive")
			(solder_mask_margin 0.05)
		)
		(pad "2" smd rect
			(at -0.5 0.3875 90)
			(size 0.2 0.475)
			(layers "F.Cu" "F.Mask" "F.Paste")
			(net 227 "/Compute module/GPIO.11")
			(pinfunction "CH2")
			(pintype "passive")
			(solder_mask_margin 0.05)
		)
		(pad "3" smd rect
			(at 0 0.3875 90)
			(size 0.2 0.475)
			(layers "F.Cu" "F.Mask" "F.Paste")
			(net 3 "GND")
			(pinfunction "GND")
			(pintype "passive")
			(solder_mask_margin 0.05)
		)
		(pad "4" smd rect
			(at 0.5 0.3875 90)
			(size 0.2 0.475)
			(layers "F.Cu" "F.Mask" "F.Paste")
			(net 447 "/Compute module/GPIO.0{slash}SDA0")
			(pinfunction "CH3")
			(pintype "passive")
			(solder_mask_margin 0.05)
		)
		(pad "5" smd rect
			(at 1 0.3875 90)
			(size 0.2 0.475)
			(layers "F.Cu" "F.Mask" "F.Paste")
			(net 225 "/Compute module/GPIO.5{slash}RXD3")
			(pinfunction "CH4")
			(pintype "passive")
			(solder_mask_margin 0.05)
		)
		(pad "6" smd rect
			(at 1 -0.3875 90)
			(size 0.2 0.475)
			(layers "F.Cu" "F.Mask" "F.Paste")
			(net 225 "/Compute module/GPIO.5{slash}RXD3")
			(pinfunction "CH4")
			(pintype "passive")
			(solder_mask_margin 0.05)
		)
		(pad "7" smd rect
			(at 0.5 -0.3875 90)
			(size 0.2 0.475)
			(layers "F.Cu" "F.Mask" "F.Paste")
			(net 447 "/Compute module/GPIO.0{slash}SDA0")
			(pinfunction "CH3")
			(pintype "passive")
			(solder_mask_margin 0.05)
		)
		(pad "8" smd rect
			(at 0 -0.3875 90)
			(size 0.2 0.475)
			(layers "F.Cu" "F.Mask" "F.Paste")
			(net 3 "GND")
			(pinfunction "GND")
			(pintype "passive")
			(solder_mask_margin 0.05)
		)
		(pad "9" smd rect
			(at -0.501 -0.3875 90)
			(size 0.2 0.475)
			(layers "F.Cu" "F.Mask" "F.Paste")
			(net 227 "/Compute module/GPIO.11")
			(pinfunction "CH2")
			(pintype "passive")
			(solder_mask_margin 0.05)
		)
		(pad "10" smd rect
			(at -1 -0.3875 90)
			(size 0.2 0.475)
			(layers "F.Cu" "F.Mask" "F.Paste")
			(net 229 "/Compute module/GPIO.9{slash}RXD4")
			(pinfunction "CH1")
			(pintype "passive")
			(solder_mask_margin 0.05)
		)
	)
	(footprint "antmicro-footprints:R_0402_1005Metric"
		(layer "F.Cu")
		(at 57.342962 134.3665 90)
		(descr "Resistor SMD 0402")
		(tags "resistor SMD 0402")
		(property "Reference" "R414"
			(at -1.985 3.495 90)
			(layer "F.SilkS")
			(effects
				(font
					(size 0.7 0.7)
					(thickness 0.15)
				)
				(justify left bottom)
			)
		)
		(property "Value" "R_24k9_0402"
			(at -1.011843 1.772047 90)
			(layer "F.Fab")
			(effects
				(font
					(size 0.7 0.7)
					(thickness 0.15)
				)
				(justify left bottom)
			)
		)
		(property "Datasheet" "https://www.bourns.com/docs/product-datasheets/cr.pdf"
			(at 0 0 90)
			(layer "F.Fab")
			(hide yes)
			(effects
				(font
					(size 1.27 1.27)
					(thickness 0.15)
				)
			)
		)
		(property "Manufacturer" "Bourns"
			(at 0 0 90)
			(unlocked yes)
			(layer "F.Fab")
			(hide yes)
			(effects
				(font
					(size 1 1)
					(thickness 0.15)
				)
			)
		)
		(property "MPN" "CR0402-FX-2492GLF"
			(at 0 0 90)
			(unlocked yes)
			(layer "F.Fab")
			(hide yes)
			(effects
				(font
					(size 1 1)
					(thickness 0.15)
				)
			)
		)
		(property "Val" "24k9"
			(at 0 0 90)
			(unlocked yes)
			(layer "F.Fab")
			(hide yes)
			(effects
				(font
					(size 1 1)
					(thickness 0.15)
				)
			)
		)
		(property "License" "Apache-2.0"
			(at 0 0 90)
			(unlocked yes)
			(layer "F.Fab")
			(hide yes)
			(effects
				(font
					(size 1 1)
					(thickness 0.15)
				)
			)
		)
		(property "Author" "Antmicro"
			(at 0 0 90)
			(unlocked yes)
			(layer "F.Fab")
			(hide yes)
			(effects
				(font
					(size 1 1)
					(thickness 0.15)
				)
			)
		)
		(property "Tolerance" "1%"
			(at 0 0 90)
			(unlocked yes)
			(layer "F.Fab")
			(hide yes)
			(effects
				(font
					(size 1 1)
					(thickness 0.15)
				)
			)
		)
		(sheetname "/Ethernet/")
		(sheetfile "ethernet.kicad_sch")
		(attr smd)
		(fp_rect
			(start -0.925 -0.47)
			(end 0.925 0.47)
			(stroke
				(width 0.05)
				(type default)
			)
			(fill no)
			(layer "F.CrtYd")
		)
		(fp_rect
			(start -0.5 -0.25)
			(end 0.5 0.25)
			(stroke
				(width 0.15)
				(type solid)
			)
			(fill no)
			(layer "F.Fab")
		)
		(fp_text user "${REFERENCE}"
			(at -0.95 3.168 90)
			(layer "F.Fab")
			(effects
				(font
					(size 0.7 0.7)
					(thickness 0.15)
				)
				(justify left bottom)
			)
		)
		(fp_text user "License: Apache-2.0"
			(at -0.95 5.169 90)
			(layer "F.Fab")
			(effects
				(font
					(size 0.7 0.7)
					(thickness 0.15)
				)
				(justify left bottom)
			)
		)
		(fp_text user "Author: Antmicro"
			(at -0.95 4.169 90)
			(layer "F.Fab")
			(effects
				(font
					(size 0.7 0.7)
					(thickness 0.15)
				)
				(justify left bottom)
			)
		)
		(pad "1" smd roundrect
			(at -0.48 0 90)
			(size 0.59 0.64)
			(layers "F.Cu" "F.Mask" "F.Paste")
			(roundrect_rratio 0.25)
			(net 477 "Net-(D404-A)")
			(pintype "passive")
		)
		(pad "2" smd roundrect
			(at 0.48 0 90)
			(size 0.59 0.64)
			(layers "F.Cu" "F.Mask" "F.Paste")
			(roundrect_rratio 0.25)
			(net 33 "/Ethernet/VDD")
			(pintype "passive")
		)
	)
	(footprint "antmicro-footprints:Conn_Socket_Samtec_ERF5_2x20_ERF5-020-05.0-L-DV-K-TR"
		(layer "F.Cu")
		(at 138.417962 145.7165 90)
		(property "Reference" "J801"
			(at 5.13 -4.53 90)
			(layer "F.SilkS")
			(effects
				(font
					(size 0.7 0.7)
					(thickness 0.15)
				)
				(justify left bottom)
			)
		)
		(property "Value" "Socket_Samtec_ERF5_2x20_ERF5-020-05.0-L-DV-K-TR"
			(at 0 3.9 90)
			(layer "F.Fab")
			(effects
				(font
					(size 0.7 0.7)
					(thickness 0.15)
				)
				(justify left bottom)
			)
		)
		(property "Datasheet" "https://suddendocs.samtec.com/productspecs/erm5-erf5.pdf?_gl=1*1g914su*_ga*MTE0MzExNjY4MC4xNjcyMTQ5NTUz*_ga_3KFNZC07WW*MTY3Mjg0NzY5Ny42LjEuMTY3Mjg0ODE3MS42MC4wLjA."
			(at 0 0 90)
			(layer "F.Fab")
			(hide yes)
			(effects
				(font
					(size 1.27 1.27)
					(thickness 0.15)
				)
			)
		)
		(property "MPN" "ERF5-020-05.0-L-DV-K-TR"
			(at 0 0 90)
			(unlocked yes)
			(layer "F.Fab")
			(hide yes)
			(effects
				(font
					(size 1 1)
					(thickness 0.15)
				)
			)
		)
		(property "Manufacturer" "Samtec"
			(at 0 0 90)
			(unlocked yes)
			(layer "F.Fab")
			(hide yes)
			(effects
				(font
					(size 1 1)
					(thickness 0.15)
				)
			)
		)
		(property "Author" "Antmicro"
			(at 0 0 90)
			(unlocked yes)
			(layer "F.Fab")
			(hide yes)
			(effects
				(font
					(size 1 1)
					(thickness 0.15)
				)
			)
		)
		(property "License" "Apache-2.0"
			(at 0 0 90)
			(unlocked yes)
			(layer "F.Fab")
			(hide yes)
			(effects
				(font
					(size 1 1)
					(thickness 0.15)
				)
			)
		)
		(property "Pitch" "0.5 mm"
			(at 0 0 90)
			(unlocked yes)
			(layer "F.Fab")
			(hide yes)
			(effects
				(font
					(size 1 1)
					(thickness 0.15)
				)
			)
		)
		(sheetname "/Peripherals/")
		(sheetfile "peripherals.kicad_sch")
		(attr smd)
		(fp_line
			(start 8.401 -2.475)
			(end 8.401 2.476)
			(stroke
				(width 0.15)
				(type solid)
			)
			(layer "F.SilkS")
		)
		(fp_line
			(start 5.351 -2.475)
			(end 8.401 -2.475)
			(stroke
				(width 0.15)
				(type solid)
			)
			(layer "F.SilkS")
		)
		(fp_line
			(start -8.4 -2.475)
			(end -5.349 -2.475)
			(stroke
				(width 0.15)
				(type solid)
			)
			(layer "F.SilkS")
		)
		(fp_line
			(start 8.401 2.476)
			(end 5.351 2.476)
			(stroke
				(width 0.15)
				(type solid)
			)
			(layer "F.SilkS")
		)
		(fp_line
			(start -5.349 2.476)
			(end -8.4 2.476)
			(stroke
				(width 0.15)
				(type solid)
			)
			(layer "F.SilkS")
		)
		(fp_line
			(start -8.4 2.476)
			(end -8.4 -2.475)
			(stroke
				(width 0.15)
				(type solid)
			)
			(layer "F.SilkS")
		)
		(fp_circle
			(center -5.2 2.9)
			(end -5.25 2.9)
			(stroke
				(width 0.15)
				(type solid)
			)
			(fill no)
			(layer "F.SilkS")
		)
		(fp_poly
			(pts
				(xy 4.877 -1.225) (xy 4.624 -1.225) (xy 4.624 -2.725) (xy 4.877 -2.725)
			)
			(stroke
				(width 0.01)
				(type solid)
			)
			(fill yes)
			(layer "F.Paste")
		)
		(fp_poly
			(pts
				(xy 4.377 -1.225) (xy 4.124 -1.225) (xy 4.124 -2.725) (xy 4.377 -2.725)
			)
			(stroke
				(width 0.01)
				(type solid)
			)
			(fill yes)
			(layer "F.Paste")
		)
		(fp_poly
			(pts
				(xy 3.878 -1.225) (xy 3.625 -1.225) (xy 3.625 -2.725) (xy 3.878 -2.725)
			)
			(stroke
				(width 0.01)
				(type solid)
			)
			(fill yes)
			(layer "F.Paste")
		)
		(fp_poly
			(pts
				(xy 3.378 -1.225) (xy 3.125 -1.225) (xy 3.125 -2.725) (xy 3.378 -2.725)
			)
			(stroke
				(width 0.01)
				(type solid)
			)
			(fill yes)
			(layer "F.Paste")
		)
		(fp_poly
			(pts
				(xy 2.878 -1.225) (xy 2.625 -1.225) (xy 2.625 -2.725) (xy 2.878 -2.725)
			)
			(stroke
				(width 0.01)
				(type solid)
			)
			(fill yes)
			(layer "F.Paste")
		)
		(fp_poly
			(pts
				(xy 2.378 -1.225) (xy 2.125 -1.225) (xy 2.125 -2.725) (xy 2.378 -2.725)
			)
			(stroke
				(width 0.01)
				(type solid)
			)
			(fill yes)
			(layer "F.Paste")
		)
		(fp_poly
			(pts
				(xy 1.877 -1.225) (xy 1.623 -1.225) (xy 1.623 -2.725) (xy 1.877 -2.725)
			)
			(stroke
				(width 0.01)
				(type solid)
			)
			(fill yes)
			(layer "F.Paste")
		)
		(fp_poly
			(pts
				(xy 1.377 -1.225) (xy 1.123 -1.225) (xy 1.123 -2.725) (xy 1.377 -2.725)
			)
			(stroke
				(width 0.01)
				(type solid)
			)
			(fill yes)
			(layer "F.Paste")
		)
		(fp_poly
			(pts
				(xy 0.877 -1.225) (xy 0.623 -1.225) (xy 0.623 -2.725) (xy 0.877 -2.725)
			)
			(stroke
				(width 0.01)
				(type solid)
			)
			(fill yes)
			(layer "F.Paste")
		)
		(fp_poly
			(pts
				(xy 0.377 -1.225) (xy 0.123 -1.225) (xy 0.123 -2.725) (xy 0.377 -2.725)
			)
			(stroke
				(width 0.01)
				(type solid)
			)
			(fill yes)
			(layer "F.Paste")
		)
		(fp_poly
			(pts
				(xy -0.121 -1.225) (xy -0.375 -1.225) (xy -0.375 -2.725) (xy -0.121 -2.725)
			)
			(stroke
				(width 0.01)
				(type solid)
			)
			(fill yes)
			(layer "F.Paste")
		)
		(fp_poly
			(pts
				(xy -0.621 -1.225) (xy -0.875 -1.225) (xy -0.875 -2.725) (xy -0.621 -2.725)
			)
			(stroke
				(width 0.01)
				(type solid)
			)
			(fill yes)
			(layer "F.Paste")
		)
		(fp_poly
			(pts
				(xy -1.122 -1.225) (xy -1.376 -1.225) (xy -1.376 -2.725) (xy -1.122 -2.725)
			)
			(stroke
				(width 0.01)
				(type solid)
			)
			(fill yes)
			(layer "F.Paste")
		)
		(fp_poly
			(pts
				(xy -1.622 -1.225) (xy -1.876 -1.225) (xy -1.876 -2.725) (xy -1.622 -2.725)
			)
			(stroke
				(width 0.01)
				(type solid)
			)
			(fill yes)
			(layer "F.Paste")
		)
		(fp_poly
			(pts
				(xy -2.123 -1.225) (xy -2.375 -1.225) (xy -2.375 -2.725) (xy -2.123 -2.725)
			)
			(stroke
				(width 0.01)
				(type solid)
			)
			(fill yes)
			(layer "F.Paste")
		)
		(fp_poly
			(pts
				(xy -2.623 -1.225) (xy -2.875 -1.225) (xy -2.875 -2.725) (xy -2.623 -2.725)
			)
			(stroke
				(width 0.01)
				(type solid)
			)
			(fill yes)
			(layer "F.Paste")
		)
		(fp_poly
			(pts
				(xy -3.123 -1.225) (xy -3.375 -1.225) (xy -3.375 -2.725) (xy -3.123 -2.725)
			)
			(stroke
				(width 0.01)
				(type solid)
			)
			(fill yes)
			(layer "F.Paste")
		)
		(fp_poly
			(pts
				(xy -3.623 -1.225) (xy -3.875 -1.225) (xy -3.875 -2.725) (xy -3.623 -2.725)
			)
			(stroke
				(width 0.01)
				(type solid)
			)
			(fill yes)
			(layer "F.Paste")
		)
		(fp_poly
			(pts
				(xy -4.123 -1.225) (xy -4.376 -1.225) (xy -4.376 -2.725) (xy -4.123 -2.725)
			)
			(stroke
				(width 0.01)
				(type solid)
			)
			(fill yes)
			(layer "F.Paste")
		)
		(fp_poly
			(pts
				(xy -4.623 -1.225) (xy -4.876 -1.225) (xy -4.876 -2.725) (xy -4.623 -2.725)
			)
			(stroke
				(width 0.01)
				(type solid)
			)
			(fill yes)
			(layer "F.Paste")
		)
		(fp_poly
			(pts
				(xy 4.877 2.726) (xy 4.624 2.726) (xy 4.624 1.226) (xy 4.877 1.226)
			)
			(stroke
				(width 0.01)
				(type solid)
			)
			(fill yes)
			(layer "F.Paste")
		)
		(fp_poly
			(pts
				(xy 4.377 2.726) (xy 4.124 2.726) (xy 4.124 1.226) (xy 4.377 1.226)
			)
			(stroke
				(width 0.01)
				(type solid)
			)
			(fill yes)
			(layer "F.Paste")
		)
		(fp_poly
			(pts
				(xy 3.878 2.726) (xy 3.625 2.726) (xy 3.625 1.226) (xy 3.878 1.226)
			)
			(stroke
				(width 0.01)
				(type solid)
			)
			(fill yes)
			(layer "F.Paste")
		)
		(fp_poly
			(pts
				(xy 3.378 2.726) (xy 3.125 2.726) (xy 3.125 1.226) (xy 3.378 1.226)
			)
			(stroke
				(width 0.01)
				(type solid)
			)
			(fill yes)
			(layer "F.Paste")
		)
		(fp_poly
			(pts
				(xy 2.878 2.726) (xy 2.625 2.726) (xy 2.625 1.226) (xy 2.878 1.226)
			)
			(stroke
				(width 0.01)
				(type solid)
			)
			(fill yes)
			(layer "F.Paste")
		)
		(fp_poly
			(pts
				(xy 2.378 2.726) (xy 2.125 2.726) (xy 2.125 1.226) (xy 2.378 1.226)
			)
			(stroke
				(width 0.01)
				(type solid)
			)
			(fill yes)
			(layer "F.Paste")
		)
		(fp_poly
			(pts
				(xy 1.877 2.726) (xy 1.623 2.726) (xy 1.623 1.226) (xy 1.877 1.226)
			)
			(stroke
				(width 0.01)
				(type solid)
			)
			(fill yes)
			(layer "F.Paste")
		)
		(fp_poly
			(pts
				(xy 1.377 2.726) (xy 1.123 2.726) (xy 1.123 1.226) (xy 1.377 1.226)
			)
			(stroke
				(width 0.01)
				(type solid)
			)
			(fill yes)
			(layer "F.Paste")
		)
		(fp_poly
			(pts
				(xy 0.877 2.726) (xy 0.623 2.726) (xy 0.623 1.226) (xy 0.877 1.226)
			)
			(stroke
				(width 0.01)
				(type solid)
			)
			(fill yes)
			(layer "F.Paste")
		)
		(fp_poly
			(pts
				(xy 0.377 2.726) (xy 0.123 2.726) (xy 0.123 1.226) (xy 0.377 1.226)
			)
			(stroke
				(width 0.01)
				(type solid)
			)
			(fill yes)
			(layer "F.Paste")
		)
		(fp_poly
			(pts
				(xy -0.121 2.726) (xy -0.375 2.726) (xy -0.375 1.226) (xy -0.121 1.226)
			)
			(stroke
				(width 0.01)
				(type solid)
			)
			(fill yes)
			(layer "F.Paste")
		)
		(fp_poly
			(pts
				(xy -0.621 2.726) (xy -0.875 2.726) (xy -0.875 1.226) (xy -0.621 1.226)
			)
			(stroke
				(width 0.01)
				(type solid)
			)
			(fill yes)
			(layer "F.Paste")
		)
		(fp_poly
			(pts
				(xy -1.122 2.726) (xy -1.376 2.726) (xy -1.376 1.226) (xy -1.122 1.226)
			)
			(stroke
				(width 0.01)
				(type solid)
			)
			(fill yes)
			(layer "F.Paste")
		)
		(fp_poly
			(pts
				(xy -1.622 2.726) (xy -1.876 2.726) (xy -1.876 1.226) (xy -1.622 1.226)
			)
			(stroke
				(width 0.01)
				(type solid)
			)
			(fill yes)
			(layer "F.Paste")
		)
		(fp_poly
			(pts
				(xy -2.123 2.726) (xy -2.375 2.726) (xy -2.375 1.226) (xy -2.123 1.226)
			)
			(stroke
				(width 0.01)
				(type solid)
			)
			(fill yes)
			(layer "F.Paste")
		)
		(fp_poly
			(pts
				(xy -2.623 2.726) (xy -2.875 2.726) (xy -2.875 1.226) (xy -2.623 1.226)
			)
			(stroke
				(width 0.01)
				(type solid)
			)
			(fill yes)
			(layer "F.Paste")
		)
		(fp_poly
			(pts
				(xy -3.123 2.726) (xy -3.375 2.726) (xy -3.375 1.226) (xy -3.123 1.226)
			)
			(stroke
				(width 0.01)
				(type solid)
			)
			(fill yes)
			(layer "F.Paste")
		)
		(fp_poly
			(pts
				(xy -3.623 2.726) (xy -3.875 2.726) (xy -3.875 1.226) (xy -3.623 1.226)
			)
			(stroke
				(width 0.01)
				(type solid)
			)
			(fill yes)
			(layer "F.Paste")
		)
		(fp_poly
			(pts
				(xy -4.123 2.726) (xy -4.376 2.726) (xy -4.376 1.226) (xy -4.123 1.226)
			)
			(stroke
				(width 0.01)
				(type solid)
			)
			(fill yes)
			(layer "F.Paste")
		)
		(fp_poly
			(pts
				(xy -4.623 2.726) (xy -4.876 2.726) (xy -4.876 1.226) (xy -4.623 1.226)
			)
			(stroke
				(width 0.01)
				(type solid)
			)
			(fill yes)
			(layer "F.Paste")
		)
		(fp_rect
			(start 8.651 2.926)
			(end -8.65 -2.925)
			(stroke
				(width 0.05)
				(type solid)
			)
			(fill no)
			(layer "F.CrtYd")
		)
		(fp_line
			(start -8.39 1.35)
			(end -7.27 2.47)
			(stroke
				(width 0.15)
				(type solid)
			)
			(layer "F.Fab")
		)
		(fp_rect
			(start 8.401 2.476)
			(end -8.4 -2.475)
			(stroke
				(width 0.15)
				(type solid)
			)
			(fill no)
			(layer "F.Fab")
		)
		(fp_text user "${REFERENCE}"
			(at -9.401 8.008 90)
			(layer "F.Fab")
			(effects
				(font
					(size 0.7 0.7)
					(thickness 0.15)
				)
				(justify left bottom)
			)
		)
		(fp_text user "Author: Antmicro"
			(at -9.401 5.608 90)
			(layer "F.Fab")
			(effects
				(font
					(size 0.7 0.7)
					(thickness 0.15)
				)
				(justify left bottom)
			)
		)
		(fp_text user "License: Apache-2.0"
			(at -9.401 6.808 90)
			(layer "F.Fab")
			(effects
				(font
					(size 0.7 0.7)
					(thickness 0.15)
				)
				(justify left bottom)
			)
		)
		(pad "" np_thru_hole circle
			(at -6.9 1.401 270)
			(size 1.45 1.45)
			(drill 1.45)
			(layers "*.Cu" "*.Mask")
		)
		(pad "" np_thru_hole circle
			(at 6.901 1.401 270)
			(size 1.45 1.45)
			(drill 1.45)
			(layers "*.Cu" "*.Mask")
		)
		(pad "1" smd rect
			(at -4.748 1.976)
			(size 1.5 0.3)
			(layers "F.Cu" "F.Mask")
			(net 9 "+3V3")
			(pintype "passive")
		)
		(pad "2" smd rect
			(at -4.748 -1.975)
			(size 1.5 0.3)
			(layers "F.Cu" "F.Mask")
			(net 10 "+5V")
			(pintype "passive")
		)
		(pad "3" smd rect
			(at -4.248 1.976)
			(size 1.5 0.3)
			(layers "F.Cu" "F.Mask")
			(net 243 "/Compute module/GPIO.2")
			(pintype "passive")
		)
		(pad "4" smd rect
			(at -4.248 -1.975)
			(size 1.5 0.3)
			(layers "F.Cu" "F.Mask")
			(net 10 "+5V")
			(pintype "passive")
		)
		(pad "5" smd rect
			(at -3.749 1.976)
			(size 1.5 0.3)
			(layers "F.Cu" "F.Mask")
			(net 242 "/Compute module/GPIO.3")
			(pintype "passive")
		)
		(pad "6" smd rect
			(at -3.749 -1.975)
			(size 1.5 0.3)
			(layers "F.Cu" "F.Mask")
			(net 3 "GND")
			(pintype "passive")
		)
		(pad "7" smd rect
			(at -3.249 1.976)
			(size 1.5 0.3)
			(layers "F.Cu" "F.Mask")
			(net 240 "/Compute module/GPIO.4{slash}TXD3")
			(pintype "passive")
		)
		(pad "8" smd rect
			(at -3.249 -1.975)
			(size 1.5 0.3)
			(layers "F.Cu" "F.Mask")
			(net 239 "/Compute module/GPIO.14{slash}RXD0")
			(pintype "passive")
		)
		(pad "9" smd rect
			(at -2.749 1.976)
			(size 1.5 0.3)
			(layers "F.Cu" "F.Mask")
			(net 3 "GND")
			(pintype "passive")
		)
		(pad "10" smd rect
			(at -2.749 -1.975)
			(size 1.5 0.3)
			(layers "F.Cu" "F.Mask")
			(net 241 "/Compute module/GPIO.15{slash}TXD0")
			(pintype "passive")
		)
		(pad "11" smd rect
			(at -2.249 1.976)
			(size 1.5 0.3)
			(layers "F.Cu" "F.Mask")
			(net 238 "/Compute module/GPIO.17")
			(pintype "passive")
		)
		(pad "12" smd rect
			(at -2.249 -1.975)
			(size 1.5 0.3)
			(layers "F.Cu" "F.Mask")
			(net 237 "/Compute module/GPIO.18")
			(pintype "passive")
		)
		(pad "13" smd rect
			(at -1.749 1.976)
			(size 1.5 0.3)
			(layers "F.Cu" "F.Mask")
			(net 236 "/Compute module/GPIO.27")
			(pintype "passive")
		)
		(pad "14" smd rect
			(at -1.749 -1.975)
			(size 1.5 0.3)
			(layers "F.Cu" "F.Mask")
			(net 251 "/Compute module/GPIO.AIN1")
			(pintype "passive")
		)
		(pad "15" smd rect
			(at -1.249 1.976)
			(size 1.5 0.3)
			(layers "F.Cu" "F.Mask")
			(net 234 "/Compute module/GPIO.22")
			(pintype "passive")
		)
		(pad "16" smd rect
			(at -1.249 -1.975)
			(size 1.5 0.3)
			(layers "F.Cu" "F.Mask")
			(net 235 "/Compute module/GPIO.23")
			(pintype "passive")
		)
		(pad "17" smd rect
			(at -0.748 1.976)
			(size 1.5 0.3)
			(layers "F.Cu" "F.Mask")
			(net 9 "+3V3")
			(pintype "passive")
		)
		(pad "18" smd rect
			(at -0.748 -1.975)
			(size 1.5 0.3)
			(layers "F.Cu" "F.Mask")
			(net 233 "/Compute module/GPIO.24")
			(pintype "passive")
		)
		(pad "19" smd rect
			(at -0.248 1.976)
			(size 1.5 0.3)
			(layers "F.Cu" "F.Mask")
			(net 232 "/Compute module/GPIO.10")
			(pintype "passive")
		)
		(pad "20" smd rect
			(at -0.248 -1.975)
			(size 1.5 0.3)
			(layers "F.Cu" "F.Mask")
			(net 3 "GND")
			(pintype "passive")
		)
		(pad "21" smd rect
			(at 0.25 1.976)
			(size 1.5 0.3)
			(layers "F.Cu" "F.Mask")
			(net 229 "/Compute module/GPIO.9{slash}RXD4")
			(pintype "passive")
		)
		(pad "22" smd rect
			(at 0.25 -1.975)
			(size 1.5 0.3)
			(layers "F.Cu" "F.Mask")
			(net 230 "/Compute module/GPIO.25")
			(pintype "passive")
		)
		(pad "23" smd rect
			(at 0.75 1.976)
			(size 1.5 0.3)
			(layers "F.Cu" "F.Mask")
			(net 227 "/Compute module/GPIO.11")
			(pintype "passive")
		)
		(pad "24" smd rect
			(at 0.75 -1.975)
			(size 1.5 0.3)
			(layers "F.Cu" "F.Mask")
			(net 228 "/Compute module/GPIO.8{slash}TXD4")
			(pintype "passive")
		)
		(pad "25" smd rect
			(at 1.25 1.976)
			(size 1.5 0.3)
			(layers "F.Cu" "F.Mask")
			(net 3 "GND")
			(pintype "passive")
		)
		(pad "26" smd rect
			(at 1.25 -1.975)
			(size 1.5 0.3)
			(layers "F.Cu" "F.Mask")
			(net 226 "/Compute module/GPIO.7")
			(pintype "passive")
		)
		(pad "27" smd rect
			(at 1.75 1.976)
			(size 1.5 0.3)
			(layers "F.Cu" "F.Mask")
			(net 447 "/Compute module/GPIO.0{slash}SDA0")
			(pintype "passive")
		)
		(pad "28" smd rect
			(at 1.75 -1.975)
			(size 1.5 0.3)
			(layers "F.Cu" "F.Mask")
			(net 446 "/Compute module/GPIO.1{slash}SCL0")
			(pintype "passive")
		)
		(pad "29" smd rect
			(at 2.25 1.976)
			(size 1.5 0.3)
			(layers "F.Cu" "F.Mask")
			(net 225 "/Compute module/GPIO.5{slash}RXD3")
			(pintype "passive")
		)
		(pad "30" smd rect
			(at 2.25 -1.975)
			(size 1.5 0.3)
			(layers "F.Cu" "F.Mask")
			(net 253 "/Compute module/GPIO.AIN0")
			(pintype "passive")
		)
		(pad "31" smd rect
			(at 2.75 1.976)
			(size 1.5 0.3)
			(layers "F.Cu" "F.Mask")
			(net 223 "/Compute module/GPIO.6")
			(pintype "passive")
		)
		(pad "32" smd rect
			(at 2.75 -1.975)
			(size 1.5 0.3)
			(layers "F.Cu" "F.Mask")
			(net 224 "/Compute module/GPIO.12{slash}RXD5")
			(pintype "passive")
		)
		(pad "33" smd rect
			(at 3.25 1.976)
			(size 1.5 0.3)
			(layers "F.Cu" "F.Mask")
			(net 221 "/Compute module/GPIO.13{slash}TXD5")
			(pintype "passive")
		)
		(pad "34" smd rect
			(at 3.25 -1.975)
			(size 1.5 0.3)
			(layers "F.Cu" "F.Mask")
			(net 3 "GND")
			(pintype "passive")
		)
		(pad "35" smd rect
			(at 3.75 1.976)
			(size 1.5 0.3)
			(layers "F.Cu" "F.Mask")
			(net 219 "/Compute module/GPIO.19")
			(pintype "passive")
		)
		(pad "36" smd rect
			(at 3.75 -1.975)
			(size 1.5 0.3)
			(layers "F.Cu" "F.Mask")
			(net 222 "/Compute module/GPIO.16")
			(pintype "passive")
		)
		(pad "37" smd rect
			(at 4.25 1.976)
			(size 1.5 0.3)
			(layers "F.Cu" "F.Mask")
			(net 217 "/Compute module/GPIO.26")
			(pintype "passive")
		)
		(pad "38" smd rect
			(at 4.25 -1.975)
			(size 1.5 0.3)
			(layers "F.Cu" "F.Mask")
			(net 220 "/Compute module/GPIO.20")
			(pintype "passive")
		)
		(pad "39" smd rect
			(at 4.75 1.976)
			(size 1.5 0.3)
			(layers "F.Cu" "F.Mask")
			(net 3 "GND")
			(pintype "passive")
		)
		(pad "40" smd rect
			(at 4.75 -1.975)
			(size 1.5 0.3)
			(layers "F.Cu" "F.Mask")
			(net 218 "/Compute module/GPIO.21")
			(pintype "passive")
		)
	)
	(footprint "antmicro-footprints:C_0402_1005Metric"
		(layer "F.Cu")
		(at 61.117962 175.7255 -90)
		(descr "Capacitor SMD 0402")
		(tags "capacitor SMD 0402")
		(property "Reference" "C827"
			(at -3.579 14.88 90)
			(layer "F.SilkS")
			(effects
				(font
					(size 0.7 0.7)
					(thickness 0.15)
				)
				(justify right bottom)
			)
		)
		(property "Value" "C_template_name_0402"
			(at -1.022927 2.155213 90)
			(layer "F.Fab")
			(effects
				(font
					(size 0.7 0.7)
					(thickness 0.15)
				)
				(justify right bottom)
			)
		)
		(property "Datasheet" "template_datasheet"
			(at 0 0 270)
			(layer "F.Fab")
			(hide yes)
			(effects
				(font
					(size 1.27 1.27)
					(thickness 0.15)
				)
			)
		)
		(property "MPN" "template_MPN"
			(at 0 0 270)
			(unlocked yes)
			(layer "F.Fab")
			(hide yes)
			(effects
				(font
					(size 1 1)
					(thickness 0.15)
				)
			)
		)
		(property "Manufacturer" "template_manufacturer"
			(at 0 0 270)
			(unlocked yes)
			(layer "F.Fab")
			(hide yes)
			(effects
				(font
					(size 1 1)
					(thickness 0.15)
				)
			)
		)
		(property "License" "Apache-2.0"
			(at 0 0 270)
			(unlocked yes)
			(layer "F.Fab")
			(hide yes)
			(effects
				(font
					(size 1 1)
					(thickness 0.15)
				)
			)
		)
		(property "Author" "Antmicro"
			(at 0 0 270)
			(unlocked yes)
			(layer "F.Fab")
			(hide yes)
			(effects
				(font
					(size 1 1)
					(thickness 0.15)
				)
			)
		)
		(property "Val" "template_value"
			(at 0 0 270)
			(unlocked yes)
			(layer "F.Fab")
			(hide yes)
			(effects
				(font
					(size 1 1)
					(thickness 0.15)
				)
			)
		)
		(property "Voltage" "template_voltage"
			(at 0 0 270)
			(unlocked yes)
			(layer "F.Fab")
			(hide yes)
			(effects
				(font
					(size 1 1)
					(thickness 0.15)
				)
			)
		)
		(property "Dielectric" "template_dielectric"
			(at 0 0 270)
			(unlocked yes)
			(layer "F.Fab")
			(hide yes)
			(effects
				(font
					(size 1 1)
					(thickness 0.15)
				)
			)
		)
		(sheetname "/Peripherals/")
		(sheetfile "peripherals.kicad_sch")
		(attr smd exclude_from_pos_files exclude_from_bom dnp)
		(fp_rect
			(start -0.925 -0.47)
			(end 0.925 0.47)
			(stroke
				(width 0.05)
				(type default)
			)
			(fill no)
			(layer "F.CrtYd")
		)
		(fp_line
			(start -0.494 0.248)
			(end -0.494 -0.25)
			(stroke
				(width 0.15)
				(type solid)
			)
			(layer "F.Fab")
		)
		(fp_line
			(start 0.504 0.248)
			(end -0.494 0.248)
			(stroke
				(width 0.15)
				(type solid)
			)
			(layer "F.Fab")
		)
		(fp_line
			(start -0.494 -0.25)
			(end 0.504 -0.25)
			(stroke
				(width 0.15)
				(type solid)
			)
			(layer "F.Fab")
		)
		(fp_line
			(start 0.504 -0.25)
			(end 0.504 0.248)
			(stroke
				(width 0.15)
				(type solid)
			)
			(layer "F.Fab")
		)
		(fp_text user "${REFERENCE}"
			(at -0.939 4.599 270)
			(layer "F.Fab")
			(effects
				(font
					(size 0.7 0.7)
					(thickness 0.15)
				)
				(justify left bottom)
			)
		)
		(fp_text user "Author: Antmicro"
			(at -0.939 3.399 270)
			(layer "F.Fab")
			(effects
				(font
					(size 0.7 0.7)
					(thickness 0.15)
				)
				(justify left bottom)
			)
		)
		(fp_text user "License: Apache-2.0"
			(at -0.939 5.799 270)
			(layer "F.Fab")
			(effects
				(font
					(size 0.7 0.7)
					(thickness 0.15)
				)
				(justify left bottom)
			)
		)
		(pad "1" smd roundrect
			(at -0.48 0 270)
			(size 0.59 0.64)
			(layers "F.Cu" "F.Mask" "F.Paste")
			(roundrect_rratio 0.25)
			(net 106 "Net-(C814-Pad2)")
			(pintype "passive")
		)
		(pad "2" smd roundrect
			(at 0.48 0 270)
			(size 0.59 0.64)
			(layers "F.Cu" "F.Mask" "F.Paste")
			(roundrect_rratio 0.25)
			(net 3 "GND")
			(pintype "passive")
		)
	)
	(footprint "antmicro-footprints:R_0402_1005Metric"
		(layer "F.Cu")
		(at 100.767962 119.079 90)
		(descr "Resistor SMD 0402")
		(tags "resistor SMD 0402")
		(property "Reference" "R915"
			(at -26.5325 27.945 90)
			(layer "F.SilkS")
			(effects
				(font
					(size 0.7 0.7)
					(thickness 0.15)
				)
				(justify left bottom)
			)
		)
		(property "Value" "R_470k_0402"
			(at -1.011843 1.772047 90)
			(layer "F.Fab")
			(effects
				(font
					(size 0.7 0.7)
					(thickness 0.15)
				)
				(justify left bottom)
			)
		)
		(property "Datasheet" "https://www.bourns.com/docs/product-datasheets/cr.pdf"
			(at 0 0 90)
			(layer "F.Fab")
			(hide yes)
			(effects
				(font
					(size 1.27 1.27)
					(thickness 0.15)
				)
			)
		)
		(property "MPN" "CR0402-FX-4703GLF"
			(at 0 0 90)
			(unlocked yes)
			(layer "F.Fab")
			(hide yes)
			(effects
				(font
					(size 1 1)
					(thickness 0.15)
				)
			)
		)
		(property "Manufacturer" "Bourns"
			(at 0 0 90)
			(unlocked yes)
			(layer "F.Fab")
			(hide yes)
			(effects
				(font
					(size 1 1)
					(thickness 0.15)
				)
			)
		)
		(property "License" "Apache-2.0"
			(at 0 0 90)
			(unlocked yes)
			(layer "F.Fab")
			(hide yes)
			(effects
				(font
					(size 1 1)
					(thickness 0.15)
				)
			)
		)
		(property "Author" "Antmicro"
			(at 0 0 90)
			(unlocked yes)
			(layer "F.Fab")
			(hide yes)
			(effects
				(font
					(size 1 1)
					(thickness 0.15)
				)
			)
		)
		(property "Val" "470k"
			(at 0 0 90)
			(unlocked yes)
			(layer "F.Fab")
			(hide yes)
			(effects
				(font
					(size 1 1)
					(thickness 0.15)
				)
			)
		)
		(property "Tolerance" "1%"
			(at 0 0 90)
			(unlocked yes)
			(layer "F.Fab")
			(hide yes)
			(effects
				(font
					(size 1 1)
					(thickness 0.15)
				)
			)
		)
		(sheetname "/USB/")
		(sheetfile "usb.kicad_sch")
		(attr smd)
		(fp_rect
			(start -0.925 -0.47)
			(end 0.925 0.47)
			(stroke
				(width 0.05)
				(type default)
			)
			(fill no)
			(layer "F.CrtYd")
		)
		(fp_rect
			(start -0.5 -0.25)
			(end 0.5 0.25)
			(stroke
				(width 0.15)
				(type solid)
			)
			(fill no)
			(layer "F.Fab")
		)
		(fp_text user "${REFERENCE}"
			(at -0.95 3.168 90)
			(layer "F.Fab")
			(effects
				(font
					(size 0.7 0.7)
					(thickness 0.15)
				)
				(justify left bottom)
			)
		)
		(fp_text user "Author: Antmicro"
			(at -0.95 4.169 90)
			(layer "F.Fab")
			(effects
				(font
					(size 0.7 0.7)
					(thickness 0.15)
				)
				(justify left bottom)
			)
		)
		(fp_text user "License: Apache-2.0"
			(at -0.95 5.169 90)
			(layer "F.Fab")
			(effects
				(font
					(size 0.7 0.7)
					(thickness 0.15)
				)
				(justify left bottom)
			)
		)
		(pad "1" smd roundrect
			(at -0.48 0 90)
			(size 0.59 0.64)
			(layers "F.Cu" "F.Mask" "F.Paste")
			(roundrect_rratio 0.25)
			(net 432 "Net-(U906-CURRENT_MODE)")
			(pintype "passive")
		)
		(pad "2" smd roundrect
			(at 0.48 0 90)
			(size 0.59 0.64)
			(layers "F.Cu" "F.Mask" "F.Paste")
			(roundrect_rratio 0.25)
			(net 28 "/USB/+5V_{CAP}")
			(pintype "passive")
		)
	)
	(footprint "antmicro-footprints:Nexperia_DFN-10_2.5x1mm_P0.5mm"
		(layer "F.Cu")
		(at 132.342962 118.9415)
		(property "Reference" "D806"
			(at 1.415 0.355 0)
			(layer "F.SilkS")
			(effects
				(font
					(size 0.7 0.7)
					(thickness 0.15)
				)
				(justify left bottom)
			)
		)
		(property "Value" "PUSB3F96X_PASS"
			(at -0.016 1.705 0)
			(layer "F.Fab")
			(effects
				(font
					(size 0.7 0.7)
					(thickness 0.15)
				)
				(justify left bottom)
			)
		)
		(property "Datasheet" "https://mouser.com/datasheet/2/916/PUSB3F96-1600324.pdf"
			(at 0 0 0)
			(layer "F.Fab")
			(hide yes)
			(effects
				(font
					(size 1.27 1.27)
					(thickness 0.15)
				)
			)
		)
		(property "Manufacturer" "Nexperia"
			(at 0 0 0)
			(unlocked yes)
			(layer "F.Fab")
			(hide yes)
			(effects
				(font
					(size 1 1)
					(thickness 0.15)
				)
			)
		)
		(property "MPN" "PUSB3F96X"
			(at 0 0 0)
			(unlocked yes)
			(layer "F.Fab")
			(hide yes)
			(effects
				(font
					(size 1 1)
					(thickness 0.15)
				)
			)
		)
		(property "Author" "Antmicro"
			(at 0 0 0)
			(unlocked yes)
			(layer "F.Fab")
			(hide yes)
			(effects
				(font
					(size 1 1)
					(thickness 0.15)
				)
			)
		)
		(property "License" "Apache-2.0"
			(at 0 0 0)
			(unlocked yes)
			(layer "F.Fab")
			(hide yes)
			(effects
				(font
					(size 1 1)
					(thickness 0.15)
				)
			)
		)
		(sheetname "/Peripherals/")
		(sheetfile "peripherals.kicad_sch")
		(attr smd)
		(fp_line
			(start -1.375 -0.4)
			(end -1.375 0.4)
			(stroke
				(width 0.15)
				(type solid)
			)
			(layer "F.SilkS")
		)
		(fp_line
			(start 1.375 0.4)
			(end 1.375 -0.4)
			(stroke
				(width 0.15)
				(type solid)
			)
			(layer "F.SilkS")
		)
		(fp_circle
			(center -1.4 0.7)
			(end -1.349 0.7)
			(stroke
				(width 0.15)
				(type solid)
			)
			(fill yes)
			(layer "F.SilkS")
		)
		(fp_rect
			(start -1.4 -0.725)
			(end 1.4 0.725)
			(stroke
				(width 0.05)
				(type solid)
			)
			(fill no)
			(layer "F.CrtYd")
		)
		(fp_line
			(start -1.25 -0.5)
			(end -1.25 0.15)
			(stroke
				(width 0.15)
				(type solid)
			)
			(layer "F.Fab")
		)
		(fp_line
			(start -1.25 0.15)
			(end -0.9 0.5)
			(stroke
				(width 0.15)
				(type solid)
			)
			(layer "F.Fab")
		)
		(fp_line
			(start -0.9 0.5)
			(end 1.25 0.5)
			(stroke
				(width 0.15)
				(type solid)
			)
			(layer "F.Fab")
		)
		(fp_line
			(start 1.25 -0.5)
			(end -1.25 -0.5)
			(stroke
				(width 0.15)
				(type solid)
			)
			(layer "F.Fab")
		)
		(fp_line
			(start 1.25 0.5)
			(end 1.25 -0.5)
			(stroke
				(width 0.15)
				(type solid)
			)
			(layer "F.Fab")
		)
		(fp_text user "${REFERENCE}"
			(at -1.367 3.704 0)
			(layer "F.Fab")
			(effects
				(font
					(size 0.7 0.7)
					(thickness 0.15)
				)
				(justify left bottom)
			)
		)
		(fp_text user "License: Apache-2.0"
			(at -1.367 6.105 0)
			(layer "F.Fab")
			(effects
				(font
					(size 0.7 0.7)
					(thickness 0.15)
				)
				(justify left bottom)
			)
		)
		(fp_text user "Author: Antmicro"
			(at -1.367 4.905 0)
			(layer "F.Fab")
			(effects
				(font
					(size 0.7 0.7)
					(thickness 0.15)
				)
				(justify left bottom)
			)
		)
		(pad "1" smd rect
			(at -1 0.3875)
			(size 0.2 0.475)
			(layers "F.Cu" "F.Mask" "F.Paste")
			(net 142 "/CSI/I_{2}C1.SCL")
			(pinfunction "CH1")
			(pintype "passive")
			(solder_mask_margin 0.05)
		)
		(pad "2" smd rect
			(at -0.5 0.3875)
			(size 0.2 0.475)
			(layers "F.Cu" "F.Mask" "F.Paste")
			(net 143 "/CSI/I_{2}C1.SDA")
			(pinfunction "CH2")
			(pintype "passive")
			(solder_mask_margin 0.05)
		)
		(pad "3" smd rect
			(at 0 0.3875)
			(size 0.2 0.475)
			(layers "F.Cu" "F.Mask" "F.Paste")
			(net 3 "GND")
			(pinfunction "GND")
			(pintype "passive")
			(solder_mask_margin 0.05)
		)
		(pad "4" smd rect
			(at 0.5 0.3875)
			(size 0.2 0.475)
			(layers "F.Cu" "F.Mask" "F.Paste")
			(net 317 "/Peripherals/VLED")
			(pinfunction "CH3")
			(pintype "passive")
			(solder_mask_margin 0.05)
		)
		(pad "5" smd rect
			(at 1 0.3875)
			(size 0.2 0.475)
			(layers "F.Cu" "F.Mask" "F.Paste")
			(net 3 "GND")
			(pinfunction "CH4")
			(pintype "passive")
			(solder_mask_margin 0.05)
		)
		(pad "6" smd rect
			(at 1 -0.3875)
			(size 0.2 0.475)
			(layers "F.Cu" "F.Mask" "F.Paste")
			(net 3 "GND")
			(pinfunction "CH4")
			(pintype "passive")
			(solder_mask_margin 0.05)
		)
		(pad "7" smd rect
			(at 0.5 -0.3875)
			(size 0.2 0.475)
			(layers "F.Cu" "F.Mask" "F.Paste")
			(net 317 "/Peripherals/VLED")
			(pinfunction "CH3")
			(pintype "passive")
			(solder_mask_margin 0.05)
		)
		(pad "8" smd rect
			(at 0 -0.3875)
			(size 0.2 0.475)
			(layers "F.Cu" "F.Mask" "F.Paste")
			(net 3 "GND")
			(pinfunction "GND")
			(pintype "passive")
			(solder_mask_margin 0.05)
		)
		(pad "9" smd rect
			(at -0.501 -0.3875)
			(size 0.2 0.475)
			(layers "F.Cu" "F.Mask" "F.Paste")
			(net 143 "/CSI/I_{2}C1.SDA")
			(pinfunction "CH2")
			(pintype "passive")
			(solder_mask_margin 0.05)
		)
		(pad "10" smd rect
			(at -1 -0.3875)
			(size 0.2 0.475)
			(layers "F.Cu" "F.Mask" "F.Paste")
			(net 142 "/CSI/I_{2}C1.SCL")
			(pinfunction "CH1")
			(pintype "passive")
			(solder_mask_margin 0.05)
		)
	)
	(footprint "antmicro-footprints:C_0402_1005Metric"
		(layer "F.Cu")
		(at 91.867962 132.432236 90)
		(descr "Capacitor SMD 0402")
		(tags "capacitor SMD 0402")
		(property "Reference" "C919"
			(at 0.820736 0.46 90)
			(layer "F.SilkS")
			(effects
				(font
					(size 0.7 0.7)
					(thickness 0.15)
				)
				(justify left bottom)
			)
		)
		(property "Value" "C_100n_0402"
			(at -1.022927 2.155213 90)
			(layer "F.Fab")
			(effects
				(font
					(size 0.7 0.7)
					(thickness 0.15)
				)
				(justify left bottom)
			)
		)
		(property "Datasheet" "https://www.murata.com/products/productdetail?partno=GRM155R61H104KE14%23"
			(at 0 0 90)
			(layer "F.Fab")
			(hide yes)
			(effects
				(font
					(size 1.27 1.27)
					(thickness 0.15)
				)
			)
		)
		(property "Manufacturer" "Murata"
			(at 0 0 90)
			(unlocked yes)
			(layer "F.Fab")
			(hide yes)
			(effects
				(font
					(size 1 1)
					(thickness 0.15)
				)
			)
		)
		(property "MPN" "GRM155R61H104KE14D"
			(at 0 0 90)
			(unlocked yes)
			(layer "F.Fab")
			(hide yes)
			(effects
				(font
					(size 1 1)
					(thickness 0.15)
				)
			)
		)
		(property "Val" "100n"
			(at 0 0 90)
			(unlocked yes)
			(layer "F.Fab")
			(hide yes)
			(effects
				(font
					(size 1 1)
					(thickness 0.15)
				)
			)
		)
		(property "License" "Apache-2.0"
			(at 0 0 90)
			(unlocked yes)
			(layer "F.Fab")
			(hide yes)
			(effects
				(font
					(size 1 1)
					(thickness 0.15)
				)
			)
		)
		(property "Author" "Antmicro"
			(at 0 0 90)
			(unlocked yes)
			(layer "F.Fab")
			(hide yes)
			(effects
				(font
					(size 1 1)
					(thickness 0.15)
				)
			)
		)
		(property "Voltage" "50V"
			(at 0 0 90)
			(unlocked yes)
			(layer "F.Fab")
			(hide yes)
			(effects
				(font
					(size 1 1)
					(thickness 0.15)
				)
			)
		)
		(property "Dielectric" "X5R"
			(at 0 0 90)
			(unlocked yes)
			(layer "F.Fab")
			(hide yes)
			(effects
				(font
					(size 1 1)
					(thickness 0.15)
				)
			)
		)
		(sheetname "/USB/")
		(sheetfile "usb.kicad_sch")
		(attr smd)
		(fp_rect
			(start -0.925 -0.47)
			(end 0.925 0.47)
			(stroke
				(width 0.05)
				(type default)
			)
			(fill no)
			(layer "F.CrtYd")
		)
		(fp_line
			(start 0.504 -0.25)
			(end 0.504 0.248)
			(stroke
				(width 0.15)
				(type solid)
			)
			(layer "F.Fab")
		)
		(fp_line
			(start -0.494 -0.25)
			(end 0.504 -0.25)
			(stroke
				(width 0.15)
				(type solid)
			)
			(layer "F.Fab")
		)
		(fp_line
			(start 0.504 0.248)
			(end -0.494 0.248)
			(stroke
				(width 0.15)
				(type solid)
			)
			(layer "F.Fab")
		)
		(fp_line
			(start -0.494 0.248)
			(end -0.494 -0.25)
			(stroke
				(width 0.15)
				(type solid)
			)
			(layer "F.Fab")
		)
		(fp_text user "License: Apache-2.0"
			(at -0.939 5.799 90)
			(layer "F.Fab")
			(effects
				(font
					(size 0.7 0.7)
					(thickness 0.15)
				)
				(justify left bottom)
			)
		)
		(fp_text user "${REFERENCE}"
			(at -0.939 4.599 90)
			(layer "F.Fab")
			(effects
				(font
					(size 0.7 0.7)
					(thickness 0.15)
				)
				(justify left bottom)
			)
		)
		(fp_text user "Author: Antmicro"
			(at -0.939 3.399 90)
			(layer "F.Fab")
			(effects
				(font
					(size 0.7 0.7)
					(thickness 0.15)
				)
				(justify left bottom)
			)
		)
		(pad "1" smd roundrect
			(at -0.48 0 90)
			(size 0.59 0.64)
			(layers "F.Cu" "F.Mask" "F.Paste")
			(roundrect_rratio 0.25)
			(net 32 "/USB/VCC_USB")
			(pintype "passive")
		)
		(pad "2" smd roundrect
			(at 0.48 0 90)
			(size 0.59 0.64)
			(layers "F.Cu" "F.Mask" "F.Paste")
			(roundrect_rratio 0.25)
			(net 3 "GND")
			(pintype "passive")
		)
	)
	(footprint "antmicro-footprints:TP_SMD_0.75mm"
		(layer "F.Cu")
		(at 74.9 151.43 180)
		(property "Reference" "TP210"
			(at 3.7 -0.25 180)
			(layer "F.SilkS")
			(effects
				(font
					(size 0.7 0.7)
					(thickness 0.15)
				)
				(justify left bottom)
			)
		)
		(property "Value" "TP_0.75mm_SMD"
			(at 0 1.2 180)
			(layer "F.Fab")
			(effects
				(font
					(size 0.7 0.7)
					(thickness 0.15)
				)
				(justify left bottom)
			)
		)
		(property "Author" "Antmicro"
			(at 0 0 180)
			(unlocked yes)
			(layer "F.Fab")
			(hide yes)
			(effects
				(font
					(size 1 1)
					(thickness 0.15)
				)
			)
		)
		(property "License" "Apache-2.0"
			(at 0 0 180)
			(unlocked yes)
			(layer "F.Fab")
			(hide yes)
			(effects
				(font
					(size 1 1)
					(thickness 0.15)
				)
			)
		)
		(property "MPN" ""
			(at 0 0 180)
			(unlocked yes)
			(layer "F.Fab")
			(hide yes)
			(effects
				(font
					(size 1 1)
					(thickness 0.15)
				)
			)
		)
		(property "Manufacturer" ""
			(at 0 0 180)
			(unlocked yes)
			(layer "F.Fab")
			(hide yes)
			(effects
				(font
					(size 1 1)
					(thickness 0.15)
				)
			)
		)
		(sheetname "/Compute module/")
		(sheetfile "compute-module.kicad_sch")
		(attr exclude_from_pos_files exclude_from_bom)
		(fp_circle
			(center 0 0)
			(end 0.475 0)
			(stroke
				(width 0.05)
				(type default)
			)
			(fill no)
			(layer "F.CrtYd")
		)
		(fp_text user "${REFERENCE}"
			(at -0.4 2.7 180)
			(layer "F.Fab")
			(effects
				(font
					(size 0.7 0.7)
					(thickness 0.15)
				)
				(justify left bottom)
			)
		)
		(fp_text user "License: Apache-2.0"
			(at -0.4 5.101 180)
			(layer "F.Fab")
			(effects
				(font
					(size 0.7 0.7)
					(thickness 0.15)
				)
				(justify left bottom)
			)
		)
		(fp_text user "Author: Antmicro"
			(at -0.4 3.901 180)
			(layer "F.Fab")
			(effects
				(font
					(size 0.7 0.7)
					(thickness 0.15)
				)
				(justify left bottom)
			)
		)
		(pad "1" smd circle
			(at 0 0 180)
			(size 0.75 0.75)
			(layers "F.Cu" "F.Mask")
			(net 22 "+1V8")
			(pinfunction "1")
			(pintype "passive")
		)
	)
	(footprint "antmicro-footprints:R_0402_1005Metric"
		(layer "F.Cu")
		(at 137.787962 154.8665)
		(descr "Resistor SMD 0402")
		(tags "resistor SMD 0402")
		(property "Reference" "R606"
			(at 0.98 0.45 0)
			(layer "F.SilkS")
			(effects
				(font
					(size 0.7 0.7)
					(thickness 0.15)
				)
				(justify left bottom)
			)
		)
		(property "Value" "R_1k_0402"
			(at -1.011843 1.772047 0)
			(layer "F.Fab")
			(effects
				(font
					(size 0.7 0.7)
					(thickness 0.15)
				)
				(justify left bottom)
			)
		)
		(property "Datasheet" "https://www.bourns.com/docs/product-datasheets/cr.pdf"
			(at 0 0 0)
			(layer "F.Fab")
			(hide yes)
			(effects
				(font
					(size 1.27 1.27)
					(thickness 0.15)
				)
			)
		)
		(property "MPN" "CR0402-FX-1001GLF"
			(at 0 0 0)
			(unlocked yes)
			(layer "F.Fab")
			(hide yes)
			(effects
				(font
					(size 1 1)
					(thickness 0.15)
				)
			)
		)
		(property "Manufacturer" "Bourns"
			(at 0 0 0)
			(unlocked yes)
			(layer "F.Fab")
			(hide yes)
			(effects
				(font
					(size 1 1)
					(thickness 0.15)
				)
			)
		)
		(property "License" "Apache-2.0"
			(at 0 0 0)
			(unlocked yes)
			(layer "F.Fab")
			(hide yes)
			(effects
				(font
					(size 1 1)
					(thickness 0.15)
				)
			)
		)
		(property "Author" "Antmicro"
			(at 0 0 0)
			(unlocked yes)
			(layer "F.Fab")
			(hide yes)
			(effects
				(font
					(size 1 1)
					(thickness 0.15)
				)
			)
		)
		(property "Val" "1k"
			(at 0 0 0)
			(unlocked yes)
			(layer "F.Fab")
			(hide yes)
			(effects
				(font
					(size 1 1)
					(thickness 0.15)
				)
			)
		)
		(property "Tolerance" "1%"
			(at 0 0 0)
			(unlocked yes)
			(layer "F.Fab")
			(hide yes)
			(effects
				(font
					(size 1 1)
					(thickness 0.15)
				)
			)
		)
		(sheetname "/CSI/")
		(sheetfile "csi.kicad_sch")
		(attr smd)
		(fp_rect
			(start -0.925 -0.47)
			(end 0.925 0.47)
			(stroke
				(width 0.05)
				(type default)
			)
			(fill no)
			(layer "F.CrtYd")
		)
		(fp_rect
			(start -0.5 -0.25)
			(end 0.5 0.25)
			(stroke
				(width 0.15)
				(type solid)
			)
			(fill no)
			(layer "F.Fab")
		)
		(fp_text user "${REFERENCE}"
			(at -0.95 3.168 0)
			(layer "F.Fab")
			(effects
				(font
					(size 0.7 0.7)
					(thickness 0.15)
				)
				(justify left bottom)
			)
		)
		(fp_text user "License: Apache-2.0"
			(at -0.95 5.169 0)
			(layer "F.Fab")
			(effects
				(font
					(size 0.7 0.7)
					(thickness 0.15)
				)
				(justify left bottom)
			)
		)
		(fp_text user "Author: Antmicro"
			(at -0.95 4.169 0)
			(layer "F.Fab")
			(effects
				(font
					(size 0.7 0.7)
					(thickness 0.15)
				)
				(justify left bottom)
			)
		)
		(pad "1" smd roundrect
			(at -0.48 0)
			(size 0.59 0.64)
			(layers "F.Cu" "F.Mask" "F.Paste")
			(roundrect_rratio 0.25)
			(net 479 "Net-(D601-A)")
			(pintype "passive")
		)
		(pad "2" smd roundrect
			(at 0.48 0)
			(size 0.59 0.64)
			(layers "F.Cu" "F.Mask" "F.Paste")
			(roundrect_rratio 0.25)
			(net 20 "/CSI/CSI_5V")
			(pintype "passive")
		)
	)
	(footprint "antmicro-footprints:C_0402_1005Metric"
		(layer "F.Cu")
		(at 66.142962 172.7165 180)
		(descr "Capacitor SMD 0402")
		(tags "capacitor SMD 0402")
		(property "Reference" "C807"
			(at 0.892962 -0.0335 0)
			(layer "F.SilkS")
			(effects
				(font
					(size 0.7 0.7)
					(thickness 0.15)
				)
				(justify right bottom)
			)
		)
		(property "Value" "C_2u2_0402"
			(at -1.022927 2.155213 0)
			(layer "F.Fab")
			(effects
				(font
					(size 0.7 0.7)
					(thickness 0.15)
				)
				(justify right bottom)
			)
		)
		(property "Datasheet" "https://product.tdk.com/en/search/capacitor/ceramic/mlcc/info?part_no=C1005X5R1A225K050BC"
			(at 0 0 180)
			(layer "F.Fab")
			(hide yes)
			(effects
				(font
					(size 1.27 1.27)
					(thickness 0.15)
				)
			)
		)
		(property "MPN" "C1005X5R1A225K050BC"
			(at 0 0 180)
			(unlocked yes)
			(layer "F.Fab")
			(hide yes)
			(effects
				(font
					(size 1 1)
					(thickness 0.15)
				)
			)
		)
		(property "Manufacturer" "TDK"
			(at 0 0 180)
			(unlocked yes)
			(layer "F.Fab")
			(hide yes)
			(effects
				(font
					(size 1 1)
					(thickness 0.15)
				)
			)
		)
		(property "License" "Apache-2.0"
			(at 0 0 180)
			(unlocked yes)
			(layer "F.Fab")
			(hide yes)
			(effects
				(font
					(size 1 1)
					(thickness 0.15)
				)
			)
		)
		(property "Author" "Antmicro"
			(at 0 0 180)
			(unlocked yes)
			(layer "F.Fab")
			(hide yes)
			(effects
				(font
					(size 1 1)
					(thickness 0.15)
				)
			)
		)
		(property "Val" "2u2"
			(at 0 0 180)
			(unlocked yes)
			(layer "F.Fab")
			(hide yes)
			(effects
				(font
					(size 1 1)
					(thickness 0.15)
				)
			)
		)
		(property "Voltage" ""
			(at 0 0 180)
			(unlocked yes)
			(layer "F.Fab")
			(hide yes)
			(effects
				(font
					(size 1 1)
					(thickness 0.15)
				)
			)
		)
		(property "Dielectric" ""
			(at 0 0 180)
			(unlocked yes)
			(layer "F.Fab")
			(hide yes)
			(effects
				(font
					(size 1 1)
					(thickness 0.15)
				)
			)
		)
		(sheetname "/Peripherals/")
		(sheetfile "peripherals.kicad_sch")
		(attr smd)
		(fp_rect
			(start -0.925 -0.47)
			(end 0.925 0.47)
			(stroke
				(width 0.05)
				(type default)
			)
			(fill no)
			(layer "F.CrtYd")
		)
		(fp_line
			(start 0.504 0.248)
			(end -0.494 0.248)
			(stroke
				(width 0.15)
				(type solid)
			)
			(layer "F.Fab")
		)
		(fp_line
			(start 0.504 -0.25)
			(end 0.504 0.248)
			(stroke
				(width 0.15)
				(type solid)
			)
			(layer "F.Fab")
		)
		(fp_line
			(start -0.494 0.248)
			(end -0.494 -0.25)
			(stroke
				(width 0.15)
				(type solid)
			)
			(layer "F.Fab")
		)
		(fp_line
			(start -0.494 -0.25)
			(end 0.504 -0.25)
			(stroke
				(width 0.15)
				(type solid)
			)
			(layer "F.Fab")
		)
		(fp_text user "License: Apache-2.0"
			(at -0.939 5.799 180)
			(layer "F.Fab")
			(effects
				(font
					(size 0.7 0.7)
					(thickness 0.15)
				)
				(justify left bottom)
			)
		)
		(fp_text user "${REFERENCE}"
			(at -0.939 4.599 180)
			(layer "F.Fab")
			(effects
				(font
					(size 0.7 0.7)
					(thickness 0.15)
				)
				(justify left bottom)
			)
		)
		(fp_text user "Author: Antmicro"
			(at -0.939 3.399 180)
			(layer "F.Fab")
			(effects
				(font
					(size 0.7 0.7)
					(thickness 0.15)
				)
				(justify left bottom)
			)
		)
		(pad "1" smd roundrect
			(at -0.48 0 180)
			(size 0.59 0.64)
			(layers "F.Cu" "F.Mask" "F.Paste")
			(roundrect_rratio 0.25)
			(net 94 "Net-(U801-TVDD_IN)")
			(pintype "passive")
		)
		(pad "2" smd roundrect
			(at 0.48 0 180)
			(size 0.59 0.64)
			(layers "F.Cu" "F.Mask" "F.Paste")
			(roundrect_rratio 0.25)
			(net 3 "GND")
			(pintype "passive")
		)
	)
	(footprint "antmicro-footprints:R_0402_1005Metric"
		(layer "F.Cu")
		(at 68.292962 143.9065 180)
		(descr "Resistor SMD 0402")
		(tags "resistor SMD 0402")
		(property "Reference" "R2"
			(at -0.45 0.565 0)
			(layer "F.SilkS")
			(effects
				(font
					(size 0.7 0.7)
					(thickness 0.15)
				)
				(justify right bottom)
			)
		)
		(property "Value" "R_0R_0402"
			(at -1.011843 1.772047 0)
			(layer "F.Fab")
			(effects
				(font
					(size 0.7 0.7)
					(thickness 0.15)
				)
				(justify right bottom)
			)
		)
		(property "Datasheet" "https://industrial.panasonic.com/cdbs/www-data/pdf/RDA0000/AOA0000C301.pdf"
			(at 0 0 180)
			(layer "F.Fab")
			(hide yes)
			(effects
				(font
					(size 1.27 1.27)
					(thickness 0.15)
				)
			)
		)
		(property "Manufacturer" "Panasonic"
			(at 0 0 180)
			(unlocked yes)
			(layer "F.Fab")
			(hide yes)
			(effects
				(font
					(size 1 1)
					(thickness 0.15)
				)
			)
		)
		(property "MPN" "ERJ2GE0R00X"
			(at 0 0 180)
			(unlocked yes)
			(layer "F.Fab")
			(hide yes)
			(effects
				(font
					(size 1 1)
					(thickness 0.15)
				)
			)
		)
		(property "Val" "0R"
			(at 0 0 180)
			(unlocked yes)
			(layer "F.Fab")
			(hide yes)
			(effects
				(font
					(size 1 1)
					(thickness 0.15)
				)
			)
		)
		(property "License" "Apache-2.0"
			(at 0 0 180)
			(unlocked yes)
			(layer "F.Fab")
			(hide yes)
			(effects
				(font
					(size 1 1)
					(thickness 0.15)
				)
			)
		)
		(property "Author" "Antmicro"
			(at 0 0 180)
			(unlocked yes)
			(layer "F.Fab")
			(hide yes)
			(effects
				(font
					(size 1 1)
					(thickness 0.15)
				)
			)
		)
		(property "Tolerance" "~"
			(at 0 0 180)
			(unlocked yes)
			(layer "F.Fab")
			(hide yes)
			(effects
				(font
					(size 1 1)
					(thickness 0.15)
				)
			)
		)
		(property "Current" "1A"
			(at 0 0 180)
			(unlocked yes)
			(layer "F.Fab")
			(hide yes)
			(effects
				(font
					(size 1 1)
					(thickness 0.15)
				)
			)
		)
		(sheetname "/Compute module/")
		(sheetfile "compute-module.kicad_sch")
		(attr smd)
		(fp_rect
			(start -0.925 -0.47)
			(end 0.925 0.47)
			(stroke
				(width 0.05)
				(type default)
			)
			(fill no)
			(layer "F.CrtYd")
		)
		(fp_rect
			(start -0.5 -0.25)
			(end 0.5 0.25)
			(stroke
				(width 0.15)
				(type solid)
			)
			(fill no)
			(layer "F.Fab")
		)
		(fp_text user "Author: Antmicro"
			(at -0.95 4.169 180)
			(layer "F.Fab")
			(effects
				(font
					(size 0.7 0.7)
					(thickness 0.15)
				)
				(justify left bottom)
			)
		)
		(fp_text user "License: Apache-2.0"
			(at -0.95 5.169 180)
			(layer "F.Fab")
			(effects
				(font
					(size 0.7 0.7)
					(thickness 0.15)
				)
				(justify left bottom)
			)
		)
		(fp_text user "${REFERENCE}"
			(at -0.95 3.168 180)
			(layer "F.Fab")
			(effects
				(font
					(size 0.7 0.7)
					(thickness 0.15)
				)
				(justify left bottom)
			)
		)
		(pad "1" smd roundrect
			(at -0.48 0 180)
			(size 0.59 0.64)
			(layers "F.Cu" "F.Mask" "F.Paste")
			(roundrect_rratio 0.25)
			(net 252 "/Compute module/~{PWR_LED}")
			(pintype "passive")
		)
		(pad "2" smd roundrect
			(at 0.48 0 180)
			(size 0.59 0.64)
			(layers "F.Cu" "F.Mask" "F.Paste")
			(roundrect_rratio 0.25)
			(net 491 "Net-(Q206-G)")
			(pintype "passive")
		)
	)
	(footprint "antmicro-footprints:R_0402_1005Metric"
		(layer "F.Cu")
		(at 133.767962 121.1915 -90)
		(descr "Resistor SMD 0402")
		(tags "resistor SMD 0402")
		(property "Reference" "R801"
			(at 6.895 -0.53 90)
			(layer "F.SilkS")
			(effects
				(font
					(size 0.7 0.7)
					(thickness 0.15)
				)
				(justify right bottom)
			)
		)
		(property "Value" "R_0R_0402"
			(at -1.011843 1.772047 90)
			(layer "F.Fab")
			(effects
				(font
					(size 0.7 0.7)
					(thickness 0.15)
				)
				(justify right bottom)
			)
		)
		(property "Datasheet" "https://industrial.panasonic.com/cdbs/www-data/pdf/RDA0000/AOA0000C301.pdf"
			(at 0 0 270)
			(layer "F.Fab")
			(hide yes)
			(effects
				(font
					(size 1.27 1.27)
					(thickness 0.15)
				)
			)
		)
		(property "MPN" "ERJ2GE0R00X"
			(at 0 0 270)
			(unlocked yes)
			(layer "F.Fab")
			(hide yes)
			(effects
				(font
					(size 1 1)
					(thickness 0.15)
				)
			)
		)
		(property "Manufacturer" "Panasonic"
			(at 0 0 270)
			(unlocked yes)
			(layer "F.Fab")
			(hide yes)
			(effects
				(font
					(size 1 1)
					(thickness 0.15)
				)
			)
		)
		(property "License" "Apache-2.0"
			(at 0 0 270)
			(unlocked yes)
			(layer "F.Fab")
			(hide yes)
			(effects
				(font
					(size 1 1)
					(thickness 0.15)
				)
			)
		)
		(property "Author" "Antmicro"
			(at 0 0 270)
			(unlocked yes)
			(layer "F.Fab")
			(hide yes)
			(effects
				(font
					(size 1 1)
					(thickness 0.15)
				)
			)
		)
		(property "Val" "0R"
			(at 0 0 270)
			(unlocked yes)
			(layer "F.Fab")
			(hide yes)
			(effects
				(font
					(size 1 1)
					(thickness 0.15)
				)
			)
		)
		(property "Tolerance" "~"
			(at 0 0 270)
			(unlocked yes)
			(layer "F.Fab")
			(hide yes)
			(effects
				(font
					(size 1 1)
					(thickness 0.15)
				)
			)
		)
		(property "Current" "1A"
			(at 0 0 270)
			(unlocked yes)
			(layer "F.Fab")
			(hide yes)
			(effects
				(font
					(size 1 1)
					(thickness 0.15)
				)
			)
		)
		(sheetname "/Peripherals/")
		(sheetfile "peripherals.kicad_sch")
		(attr smd exclude_from_pos_files exclude_from_bom dnp)
		(fp_rect
			(start -0.925 -0.47)
			(end 0.925 0.47)
			(stroke
				(width 0.05)
				(type default)
			)
			(fill no)
			(layer "F.CrtYd")
		)
		(fp_rect
			(start -0.5 -0.25)
			(end 0.5 0.25)
			(stroke
				(width 0.15)
				(type solid)
			)
			(fill no)
			(layer "F.Fab")
		)
		(fp_text user "Author: Antmicro"
			(at -0.95 4.169 270)
			(layer "F.Fab")
			(effects
				(font
					(size 0.7 0.7)
					(thickness 0.15)
				)
				(justify left bottom)
			)
		)
		(fp_text user "${REFERENCE}"
			(at -0.95 3.168 270)
			(layer "F.Fab")
			(effects
				(font
					(size 0.7 0.7)
					(thickness 0.15)
				)
				(justify left bottom)
			)
		)
		(fp_text user "License: Apache-2.0"
			(at -0.95 5.169 270)
			(layer "F.Fab")
			(effects
				(font
					(size 0.7 0.7)
					(thickness 0.15)
				)
				(justify left bottom)
			)
		)
		(pad "1" smd roundrect
			(at -0.48 0 270)
			(size 0.59 0.64)
			(layers "F.Cu" "F.Mask" "F.Paste")
			(roundrect_rratio 0.25)
			(net 317 "/Peripherals/VLED")
			(pintype "passive")
		)
		(pad "2" smd roundrect
			(at 0.48 0 270)
			(size 0.59 0.64)
			(layers "F.Cu" "F.Mask" "F.Paste")
			(roundrect_rratio 0.25)
			(net 10 "+5V")
			(pintype "passive")
		)
	)
	(footprint "antmicro-footprints:R_0402_1005Metric"
		(layer "F.Cu")
		(at 54.827962 130.8765)
		(descr "Resistor SMD 0402")
		(tags "resistor SMD 0402")
		(property "Reference" "R407"
			(at -1.49 -5.38 0)
			(layer "F.SilkS")
			(effects
				(font
					(size 0.7 0.7)
					(thickness 0.15)
				)
				(justify left bottom)
			)
		)
		(property "Value" "R_10k_0402"
			(at -1.011843 1.772047 0)
			(layer "F.Fab")
			(effects
				(font
					(size 0.7 0.7)
					(thickness 0.15)
				)
				(justify left bottom)
			)
		)
		(property "Datasheet" "https://www.bourns.com/docs/product-datasheets/cr.pdf"
			(at 0 0 0)
			(layer "F.Fab")
			(hide yes)
			(effects
				(font
					(size 1.27 1.27)
					(thickness 0.15)
				)
			)
		)
		(property "Manufacturer" "Bourns"
			(at 0 0 0)
			(unlocked yes)
			(layer "F.Fab")
			(hide yes)
			(effects
				(font
					(size 1 1)
					(thickness 0.15)
				)
			)
		)
		(property "MPN" "CR0402-FX-1002GLF"
			(at 0 0 0)
			(unlocked yes)
			(layer "F.Fab")
			(hide yes)
			(effects
				(font
					(size 1 1)
					(thickness 0.15)
				)
			)
		)
		(property "Val" "10k"
			(at 0 0 0)
			(unlocked yes)
			(layer "F.Fab")
			(hide yes)
			(effects
				(font
					(size 1 1)
					(thickness 0.15)
				)
			)
		)
		(property "License" "Apache-2.0"
			(at 0 0 0)
			(unlocked yes)
			(layer "F.Fab")
			(hide yes)
			(effects
				(font
					(size 1 1)
					(thickness 0.15)
				)
			)
		)
		(property "Author" "Antmicro"
			(at 0 0 0)
			(unlocked yes)
			(layer "F.Fab")
			(hide yes)
			(effects
				(font
					(size 1 1)
					(thickness 0.15)
				)
			)
		)
		(property "Tolerance" "1%"
			(at 0 0 0)
			(unlocked yes)
			(layer "F.Fab")
			(hide yes)
			(effects
				(font
					(size 1 1)
					(thickness 0.15)
				)
			)
		)
		(sheetname "/Ethernet/")
		(sheetfile "ethernet.kicad_sch")
		(attr smd exclude_from_pos_files exclude_from_bom dnp)
		(fp_rect
			(start -0.925 -0.47)
			(end 0.925 0.47)
			(stroke
				(width 0.05)
				(type default)
			)
			(fill no)
			(layer "F.CrtYd")
		)
		(fp_rect
			(start -0.5 -0.25)
			(end 0.5 0.25)
			(stroke
				(width 0.15)
				(type solid)
			)
			(fill no)
			(layer "F.Fab")
		)
		(fp_text user "${REFERENCE}"
			(at -0.95 3.168 0)
			(layer "F.Fab")
			(effects
				(font
					(size 0.7 0.7)
					(thickness 0.15)
				)
				(justify left bottom)
			)
		)
		(fp_text user "Author: Antmicro"
			(at -0.95 4.169 0)
			(layer "F.Fab")
			(effects
				(font
					(size 0.7 0.7)
					(thickness 0.15)
				)
				(justify left bottom)
			)
		)
		(fp_text user "License: Apache-2.0"
			(at -0.95 5.169 0)
			(layer "F.Fab")
			(effects
				(font
					(size 0.7 0.7)
					(thickness 0.15)
				)
				(justify left bottom)
			)
		)
		(pad "1" smd roundrect
			(at -0.48 0)
			(size 0.59 0.64)
			(layers "F.Cu" "F.Mask" "F.Paste")
			(roundrect_rratio 0.25)
			(net 362 "/Ethernet/TPH")
			(pintype "passive")
		)
		(pad "2" smd roundrect
			(at 0.48 0)
			(size 0.59 0.64)
			(layers "F.Cu" "F.Mask" "F.Paste")
			(roundrect_rratio 0.25)
			(net 33 "/Ethernet/VDD")
			(pintype "passive")
		)
	)
	(footprint "antmicro-footprints:SW_KMR211NGLFS_SMD"
		(layer "F.Cu")
		(at 130.517962 122.8665 -90)
		(property "Reference" "S202"
			(at 3.6335 1.542962 0)
			(layer "F.SilkS")
			(effects
				(font
					(size 0.7 0.7)
					(thickness 0.15)
				)
				(justify left bottom)
			)
		)
		(property "Value" "SW_KMR211NGLFS_SMD"
			(at 0 2.8 90)
			(layer "F.Fab")
			(effects
				(font
					(size 0.7 0.7)
					(thickness 0.15)
				)
				(justify right bottom)
			)
		)
		(property "Datasheet" "http://www.farnell.com/datasheets/2631211.pdf"
			(at 0 0 270)
			(layer "F.Fab")
			(hide yes)
			(effects
				(font
					(size 1.27 1.27)
					(thickness 0.15)
				)
			)
		)
		(property "MPN" "KMR211NGLFS"
			(at 0 0 270)
			(unlocked yes)
			(layer "F.Fab")
			(hide yes)
			(effects
				(font
					(size 1 1)
					(thickness 0.15)
				)
			)
		)
		(property "Manufacturer" "C&K"
			(at 0 0 270)
			(unlocked yes)
			(layer "F.Fab")
			(hide yes)
			(effects
				(font
					(size 1 1)
					(thickness 0.15)
				)
			)
		)
		(property "Author" "Antmicro"
			(at 0 0 270)
			(unlocked yes)
			(layer "F.Fab")
			(hide yes)
			(effects
				(font
					(size 1 1)
					(thickness 0.15)
				)
			)
		)
		(property "License" "Apache-2.0"
			(at 0 0 270)
			(unlocked yes)
			(layer "F.Fab")
			(hide yes)
			(effects
				(font
					(size 1 1)
					(thickness 0.15)
				)
			)
		)
		(sheetname "/Compute module/")
		(sheetfile "compute-module.kicad_sch")
		(attr smd)
		(fp_line
			(start -2.1 1.601)
			(end -2.1 1.48)
			(stroke
				(width 0.15)
				(type solid)
			)
			(layer "F.SilkS")
		)
		(fp_line
			(start 2.101 1.601)
			(end -2.1 1.601)
			(stroke
				(width 0.15)
				(type solid)
			)
			(layer "F.SilkS")
		)
		(fp_line
			(start 2.101 1.601)
			(end 2.101 1.48)
			(stroke
				(width 0.15)
				(type solid)
			)
			(layer "F.SilkS")
		)
		(fp_line
			(start 2.101 -1.58)
			(end 2.101 -1.459)
			(stroke
				(width 0.15)
				(type solid)
			)
			(layer "F.SilkS")
		)
		(fp_line
			(start -2.1 -1.6)
			(end -2.1 -1.499)
			(stroke
				(width 0.15)
				(type solid)
			)
			(layer "F.SilkS")
		)
		(fp_line
			(start 2.101 -1.6)
			(end -2.1 -1.6)
			(stroke
				(width 0.15)
				(type solid)
			)
			(layer "F.SilkS")
		)
		(fp_rect
			(start 2.751 1.75)
			(end -2.748 -1.749)
			(stroke
				(width 0.05)
				(type solid)
			)
			(fill no)
			(layer "F.CrtYd")
		)
		(fp_line
			(start -2.1 1.601)
			(end 2.101 1.601)
			(stroke
				(width 0.15)
				(type solid)
			)
			(layer "F.Fab")
		)
		(fp_line
			(start 2.101 1.601)
			(end 2.101 -1.6)
			(stroke
				(width 0.15)
				(type solid)
			)
			(layer "F.Fab")
		)
		(fp_line
			(start 0.25 0.802)
			(end -0.248 0.802)
			(stroke
				(width 0.15)
				(type solid)
			)
			(layer "F.Fab")
		)
		(fp_line
			(start -0.248 -0.8)
			(end 0.25 -0.8)
			(stroke
				(width 0.15)
				(type solid)
			)
			(layer "F.Fab")
		)
		(fp_line
			(start -2.1 -1.6)
			(end -2.1 1.601)
			(stroke
				(width 0.15)
				(type solid)
			)
			(layer "F.Fab")
		)
		(fp_line
			(start 2.101 -1.6)
			(end -2.1 -1.6)
			(stroke
				(width 0.15)
				(type solid)
			)
			(layer "F.Fab")
		)
		(fp_arc
			(start -0.248 0.802)
			(mid -1.050001 0.001)
			(end -0.248 -0.8)
			(stroke
				(width 0.15)
				(type solid)
			)
			(layer "F.Fab")
		)
		(fp_arc
			(start 0.25 -0.8)
			(mid 1.051001 0.001)
			(end 0.25 0.802)
			(stroke
				(width 0.15)
				(type solid)
			)
			(layer "F.Fab")
		)
		(fp_text user "${REFERENCE}"
			(at -3 4.25 270)
			(layer "F.Fab")
			(effects
				(font
					(size 0.7 0.7)
					(thickness 0.15)
				)
				(justify left bottom)
			)
		)
		(fp_text user "License: Apache-2.0"
			(at -3 6.75 270)
			(layer "F.Fab")
			(effects
				(font
					(size 0.7 0.7)
					(thickness 0.15)
				)
				(justify left bottom)
			)
		)
		(fp_text user "Author: Antmicro"
			(at -3 5.5 270)
			(layer "F.Fab")
			(effects
				(font
					(size 0.7 0.7)
					(thickness 0.15)
				)
				(justify left bottom)
			)
		)
		(pad "1" smd rect
			(at -2.048 -0.8 90)
			(size 0.9 1)
			(layers "F.Cu" "F.Mask" "F.Paste")
			(net 9 "+3V3")
			(pinfunction "1")
			(pintype "passive")
		)
		(pad "2" smd rect
			(at 2.05 -0.8 90)
			(size 0.9 1)
			(layers "F.Cu" "F.Mask" "F.Paste")
			(net 9 "+3V3")
			(pinfunction "2")
			(pintype "passive")
		)
		(pad "3" smd rect
			(at -2.048 0.802 90)
			(size 0.9 1)
			(layers "F.Cu" "F.Mask" "F.Paste")
			(net 4 "Net-(D204-A)")
			(pinfunction "3")
			(pintype "passive")
		)
		(pad "4" smd rect
			(at 2.05 0.802 90)
			(size 0.9 1)
			(layers "F.Cu" "F.Mask" "F.Paste")
			(net 4 "Net-(D204-A)")
			(pinfunction "4")
			(pintype "passive")
		)
	)
	(footprint "antmicro-footprints:Spacer_Drill3.7mm_H3mm_9774030151R"
		(layer "F.Cu")
		(at 113.520961 176.314 90)
		(descr "Spacer M=3 h=3mm fi=5.1mm")
		(property "Reference" "H201"
			(at 0 -3.2 90)
			(layer "F.SilkS")
			(hide yes)
			(effects
				(font
					(size 0.7 0.7)
					(thickness 0.15)
				)
				(justify left bottom)
			)
		)
		(property "Value" "Spacer_Drill3.7mm_H3mm_9774030151R"
			(at 0 4 90)
			(layer "F.Fab")
			(effects
				(font
					(size 0.7 0.7)
					(thickness 0.15)
				)
				(justify left bottom)
			)
		)
		(property "Datasheet" "https://www.we-online.com/catalog/datasheet/9774030151.pdf"
			(at 0 0 90)
			(layer "F.Fab")
			(hide yes)
			(effects
				(font
					(size 1.27 1.27)
					(thickness 0.15)
				)
			)
		)
		(property "Manufacturer" "Würth Elektronik"
			(at 0 0 90)
			(unlocked yes)
			(layer "F.Fab")
			(hide yes)
			(effects
				(font
					(size 1 1)
					(thickness 0.15)
				)
			)
		)
		(property "MPN" "9774030151R"
			(at 0 0 90)
			(unlocked yes)
			(layer "F.Fab")
			(hide yes)
			(effects
				(font
					(size 1 1)
					(thickness 0.15)
				)
			)
		)
		(property "Author" "Antmicro"
			(at 0 0 90)
			(unlocked yes)
			(layer "F.Fab")
			(hide yes)
			(effects
				(font
					(size 1 1)
					(thickness 0.15)
				)
			)
		)
		(property "License" "Apache-2.0"
			(at 0 0 90)
			(unlocked yes)
			(layer "F.Fab")
			(hide yes)
			(effects
				(font
					(size 1 1)
					(thickness 0.15)
				)
			)
		)
		(sheetname "/Compute module/")
		(sheetfile "compute-module.kicad_sch")
		(solder_paste_margin_ratio -1)
		(attr smd)
		(fp_circle
			(center 0 0)
			(end 3.05 0)
			(stroke
				(width 0.05)
				(type solid)
			)
			(fill no)
			(layer "F.CrtYd")
		)
		(fp_circle
			(center 0 0)
			(end 2.6 0)
			(stroke
				(width 0.15)
				(type solid)
			)
			(fill no)
			(layer "F.Fab")
		)
		(fp_text user "Author: Antmicro"
			(at -9.6 7.7 90)
			(layer "F.Fab")
			(effects
				(font
					(size 0.7 0.7)
					(thickness 0.15)
				)
				(justify left bottom)
			)
		)
		(fp_text user "License: Apache-2.0"
			(at -9.6 8.9 90)
			(layer "F.Fab")
			(effects
				(font
					(size 0.7 0.7)
					(thickness 0.15)
				)
				(justify left bottom)
			)
		)
		(fp_text user "${REFERENCE}"
			(at -9.6 6.5 90)
			(layer "F.Fab")
			(effects
				(font
					(size 0.7 0.7)
					(thickness 0.15)
				)
				(justify left bottom)
			)
		)
		(pad "" smd custom
			(at -1.7 -1.7 90)
			(size 0.62 0.62)
			(layers "F.Paste")
			(thermal_bridge_angle 90)
			(options
				(clearance outline)
				(anchor circle)
			)
			(primitives
				(gr_arc
					(start -0.250195 1.279127)
					(mid 0.285453 0.294389)
					(end 1.266786 -0.24747)
					(width 0.2)
				)
				(gr_arc
					(start -0.34334 1.279127)
					(mid 0.218448 0.232561)
					(end 1.259603 -0.339191)
					(width 0.2)
				)
				(gr_arc
					(start -0.436309 1.279127)
					(mid 0.152481 0.169693)
					(end 1.255279 -0.431435)
					(width 0.2)
				)
				(gr_arc
					(start -0.529126 1.279127)
					(mid 0.087542 0.105784)
					(end 1.253811 -0.524161)
					(width 0.2)
				)
				(gr_arc
					(start -0.621807 1.279127)
					(mid 0.0309 0.033527)
					(end 1.275473 -0.621136)
					(width 0.2)
				)
				(gr_arc
					(start -0.71437 1.279127)
					(mid -0.037758 -0.026651)
					(end 1.263664 -0.711602)
					(width 0.2)
				)
				(gr_arc
					(start -0.806826 1.279127)
					(mid -0.105837 -0.087395)
					(end 1.253435 -0.802342)
					(width 0.2)
				)
				(gr_arc
					(start -0.899187 1.279127)
					(mid -0.165236 -0.156885)
					(end 1.267475 -0.897258)
					(width 0.2)
				)
				(gr_arc
					(start -0.991463 1.279127)
					(mid -0.228522 -0.222449)
					(end 1.270645 -0.990112)
					(width 0.2)
				)
				(gr_arc
					(start -1.083663 1.279127)
					(mid -0.294507 -0.285313)
					(end 1.266278 -1.081674)
					(width 0.2)
				)
				(gr_line
					(start 1.279127 -0.250195)
					(end 1.279127 -1.083663)
					(width 0.2)
				)
				(gr_line
					(start -0.250195 1.279127)
					(end -1.083663 1.279127)
					(width 0.2)
				)
			)
		)
		(pad "" smd custom
			(at -1.7 1.7 180)
			(size 0.62 0.62)
			(layers "F.Paste")
			(thermal_bridge_angle 90)
			(options
				(clearance outline)
				(anchor circle)
			)
			(primitives
				(gr_arc
					(start -0.250195 1.279127)
					(mid 0.285453 0.294389)
					(end 1.266786 -0.24747)
					(width 0.2)
				)
				(gr_arc
					(start -0.34334 1.279127)
					(mid 0.218448 0.232561)
					(end 1.259603 -0.339191)
					(width 0.2)
				)
				(gr_arc
					(start -0.436309 1.279127)
					(mid 0.152481 0.169693)
					(end 1.255279 -0.431435)
					(width 0.2)
				)
				(gr_arc
					(start -0.529126 1.279127)
					(mid 0.087542 0.105784)
					(end 1.253811 -0.524161)
					(width 0.2)
				)
				(gr_arc
					(start -0.621807 1.279127)
					(mid 0.0309 0.033527)
					(end 1.275473 -0.621136)
					(width 0.2)
				)
				(gr_arc
					(start -0.71437 1.279127)
					(mid -0.037758 -0.026651)
					(end 1.263664 -0.711602)
					(width 0.2)
				)
				(gr_arc
					(start -0.806826 1.279127)
					(mid -0.105837 -0.087395)
					(end 1.253435 -0.802342)
					(width 0.2)
				)
				(gr_arc
					(start -0.899187 1.279127)
					(mid -0.165236 -0.156885)
					(end 1.267475 -0.897258)
					(width 0.2)
				)
				(gr_arc
					(start -0.991463 1.279127)
					(mid -0.228522 -0.222449)
					(end 1.270645 -0.990112)
					(width 0.2)
				)
				(gr_arc
					(start -1.083663 1.279127)
					(mid -0.294507 -0.285313)
					(end 1.266278 -1.081674)
					(width 0.2)
				)
				(gr_line
					(start 1.279127 -0.250195)
					(end 1.279127 -1.083663)
					(width 0.2)
				)
				(gr_line
					(start -0.250195 1.279127)
					(end -1.083663 1.279127)
					(width 0.2)
				)
			)
		)
		(pad "" smd custom
			(at 1.7 -1.7)
			(size 0.62 0.62)
			(layers "F.Paste")
			(thermal_bridge_angle 90)
			(options
				(clearance outline)
				(anchor circle)
			)
			(primitives
				(gr_arc
					(start -0.250195 1.279127)
					(mid 0.285453 0.294389)
					(end 1.266786 -0.24747)
					(width 0.2)
				)
				(gr_arc
					(start -0.34334 1.279127)
					(mid 0.218448 0.232561)
					(end 1.259603 -0.339191)
					(width 0.2)
				)
				(gr_arc
					(start -0.436309 1.279127)
					(mid 0.152481 0.169693)
					(end 1.255279 -0.431435)
					(width 0.2)
				)
				(gr_arc
					(start -0.529126 1.279127)
					(mid 0.087542 0.105784)
					(end 1.253811 -0.524161)
					(width 0.2)
				)
				(gr_arc
					(start -0.621807 1.279127)
					(mid 0.0309 0.033527)
					(end 1.275473 -0.621136)
					(width 0.2)
				)
				(gr_arc
					(start -0.71437 1.279127)
					(mid -0.037758 -0.026651)
					(end 1.263664 -0.711602)
					(width 0.2)
				)
				(gr_arc
					(start -0.806826 1.279127)
					(mid -0.105837 -0.087395)
					(end 1.253435 -0.802342)
					(width 0.2)
				)
				(gr_arc
					(start -0.899187 1.279127)
					(mid -0.165236 -0.156885)
					(end 1.267475 -0.897258)
					(width 0.2)
				)
				(gr_arc
					(start -0.991463 1.279127)
					(mid -0.228522 -0.222449)
					(end 1.270645 -0.990112)
					(width 0.2)
				)
				(gr_arc
					(start -1.083663 1.279127)
					(mid -0.294507 -0.285313)
					(end 1.266278 -1.081674)
					(width 0.2)
				)
				(gr_line
					(start 1.279127 -0.250195)
					(end 1.279127 -1.083663)
					(width 0.2)
				)
				(gr_line
					(start -0.250195 1.279127)
					(end -1.083663 1.279127)
					(width 0.2)
				)
			)
		)
		(pad "" smd custom
			(at 1.7 1.7 270)
			(size 0.62 0.62)
			(layers "F.Paste")
			(thermal_bridge_angle 90)
			(options
				(clearance outline)
				(anchor circle)
			)
			(primitives
				(gr_arc
					(start -0.250195 1.279127)
					(mid 0.285453 0.294389)
					(end 1.266786 -0.24747)
					(width 0.2)
				)
				(gr_arc
					(start -0.34334 1.279127)
					(mid 0.218448 0.232561)
					(end 1.259603 -0.339191)
					(width 0.2)
				)
				(gr_arc
					(start -0.436309 1.279127)
					(mid 0.152481 0.169693)
					(end 1.255279 -0.431435)
					(width 0.2)
				)
				(gr_arc
					(start -0.529126 1.279127)
					(mid 0.087542 0.105784)
					(end 1.253811 -0.524161)
					(width 0.2)
				)
				(gr_arc
					(start -0.621807 1.279127)
					(mid 0.0309 0.033527)
					(end 1.275473 -0.621136)
					(width 0.2)
				)
				(gr_arc
					(start -0.71437 1.279127)
					(mid -0.037758 -0.026651)
					(end 1.263664 -0.711602)
					(width 0.2)
				)
				(gr_arc
					(start -0.806826 1.279127)
					(mid -0.105837 -0.087395)
					(end 1.253435 -0.802342)
					(width 0.2)
				)
				(gr_arc
					(start -0.899187 1.279127)
					(mid -0.165236 -0.156885)
					(end 1.267475 -0.897258)
					(width 0.2)
				)
				(gr_arc
					(start -0.991463 1.279127)
					(mid -0.228522 -0.222449)
					(end 1.270645 -0.990112)
					(width 0.2)
				)
				(gr_arc
					(start -1.083663 1.279127)
					(mid -0.294507 -0.285313)
					(end 1.266278 -1.081674)
					(width 0.2)
				)
				(gr_line
					(start 1.279127 -0.250195)
					(end 1.279127 -1.083663)
					(width 0.2)
				)
				(gr_line
					(start -0.250195 1.279127)
					(end -1.083663 1.279127)
					(width 0.2)
				)
			)
		)
		(pad "1" thru_hole circle
			(at 0 0 90)
			(size 6 6)
			(drill 3.7)
			(layers "*.Cu" "*.Mask")
			(remove_unused_layers no)
			(net 3 "GND")
			(pintype "passive")
		)
	)
	(footprint "antmicro-footprints:R_0402_1005Metric"
		(layer "F.Cu")
		(at 102.067962 142.6415)
		(descr "Resistor SMD 0402")
		(tags "resistor SMD 0402")
		(property "Reference" "R930"
			(at 0.725 0.45 0)
			(layer "F.SilkS")
			(effects
				(font
					(size 0.7 0.7)
					(thickness 0.15)
				)
				(justify left bottom)
			)
		)
		(property "Value" "R_10k_0402"
			(at -1.011843 1.772047 0)
			(layer "F.Fab")
			(effects
				(font
					(size 0.7 0.7)
					(thickness 0.15)
				)
				(justify left bottom)
			)
		)
		(property "Datasheet" "https://www.bourns.com/docs/product-datasheets/cr.pdf"
			(at 0 0 0)
			(layer "F.Fab")
			(hide yes)
			(effects
				(font
					(size 1.27 1.27)
					(thickness 0.15)
				)
			)
		)
		(property "Manufacturer" "Bourns"
			(at 0 0 0)
			(unlocked yes)
			(layer "F.Fab")
			(hide yes)
			(effects
				(font
					(size 1 1)
					(thickness 0.15)
				)
			)
		)
		(property "MPN" "CR0402-FX-1002GLF"
			(at 0 0 0)
			(unlocked yes)
			(layer "F.Fab")
			(hide yes)
			(effects
				(font
					(size 1 1)
					(thickness 0.15)
				)
			)
		)
		(property "Val" "10k"
			(at 0 0 0)
			(unlocked yes)
			(layer "F.Fab")
			(hide yes)
			(effects
				(font
					(size 1 1)
					(thickness 0.15)
				)
			)
		)
		(property "License" "Apache-2.0"
			(at 0 0 0)
			(unlocked yes)
			(layer "F.Fab")
			(hide yes)
			(effects
				(font
					(size 1 1)
					(thickness 0.15)
				)
			)
		)
		(property "Author" "Antmicro"
			(at 0 0 0)
			(unlocked yes)
			(layer "F.Fab")
			(hide yes)
			(effects
				(font
					(size 1 1)
					(thickness 0.15)
				)
			)
		)
		(property "Tolerance" "1%"
			(at 0 0 0)
			(unlocked yes)
			(layer "F.Fab")
			(hide yes)
			(effects
				(font
					(size 1 1)
					(thickness 0.15)
				)
			)
		)
		(sheetname "/USB/")
		(sheetfile "usb.kicad_sch")
		(attr smd)
		(fp_rect
			(start -0.925 -0.47)
			(end 0.925 0.47)
			(stroke
				(width 0.05)
				(type default)
			)
			(fill no)
			(layer "F.CrtYd")
		)
		(fp_rect
			(start -0.5 -0.25)
			(end 0.5 0.25)
			(stroke
				(width 0.15)
				(type solid)
			)
			(fill no)
			(layer "F.Fab")
		)
		(fp_text user "${REFERENCE}"
			(at -0.95 3.168 0)
			(layer "F.Fab")
			(effects
				(font
					(size 0.7 0.7)
					(thickness 0.15)
				)
				(justify left bottom)
			)
		)
		(fp_text user "Author: Antmicro"
			(at -0.95 4.169 0)
			(layer "F.Fab")
			(effects
				(font
					(size 0.7 0.7)
					(thickness 0.15)
				)
				(justify left bottom)
			)
		)
		(fp_text user "License: Apache-2.0"
			(at -0.95 5.169 0)
			(layer "F.Fab")
			(effects
				(font
					(size 0.7 0.7)
					(thickness 0.15)
				)
				(justify left bottom)
			)
		)
		(pad "1" smd roundrect
			(at -0.48 0)
			(size 0.59 0.64)
			(layers "F.Cu" "F.Mask" "F.Paste")
			(roundrect_rratio 0.25)
			(net 27 "/USB/USB_3V3")
			(pintype "passive")
		)
		(pad "2" smd roundrect
			(at 0.48 0)
			(size 0.59 0.64)
			(layers "F.Cu" "F.Mask" "F.Paste")
			(roundrect_rratio 0.25)
			(net 455 "Net-(Q905-D)")
			(pintype "passive")
		)
	)
	(footprint "antmicro-footprints:C_0402_1005Metric"
		(layer "F.Cu")
		(at 65.092962 177.7005 -90)
		(descr "Capacitor SMD 0402")
		(tags "capacitor SMD 0402")
		(property "Reference" "C818"
			(at -2.704 13.955 90)
			(layer "F.SilkS")
			(effects
				(font
					(size 0.7 0.7)
					(thickness 0.15)
				)
				(justify right bottom)
			)
		)
		(property "Value" "C_470p_100V_0402"
			(at -1.022927 2.155213 90)
			(layer "F.Fab")
			(effects
				(font
					(size 0.7 0.7)
					(thickness 0.15)
				)
				(justify right bottom)
			)
		)
		(property "Datasheet" "https://search.murata.co.jp/Ceramy/image/img/A01X/G101/ENG/GRM1555C2A471JE01-01A.pdf"
			(at 0 0 270)
			(layer "F.Fab")
			(hide yes)
			(effects
				(font
					(size 1.27 1.27)
					(thickness 0.15)
				)
			)
		)
		(property "Description" "MLCC, SMD/SMT, 100V, 470pF, C0G/NP0, 0402 5%"
			(at 0 0 270)
			(layer "F.Fab")
			(hide yes)
			(effects
				(font
					(size 1.27 1.27)
					(thickness 0.15)
				)
			)
		)
		(property "MPN" "GRM1555C2A471JE01D"
			(at 0 0 270)
			(unlocked yes)
			(layer "F.Fab")
			(hide yes)
			(effects
				(font
					(size 1 1)
					(thickness 0.15)
				)
			)
		)
		(property "Manufacturer" "Murata"
			(at 0 0 270)
			(unlocked yes)
			(layer "F.Fab")
			(hide yes)
			(effects
				(font
					(size 1 1)
					(thickness 0.15)
				)
			)
		)
		(property "License" "Apache-2.0"
			(at 0 0 270)
			(unlocked yes)
			(layer "F.Fab")
			(hide yes)
			(effects
				(font
					(size 1 1)
					(thickness 0.15)
				)
			)
		)
		(property "Author" "Antmicro"
			(at 0 0 270)
			(unlocked yes)
			(layer "F.Fab")
			(hide yes)
			(effects
				(font
					(size 1 1)
					(thickness 0.15)
				)
			)
		)
		(property "Val" "470p"
			(at 0 0 270)
			(unlocked yes)
			(layer "F.Fab")
			(hide yes)
			(effects
				(font
					(size 1 1)
					(thickness 0.15)
				)
			)
		)
		(property "Voltage" "100V"
			(at 0 0 270)
			(unlocked yes)
			(layer "F.Fab")
			(hide yes)
			(effects
				(font
					(size 1 1)
					(thickness 0.15)
				)
			)
		)
		(property "Dielectric" "C0G/NP0"
			(at 0 0 270)
			(unlocked yes)
			(layer "F.Fab")
			(hide yes)
			(effects
				(font
					(size 1 1)
					(thickness 0.15)
				)
			)
		)
		(sheetname "/Peripherals/")
		(sheetfile "peripherals.kicad_sch")
		(attr smd)
		(fp_rect
			(start -0.925 -0.47)
			(end 0.925 0.47)
			(stroke
				(width 0.05)
				(type default)
			)
			(fill no)
			(layer "F.CrtYd")
		)
		(fp_line
			(start -0.494 0.248)
			(end -0.494 -0.25)
			(stroke
				(width 0.15)
				(type solid)
			)
			(layer "F.Fab")
		)
		(fp_line
			(start 0.504 0.248)
			(end -0.494 0.248)
			(stroke
				(width 0.15)
				(type solid)
			)
			(layer "F.Fab")
		)
		(fp_line
			(start -0.494 -0.25)
			(end 0.504 -0.25)
			(stroke
				(width 0.15)
				(type solid)
			)
			(layer "F.Fab")
		)
		(fp_line
			(start 0.504 -0.25)
			(end 0.504 0.248)
			(stroke
				(width 0.15)
				(type solid)
			)
			(layer "F.Fab")
		)
		(fp_text user "${REFERENCE}"
			(at -0.939 4.599 270)
			(layer "F.Fab")
			(effects
				(font
					(size 0.7 0.7)
					(thickness 0.15)
				)
				(justify left bottom)
			)
		)
		(fp_text user "License: Apache-2.0"
			(at -0.939 5.799 270)
			(layer "F.Fab")
			(effects
				(font
					(size 0.7 0.7)
					(thickness 0.15)
				)
				(justify left bottom)
			)
		)
		(fp_text user "Author: Antmicro"
			(at -0.939 3.399 270)
			(layer "F.Fab")
			(effects
				(font
					(size 0.7 0.7)
					(thickness 0.15)
				)
				(justify left bottom)
			)
		)
		(pad "1" smd roundrect
			(at -0.48 0 270)
			(size 0.59 0.64)
			(layers "F.Cu" "F.Mask" "F.Paste")
			(roundrect_rratio 0.25)
			(net 3 "GND")
			(pintype "passive")
		)
		(pad "2" smd roundrect
			(at 0.48 0 270)
			(size 0.59 0.64)
			(layers "F.Cu" "F.Mask" "F.Paste")
			(roundrect_rratio 0.25)
			(net 109 "Net-(C816-Pad2)")
			(pintype "passive")
		)
	)
	(footprint "antmicro-footprints:C_0402_1005Metric"
		(layer "F.Cu")
		(at 100.387962 123.6065)
		(descr "Capacitor SMD 0402")
		(tags "capacitor SMD 0402")
		(property "Reference" "C928"
			(at 0.87 0.67 0)
			(layer "F.SilkS")
			(effects
				(font
					(size 0.7 0.7)
					(thickness 0.15)
				)
				(justify left bottom)
			)
		)
		(property "Value" "C_100n_0402"
			(at -1.022927 2.155213 0)
			(layer "F.Fab")
			(effects
				(font
					(size 0.7 0.7)
					(thickness 0.15)
				)
				(justify left bottom)
			)
		)
		(property "Datasheet" "https://www.murata.com/products/productdetail?partno=GRM155R61H104KE14%23"
			(at 0 0 0)
			(layer "F.Fab")
			(hide yes)
			(effects
				(font
					(size 1.27 1.27)
					(thickness 0.15)
				)
			)
		)
		(property "Manufacturer" "Murata"
			(at 0 0 0)
			(unlocked yes)
			(layer "F.Fab")
			(hide yes)
			(effects
				(font
					(size 1 1)
					(thickness 0.15)
				)
			)
		)
		(property "MPN" "GRM155R61H104KE14D"
			(at 0 0 0)
			(unlocked yes)
			(layer "F.Fab")
			(hide yes)
			(effects
				(font
					(size 1 1)
					(thickness 0.15)
				)
			)
		)
		(property "Val" "100n"
			(at 0 0 0)
			(unlocked yes)
			(layer "F.Fab")
			(hide yes)
			(effects
				(font
					(size 1 1)
					(thickness 0.15)
				)
			)
		)
		(property "License" "Apache-2.0"
			(at 0 0 0)
			(unlocked yes)
			(layer "F.Fab")
			(hide yes)
			(effects
				(font
					(size 1 1)
					(thickness 0.15)
				)
			)
		)
		(property "Author" "Antmicro"
			(at 0 0 0)
			(unlocked yes)
			(layer "F.Fab")
			(hide yes)
			(effects
				(font
					(size 1 1)
					(thickness 0.15)
				)
			)
		)
		(property "Voltage" "50V"
			(at 0 0 0)
			(unlocked yes)
			(layer "F.Fab")
			(hide yes)
			(effects
				(font
					(size 1 1)
					(thickness 0.15)
				)
			)
		)
		(property "Dielectric" "X5R"
			(at 0 0 0)
			(unlocked yes)
			(layer "F.Fab")
			(hide yes)
			(effects
				(font
					(size 1 1)
					(thickness 0.15)
				)
			)
		)
		(sheetname "/USB/")
		(sheetfile "usb.kicad_sch")
		(attr smd)
		(fp_rect
			(start -0.925 -0.47)
			(end 0.925 0.47)
			(stroke
				(width 0.05)
				(type default)
			)
			(fill no)
			(layer "F.CrtYd")
		)
		(fp_line
			(start -0.494 -0.25)
			(end 0.504 -0.25)
			(stroke
				(width 0.15)
				(type solid)
			)
			(layer "F.Fab")
		)
		(fp_line
			(start -0.494 0.248)
			(end -0.494 -0.25)
			(stroke
				(width 0.15)
				(type solid)
			)
			(layer "F.Fab")
		)
		(fp_line
			(start 0.504 -0.25)
			(end 0.504 0.248)
			(stroke
				(width 0.15)
				(type solid)
			)
			(layer "F.Fab")
		)
		(fp_line
			(start 0.504 0.248)
			(end -0.494 0.248)
			(stroke
				(width 0.15)
				(type solid)
			)
			(layer "F.Fab")
		)
		(fp_text user "Author: Antmicro"
			(at -0.939 3.399 0)
			(layer "F.Fab")
			(effects
				(font
					(size 0.7 0.7)
					(thickness 0.15)
				)
				(justify left bottom)
			)
		)
		(fp_text user "License: Apache-2.0"
			(at -0.939 5.799 0)
			(layer "F.Fab")
			(effects
				(font
					(size 0.7 0.7)
					(thickness 0.15)
				)
				(justify left bottom)
			)
		)
		(fp_text user "${REFERENCE}"
			(at -0.939 4.599 0)
			(layer "F.Fab")
			(effects
				(font
					(size 0.7 0.7)
					(thickness 0.15)
				)
				(justify left bottom)
			)
		)
		(pad "1" smd roundrect
			(at -0.48 0)
			(size 0.59 0.64)
			(layers "F.Cu" "F.Mask" "F.Paste")
			(roundrect_rratio 0.25)
			(net 28 "/USB/+5V_{CAP}")
			(pintype "passive")
		)
		(pad "2" smd roundrect
			(at 0.48 0)
			(size 0.59 0.64)
			(layers "F.Cu" "F.Mask" "F.Paste")
			(roundrect_rratio 0.25)
			(net 3 "GND")
			(pintype "passive")
		)
	)
	(footprint "antmicro-footprints:R_0402_1005Metric"
		(layer "F.Cu")
		(at 83.092962 148.5415 180)
		(descr "Resistor SMD 0402")
		(tags "resistor SMD 0402")
		(property "Reference" "R205"
			(at -1.575 0.475 0)
			(layer "F.SilkS")
			(effects
				(font
					(size 0.7 0.7)
					(thickness 0.15)
				)
				(justify right bottom)
			)
		)
		(property "Value" "R_0R_0402"
			(at -1.011843 1.772047 0)
			(layer "F.Fab")
			(effects
				(font
					(size 0.7 0.7)
					(thickness 0.15)
				)
				(justify right bottom)
			)
		)
		(property "Datasheet" "https://industrial.panasonic.com/cdbs/www-data/pdf/RDA0000/AOA0000C301.pdf"
			(at 0 0 180)
			(layer "F.Fab")
			(hide yes)
			(effects
				(font
					(size 1.27 1.27)
					(thickness 0.15)
				)
			)
		)
		(property "MPN" "ERJ2GE0R00X"
			(at 0 0 180)
			(unlocked yes)
			(layer "F.Fab")
			(hide yes)
			(effects
				(font
					(size 1 1)
					(thickness 0.15)
				)
			)
		)
		(property "Manufacturer" "Panasonic"
			(at 0 0 180)
			(unlocked yes)
			(layer "F.Fab")
			(hide yes)
			(effects
				(font
					(size 1 1)
					(thickness 0.15)
				)
			)
		)
		(property "License" "Apache-2.0"
			(at 0 0 180)
			(unlocked yes)
			(layer "F.Fab")
			(hide yes)
			(effects
				(font
					(size 1 1)
					(thickness 0.15)
				)
			)
		)
		(property "Author" "Antmicro"
			(at 0 0 180)
			(unlocked yes)
			(layer "F.Fab")
			(hide yes)
			(effects
				(font
					(size 1 1)
					(thickness 0.15)
				)
			)
		)
		(property "Val" "0R"
			(at 0 0 180)
			(unlocked yes)
			(layer "F.Fab")
			(hide yes)
			(effects
				(font
					(size 1 1)
					(thickness 0.15)
				)
			)
		)
		(property "Tolerance" "~"
			(at 0 0 180)
			(unlocked yes)
			(layer "F.Fab")
			(hide yes)
			(effects
				(font
					(size 1 1)
					(thickness 0.15)
				)
			)
		)
		(property "Current" "1A"
			(at 0 0 180)
			(unlocked yes)
			(layer "F.Fab")
			(hide yes)
			(effects
				(font
					(size 1 1)
					(thickness 0.15)
				)
			)
		)
		(sheetname "/Compute module/")
		(sheetfile "compute-module.kicad_sch")
		(attr smd exclude_from_pos_files exclude_from_bom dnp)
		(fp_rect
			(start -0.925 -0.47)
			(end 0.925 0.47)
			(stroke
				(width 0.05)
				(type default)
			)
			(fill no)
			(layer "F.CrtYd")
		)
		(fp_rect
			(start -0.5 -0.25)
			(end 0.5 0.25)
			(stroke
				(width 0.15)
				(type solid)
			)
			(fill no)
			(layer "F.Fab")
		)
		(fp_text user "${REFERENCE}"
			(at -0.95 3.168 180)
			(layer "F.Fab")
			(effects
				(font
					(size 0.7 0.7)
					(thickness 0.15)
				)
				(justify left bottom)
			)
		)
		(fp_text user "Author: Antmicro"
			(at -0.95 4.169 180)
			(layer "F.Fab")
			(effects
				(font
					(size 0.7 0.7)
					(thickness 0.15)
				)
				(justify left bottom)
			)
		)
		(fp_text user "License: Apache-2.0"
			(at -0.95 5.169 180)
			(layer "F.Fab")
			(effects
				(font
					(size 0.7 0.7)
					(thickness 0.15)
				)
				(justify left bottom)
			)
		)
		(pad "1" smd roundrect
			(at -0.48 0 180)
			(size 0.59 0.64)
			(layers "F.Cu" "F.Mask" "F.Paste")
			(roundrect_rratio 0.25)
			(net 3 "GND")
			(pintype "passive")
		)
		(pad "2" smd roundrect
			(at 0.48 0 180)
			(size 0.59 0.64)
			(layers "F.Cu" "F.Mask" "F.Paste")
			(roundrect_rratio 0.25)
			(net 216 "/Compute module/~{EEPROM_WP}")
			(pintype "passive")
		)
	)
	(footprint "antmicro-footprints:TP_SMD_0.75mm"
		(layer "F.Cu")
		(at 120 118.3 180)
		(property "Reference" "TP501"
			(at -0.955 -1.455 0)
			(layer "F.SilkS")
			(effects
				(font
					(size 0.7 0.7)
					(thickness 0.15)
				)
				(justify right bottom)
			)
		)
		(property "Value" "TP_0.75mm_SMD"
			(at 0 1.2 0)
			(layer "F.Fab")
			(effects
				(font
					(size 0.7 0.7)
					(thickness 0.15)
				)
				(justify right bottom)
			)
		)
		(property "MPN" ""
			(at 0 0 180)
			(unlocked yes)
			(layer "F.Fab")
			(hide yes)
			(effects
				(font
					(size 1 1)
					(thickness 0.15)
				)
			)
		)
		(property "Manufacturer" ""
			(at 0 0 180)
			(unlocked yes)
			(layer "F.Fab")
			(hide yes)
			(effects
				(font
					(size 1 1)
					(thickness 0.15)
				)
			)
		)
		(property "Author" "Antmicro"
			(at 0 0 180)
			(unlocked yes)
			(layer "F.Fab")
			(hide yes)
			(effects
				(font
					(size 1 1)
					(thickness 0.15)
				)
			)
		)
		(property "License" "Apache-2.0"
			(at 0 0 180)
			(unlocked yes)
			(layer "F.Fab")
			(hide yes)
			(effects
				(font
					(size 1 1)
					(thickness 0.15)
				)
			)
		)
		(sheetname "/NVMe & microSD/")
		(sheetfile "nvme-micro-sd.kicad_sch")
		(attr exclude_from_pos_files exclude_from_bom)
		(fp_circle
			(center 0 0)
			(end 0.475 0)
			(stroke
				(width 0.05)
				(type default)
			)
			(fill no)
			(layer "F.CrtYd")
		)
		(fp_text user "License: Apache-2.0"
			(at -0.4 5.101 180)
			(layer "F.Fab")
			(effects
				(font
					(size 0.7 0.7)
					(thickness 0.15)
				)
				(justify left bottom)
			)
		)
		(fp_text user "${REFERENCE}"
			(at -0.4 2.7 180)
			(layer "F.Fab")
			(effects
				(font
					(size 0.7 0.7)
					(thickness 0.15)
				)
				(justify left bottom)
			)
		)
		(fp_text user "Author: Antmicro"
			(at -0.4 3.901 180)
			(layer "F.Fab")
			(effects
				(font
					(size 0.7 0.7)
					(thickness 0.15)
				)
				(justify left bottom)
			)
		)
		(pad "1" smd circle
			(at 0 0 180)
			(size 0.75 0.75)
			(layers "F.Cu" "F.Mask")
			(net 178 "Net-(J501-SUSCLK)")
			(pinfunction "1")
			(pintype "passive")
		)
	)
	(footprint "antmicro-footprints:C_0402_1005Metric"
		(layer "F.Cu")
		(at 66.917962 169.4165 180)
		(descr "Capacitor SMD 0402")
		(tags "capacitor SMD 0402")
		(property "Reference" "C804"
			(at 6.762037 -3.158819 0)
			(layer "F.SilkS")
			(effects
				(font
					(size 0.7 0.7)
					(thickness 0.15)
				)
				(justify right bottom)
			)
		)
		(property "Value" "C_100n_0402"
			(at -1.022927 2.155213 0)
			(layer "F.Fab")
			(effects
				(font
					(size 0.7 0.7)
					(thickness 0.15)
				)
				(justify right bottom)
			)
		)
		(property "Datasheet" "https://www.murata.com/products/productdetail?partno=GRM155R61H104KE14%23"
			(at 0 0 180)
			(layer "F.Fab")
			(hide yes)
			(effects
				(font
					(size 1.27 1.27)
					(thickness 0.15)
				)
			)
		)
		(property "MPN" "GRM155R61H104KE14D"
			(at 0 0 180)
			(unlocked yes)
			(layer "F.Fab")
			(hide yes)
			(effects
				(font
					(size 1 1)
					(thickness 0.15)
				)
			)
		)
		(property "Manufacturer" "Murata"
			(at 0 0 180)
			(unlocked yes)
			(layer "F.Fab")
			(hide yes)
			(effects
				(font
					(size 1 1)
					(thickness 0.15)
				)
			)
		)
		(property "License" "Apache-2.0"
			(at 0 0 180)
			(unlocked yes)
			(layer "F.Fab")
			(hide yes)
			(effects
				(font
					(size 1 1)
					(thickness 0.15)
				)
			)
		)
		(property "Author" "Antmicro"
			(at 0 0 180)
			(unlocked yes)
			(layer "F.Fab")
			(hide yes)
			(effects
				(font
					(size 1 1)
					(thickness 0.15)
				)
			)
		)
		(property "Val" "100n"
			(at 0 0 180)
			(unlocked yes)
			(layer "F.Fab")
			(hide yes)
			(effects
				(font
					(size 1 1)
					(thickness 0.15)
				)
			)
		)
		(property "Voltage" "50V"
			(at 0 0 180)
			(unlocked yes)
			(layer "F.Fab")
			(hide yes)
			(effects
				(font
					(size 1 1)
					(thickness 0.15)
				)
			)
		)
		(property "Dielectric" "X5R"
			(at 0 0 180)
			(unlocked yes)
			(layer "F.Fab")
			(hide yes)
			(effects
				(font
					(size 1 1)
					(thickness 0.15)
				)
			)
		)
		(sheetname "/Peripherals/")
		(sheetfile "peripherals.kicad_sch")
		(attr smd)
		(fp_rect
			(start -0.925 -0.47)
			(end 0.925 0.47)
			(stroke
				(width 0.05)
				(type default)
			)
			(fill no)
			(layer "F.CrtYd")
		)
		(fp_line
			(start 0.504 0.248)
			(end -0.494 0.248)
			(stroke
				(width 0.15)
				(type solid)
			)
			(layer "F.Fab")
		)
		(fp_line
			(start 0.504 -0.25)
			(end 0.504 0.248)
			(stroke
				(width 0.15)
				(type solid)
			)
			(layer "F.Fab")
		)
		(fp_line
			(start -0.494 0.248)
			(end -0.494 -0.25)
			(stroke
				(width 0.15)
				(type solid)
			)
			(layer "F.Fab")
		)
		(fp_line
			(start -0.494 -0.25)
			(end 0.504 -0.25)
			(stroke
				(width 0.15)
				(type solid)
			)
			(layer "F.Fab")
		)
		(fp_text user "License: Apache-2.0"
			(at -0.939 5.799 180)
			(layer "F.Fab")
			(effects
				(font
					(size 0.7 0.7)
					(thickness 0.15)
				)
				(justify left bottom)
			)
		)
		(fp_text user "${REFERENCE}"
			(at -0.939 4.599 180)
			(layer "F.Fab")
			(effects
				(font
					(size 0.7 0.7)
					(thickness 0.15)
				)
				(justify left bottom)
			)
		)
		(fp_text user "Author: Antmicro"
			(at -0.939 3.399 180)
			(layer "F.Fab")
			(effects
				(font
					(size 0.7 0.7)
					(thickness 0.15)
				)
				(justify left bottom)
			)
		)
		(pad "1" smd roundrect
			(at -0.48 0 180)
			(size 0.59 0.64)
			(layers "F.Cu" "F.Mask" "F.Paste")
			(roundrect_rratio 0.25)
			(net 501 "Net-(U801-V_{DD(UP)})")
			(pintype "passive")
		)
		(pad "2" smd roundrect
			(at 0.48 0 180)
			(size 0.59 0.64)
			(layers "F.Cu" "F.Mask" "F.Paste")
			(roundrect_rratio 0.25)
			(net 3 "GND")
			(pintype "passive")
		)
	)
	(footprint "antmicro-footprints:C_0402_1005Metric"
		(layer "F.Cu")
		(at 66.917962 170.4165)
		(descr "Capacitor SMD 0402")
		(tags "capacitor SMD 0402")
		(property "Reference" "C803"
			(at -9.611139 3.137927 0)
			(layer "F.SilkS")
			(effects
				(font
					(size 0.7 0.7)
					(thickness 0.15)
				)
				(justify left bottom)
			)
		)
		(property "Value" "C_4u7_0402"
			(at -1.022927 2.155213 0)
			(layer "F.Fab")
			(effects
				(font
					(size 0.7 0.7)
					(thickness 0.15)
				)
				(justify left bottom)
			)
		)
		(property "Datasheet" "https://www.murata.com/products/productdetail?partno=GRM155R61A475MEAA%23"
			(at 0 0 0)
			(layer "F.Fab")
			(hide yes)
			(effects
				(font
					(size 1.27 1.27)
					(thickness 0.15)
				)
			)
		)
		(property "MPN" "GRM155R61A475MEAAD"
			(at 0 0 0)
			(unlocked yes)
			(layer "F.Fab")
			(hide yes)
			(effects
				(font
					(size 1 1)
					(thickness 0.15)
				)
			)
		)
		(property "Manufacturer" "Murata"
			(at 0 0 0)
			(unlocked yes)
			(layer "F.Fab")
			(hide yes)
			(effects
				(font
					(size 1 1)
					(thickness 0.15)
				)
			)
		)
		(property "License" "Apache-2.0"
			(at 0 0 0)
			(unlocked yes)
			(layer "F.Fab")
			(hide yes)
			(effects
				(font
					(size 1 1)
					(thickness 0.15)
				)
			)
		)
		(property "Author" "Antmicro"
			(at 0 0 0)
			(unlocked yes)
			(layer "F.Fab")
			(hide yes)
			(effects
				(font
					(size 1 1)
					(thickness 0.15)
				)
			)
		)
		(property "Val" "4u7"
			(at 0 0 0)
			(unlocked yes)
			(layer "F.Fab")
			(hide yes)
			(effects
				(font
					(size 1 1)
					(thickness 0.15)
				)
			)
		)
		(property "Voltage" ""
			(at 0 0 0)
			(unlocked yes)
			(layer "F.Fab")
			(hide yes)
			(effects
				(font
					(size 1 1)
					(thickness 0.15)
				)
			)
		)
		(property "Dielectric" ""
			(at 0 0 0)
			(unlocked yes)
			(layer "F.Fab")
			(hide yes)
			(effects
				(font
					(size 1 1)
					(thickness 0.15)
				)
			)
		)
		(sheetname "/Peripherals/")
		(sheetfile "peripherals.kicad_sch")
		(attr smd)
		(fp_rect
			(start -0.925 -0.47)
			(end 0.925 0.47)
			(stroke
				(width 0.05)
				(type default)
			)
			(fill no)
			(layer "F.CrtYd")
		)
		(fp_line
			(start -0.494 -0.25)
			(end 0.504 -0.25)
			(stroke
				(width 0.15)
				(type solid)
			)
			(layer "F.Fab")
		)
		(fp_line
			(start -0.494 0.248)
			(end -0.494 -0.25)
			(stroke
				(width 0.15)
				(type solid)
			)
			(layer "F.Fab")
		)
		(fp_line
			(start 0.504 -0.25)
			(end 0.504 0.248)
			(stroke
				(width 0.15)
				(type solid)
			)
			(layer "F.Fab")
		)
		(fp_line
			(start 0.504 0.248)
			(end -0.494 0.248)
			(stroke
				(width 0.15)
				(type solid)
			)
			(layer "F.Fab")
		)
		(fp_text user "License: Apache-2.0"
			(at -0.939 5.799 0)
			(layer "F.Fab")
			(effects
				(font
					(size 0.7 0.7)
					(thickness 0.15)
				)
				(justify left bottom)
			)
		)
		(fp_text user "Author: Antmicro"
			(at -0.939 3.399 0)
			(layer "F.Fab")
			(effects
				(font
					(size 0.7 0.7)
					(thickness 0.15)
				)
				(justify left bottom)
			)
		)
		(fp_text user "${REFERENCE}"
			(at -0.939 4.599 0)
			(layer "F.Fab")
			(effects
				(font
					(size 0.7 0.7)
					(thickness 0.15)
				)
				(justify left bottom)
			)
		)
		(pad "1" smd roundrect
			(at -0.48 0)
			(size 0.59 0.64)
			(layers "F.Cu" "F.Mask" "F.Paste")
			(roundrect_rratio 0.25)
			(net 3 "GND")
			(pintype "passive")
		)
		(pad "2" smd roundrect
			(at 0.48 0)
			(size 0.59 0.64)
			(layers "F.Cu" "F.Mask" "F.Paste")
			(roundrect_rratio 0.25)
			(net 501 "Net-(U801-V_{DD(UP)})")
			(pintype "passive")
		)
	)
	(footprint "antmicro-footprints:C_0402_1005Metric"
		(layer "F.Cu")
		(at 139.517962 159.4915 90)
		(descr "Capacitor SMD 0402")
		(tags "capacitor SMD 0402")
		(property "Reference" "C601"
			(at -1.3585 1.232038 90)
			(layer "F.SilkS")
			(effects
				(font
					(size 0.7 0.7)
					(thickness 0.15)
				)
				(justify left bottom)
			)
		)
		(property "Value" "C_100n_0402"
			(at -1.022927 2.155213 90)
			(layer "F.Fab")
			(effects
				(font
					(size 0.7 0.7)
					(thickness 0.15)
				)
				(justify left bottom)
			)
		)
		(property "Datasheet" "https://www.murata.com/products/productdetail?partno=GRM155R61H104KE14%23"
			(at 0 0 90)
			(layer "F.Fab")
			(hide yes)
			(effects
				(font
					(size 1.27 1.27)
					(thickness 0.15)
				)
			)
		)
		(property "Manufacturer" "Murata"
			(at 0 0 90)
			(unlocked yes)
			(layer "F.Fab")
			(hide yes)
			(effects
				(font
					(size 1 1)
					(thickness 0.15)
				)
			)
		)
		(property "MPN" "GRM155R61H104KE14D"
			(at 0 0 90)
			(unlocked yes)
			(layer "F.Fab")
			(hide yes)
			(effects
				(font
					(size 1 1)
					(thickness 0.15)
				)
			)
		)
		(property "Val" "100n"
			(at 0 0 90)
			(unlocked yes)
			(layer "F.Fab")
			(hide yes)
			(effects
				(font
					(size 1 1)
					(thickness 0.15)
				)
			)
		)
		(property "License" "Apache-2.0"
			(at 0 0 90)
			(unlocked yes)
			(layer "F.Fab")
			(hide yes)
			(effects
				(font
					(size 1 1)
					(thickness 0.15)
				)
			)
		)
		(property "Author" "Antmicro"
			(at 0 0 90)
			(unlocked yes)
			(layer "F.Fab")
			(hide yes)
			(effects
				(font
					(size 1 1)
					(thickness 0.15)
				)
			)
		)
		(property "Voltage" "50V"
			(at 0 0 90)
			(unlocked yes)
			(layer "F.Fab")
			(hide yes)
			(effects
				(font
					(size 1 1)
					(thickness 0.15)
				)
			)
		)
		(property "Dielectric" "X5R"
			(at 0 0 90)
			(unlocked yes)
			(layer "F.Fab")
			(hide yes)
			(effects
				(font
					(size 1 1)
					(thickness 0.15)
				)
			)
		)
		(sheetname "/CSI/")
		(sheetfile "csi.kicad_sch")
		(attr smd)
		(fp_rect
			(start -0.925 -0.47)
			(end 0.925 0.47)
			(stroke
				(width 0.05)
				(type default)
			)
			(fill no)
			(layer "F.CrtYd")
		)
		(fp_line
			(start 0.504 -0.25)
			(end 0.504 0.248)
			(stroke
				(width 0.15)
				(type solid)
			)
			(layer "F.Fab")
		)
		(fp_line
			(start -0.494 -0.25)
			(end 0.504 -0.25)
			(stroke
				(width 0.15)
				(type solid)
			)
			(layer "F.Fab")
		)
		(fp_line
			(start 0.504 0.248)
			(end -0.494 0.248)
			(stroke
				(width 0.15)
				(type solid)
			)
			(layer "F.Fab")
		)
		(fp_line
			(start -0.494 0.248)
			(end -0.494 -0.25)
			(stroke
				(width 0.15)
				(type solid)
			)
			(layer "F.Fab")
		)
		(fp_text user "Author: Antmicro"
			(at -0.939 3.399 90)
			(layer "F.Fab")
			(effects
				(font
					(size 0.7 0.7)
					(thickness 0.15)
				)
				(justify left bottom)
			)
		)
		(fp_text user "${REFERENCE}"
			(at -0.939 4.599 90)
			(layer "F.Fab")
			(effects
				(font
					(size 0.7 0.7)
					(thickness 0.15)
				)
				(justify left bottom)
			)
		)
		(fp_text user "License: Apache-2.0"
			(at -0.939 5.799 90)
			(layer "F.Fab")
			(effects
				(font
					(size 0.7 0.7)
					(thickness 0.15)
				)
				(justify left bottom)
			)
		)
		(pad "1" smd roundrect
			(at -0.48 0 90)
			(size 0.59 0.64)
			(layers "F.Cu" "F.Mask" "F.Paste")
			(roundrect_rratio 0.25)
			(net 10 "+5V")
			(pintype "passive")
		)
		(pad "2" smd roundrect
			(at 0.48 0 90)
			(size 0.59 0.64)
			(layers "F.Cu" "F.Mask" "F.Paste")
			(roundrect_rratio 0.25)
			(net 3 "GND")
			(pintype "passive")
		)
	)
	(footprint "antmicro-footprints:SOD-123FL"
		(layer "F.Cu")
		(at 75.767962 121.2165 180)
		(property "Reference" "D904"
			(at 2.107962 1.6565 90)
			(layer "F.SilkS")
			(effects
				(font
					(size 0.7 0.7)
					(thickness 0.15)
				)
				(justify right bottom)
			)
		)
		(property "Value" "SMF4L15A"
			(at 0 1.967 0)
			(layer "F.Fab")
			(effects
				(font
					(size 0.7 0.7)
					(thickness 0.15)
				)
				(justify right bottom)
			)
		)
		(property "Datasheet" "https://www.littelfuse.com/media?resourcetype=datasheets&itemid=d2ba8fab-1de3-4176-8530-f36ecb0b8799&filename=smf4l"
			(at 0 0 180)
			(layer "F.Fab")
			(hide yes)
			(effects
				(font
					(size 1.27 1.27)
					(thickness 0.15)
				)
			)
		)
		(property "MPN" "SMF4L15A"
			(at 0 0 180)
			(unlocked yes)
			(layer "F.Fab")
			(hide yes)
			(effects
				(font
					(size 1 1)
					(thickness 0.15)
				)
			)
		)
		(property "Manufacturer" "Littelfuse"
			(at 0 0 180)
			(unlocked yes)
			(layer "F.Fab")
			(hide yes)
			(effects
				(font
					(size 1 1)
					(thickness 0.15)
				)
			)
		)
		(property "Author" "Antmicro"
			(at 0 0 180)
			(unlocked yes)
			(layer "F.Fab")
			(hide yes)
			(effects
				(font
					(size 1 1)
					(thickness 0.15)
				)
			)
		)
		(property "License" "Apache-2.0"
			(at 0 0 180)
			(unlocked yes)
			(layer "F.Fab")
			(hide yes)
			(effects
				(font
					(size 1 1)
					(thickness 0.15)
				)
			)
		)
		(sheetname "/USB/")
		(sheetfile "usb.kicad_sch")
		(attr smd)
		(fp_line
			(start 0 -1.1)
			(end -2.3 -1.1)
			(stroke
				(width 0.15)
				(type solid)
			)
			(layer "F.SilkS")
		)
		(fp_line
			(start -2.3 1.1)
			(end 0 1.1)
			(stroke
				(width 0.15)
				(type solid)
			)
			(layer "F.SilkS")
		)
		(fp_line
			(start -2.3 -1.1)
			(end -2.3 1.1)
			(stroke
				(width 0.15)
				(type solid)
			)
			(layer "F.SilkS")
		)
		(fp_rect
			(start -2.35 -1.125)
			(end 2.35 1.125)
			(stroke
				(width 0.05)
				(type solid)
			)
			(fill no)
			(layer "F.CrtYd")
		)
		(fp_rect
			(start -0.775 -0.875)
			(end -0.525 0.875)
			(stroke
				(width 0.15)
				(type solid)
			)
			(fill yes)
			(layer "F.Fab")
		)
		(fp_rect
			(start -1.825 -0.875)
			(end 1.824 0.873)
			(stroke
				(width 0.15)
				(type solid)
			)
			(fill no)
			(layer "F.Fab")
		)
		(fp_text user "${REFERENCE}"
			(at -2.406 3.967 180)
			(layer "F.Fab")
			(effects
				(font
					(size 0.7 0.7)
					(thickness 0.15)
				)
				(justify left bottom)
			)
		)
		(fp_text user "Author: Antmicro"
			(at -2.406 5.168 180)
			(layer "F.Fab")
			(effects
				(font
					(size 0.7 0.7)
					(thickness 0.15)
				)
				(justify left bottom)
			)
		)
		(fp_text user "License: Apache-2.0"
			(at -2.406 6.368 180)
			(layer "F.Fab")
			(effects
				(font
					(size 0.7 0.7)
					(thickness 0.15)
				)
				(justify left bottom)
			)
		)
		(pad "1" smd roundrect
			(at -1.43 0 180)
			(size 1.34 1.8)
			(layers "F.Cu" "F.Mask" "F.Paste")
			(roundrect_rratio 0.14)
			(net 26 "/USB/USBD_VBUS")
			(pinfunction "C")
			(pintype "passive")
		)
		(pad "2" smd roundrect
			(at 1.429 0 180)
			(size 1.34 1.8)
			(layers "F.Cu" "F.Mask" "F.Paste")
			(roundrect_rratio 0.14)
			(net 3 "GND")
			(pinfunction "A")
			(pintype "passive")
		)
	)
	(footprint "antmicro-footprints:SOT-23-3"
		(layer "F.Cu")
		(at 101.667962 129.7165 90)
		(property "Reference" "Q903"
			(at -1.83 -1.62 90)
			(layer "F.SilkS")
			(effects
				(font
					(size 0.7 0.7)
					(thickness 0.15)
				)
				(justify left bottom)
			)
		)
		(property "Value" "SSM3J332R"
			(at -1.9 2.7 90)
			(layer "F.Fab")
			(effects
				(font
					(size 0.7 0.7)
					(thickness 0.15)
				)
				(justify left bottom)
			)
		)
		(property "Datasheet" "https://www.mouser.com/datasheet/2/408/SSM3J332R_datasheet_en_20181015-1150575.pdf"
			(at 0 0 90)
			(layer "F.Fab")
			(hide yes)
			(effects
				(font
					(size 1.27 1.27)
					(thickness 0.15)
				)
			)
		)
		(property "MPN" "SSM3J332R,LF"
			(at 0 0 90)
			(unlocked yes)
			(layer "F.Fab")
			(hide yes)
			(effects
				(font
					(size 1 1)
					(thickness 0.15)
				)
			)
		)
		(property "Manufacturer" "Toshiba"
			(at 0 0 90)
			(unlocked yes)
			(layer "F.Fab")
			(hide yes)
			(effects
				(font
					(size 1 1)
					(thickness 0.15)
				)
			)
		)
		(property "Author" "Antmicro"
			(at 0 0 90)
			(unlocked yes)
			(layer "F.Fab")
			(hide yes)
			(effects
				(font
					(size 1 1)
					(thickness 0.15)
				)
			)
		)
		(property "License" "Apache-2.0"
			(at 0 0 90)
			(unlocked yes)
			(layer "F.Fab")
			(hide yes)
			(effects
				(font
					(size 1 1)
					(thickness 0.15)
				)
			)
		)
		(sheetname "/USB/")
		(sheetfile "usb.kicad_sch")
		(attr smd)
		(fp_line
			(start 0.7 -1.5)
			(end -0.7 -1.5)
			(stroke
				(width 0.15)
				(type solid)
			)
			(layer "F.SilkS")
		)
		(fp_line
			(start -0.85 -1.35)
			(end -0.7 -1.5)
			(stroke
				(width 0.15)
				(type solid)
			)
			(layer "F.SilkS")
		)
		(fp_line
			(start -1.45 -1.35)
			(end -0.85 -1.35)
			(stroke
				(width 0.15)
				(type solid)
			)
			(layer "F.SilkS")
		)
		(fp_line
			(start 0.7 -0.4)
			(end 0.7 -1.5)
			(stroke
				(width 0.15)
				(type solid)
			)
			(layer "F.SilkS")
		)
		(fp_line
			(start 0.7 0.4)
			(end 0.7 1.5)
			(stroke
				(width 0.15)
				(type solid)
			)
			(layer "F.SilkS")
		)
		(fp_line
			(start 0.7 1.5)
			(end -0.7 1.5)
			(stroke
				(width 0.15)
				(type solid)
			)
			(layer "F.SilkS")
		)
		(fp_line
			(start -0.7 1.5)
			(end -0.7 1.35)
			(stroke
				(width 0.15)
				(type solid)
			)
			(layer "F.SilkS")
		)
		(fp_line
			(start 0.825 -1.6)
			(end 0.825 -0.45)
			(stroke
				(width 0.05)
				(type solid)
			)
			(layer "F.CrtYd")
		)
		(fp_line
			(start -0.9 -1.6)
			(end 0.825 -1.6)
			(stroke
				(width 0.05)
				(type solid)
			)
			(layer "F.CrtYd")
		)
		(fp_line
			(start -0.9 -1.6)
			(end -0.9 -1.4)
			(stroke
				(width 0.05)
				(type solid)
			)
			(layer "F.CrtYd")
		)
		(fp_line
			(start -0.9 -1.4)
			(end -1.75 -1.4)
			(stroke
				(width 0.05)
				(type solid)
			)
			(layer "F.CrtYd")
		)
		(fp_line
			(start -0.85 -0.5)
			(end -1.75 -0.5)
			(stroke
				(width 0.05)
				(type solid)
			)
			(layer "F.CrtYd")
		)
		(fp_line
			(start -1.75 -0.5)
			(end -1.75 -1.4)
			(stroke
				(width 0.05)
				(type solid)
			)
			(layer "F.CrtYd")
		)
		(fp_line
			(start 1.75 -0.45)
			(end 1.75 0.45)
			(stroke
				(width 0.05)
				(type solid)
			)
			(layer "F.CrtYd")
		)
		(fp_line
			(start 0.825 -0.45)
			(end 1.75 -0.45)
			(stroke
				(width 0.05)
				(type solid)
			)
			(layer "F.CrtYd")
		)
		(fp_line
			(start 1.75 0.45)
			(end 0.85 0.45)
			(stroke
				(width 0.05)
				(type solid)
			)
			(layer "F.CrtYd")
		)
		(fp_line
			(start 0.85 0.45)
			(end 0.85 1.65)
			(stroke
				(width 0.05)
				(type solid)
			)
			(layer "F.CrtYd")
		)
		(fp_line
			(start -0.85 0.5)
			(end -0.85 -0.5)
			(stroke
				(width 0.05)
				(type solid)
			)
			(layer "F.CrtYd")
		)
		(fp_line
			(start -1.75 0.5)
			(end -0.85 0.5)
			(stroke
				(width 0.05)
				(type solid)
			)
			(layer "F.CrtYd")
		)
		(fp_line
			(start -0.85 1.4)
			(end -1.75 1.4)
			(stroke
				(width 0.05)
				(type solid)
			)
			(layer "F.CrtYd")
		)
		(fp_line
			(start -1.75 1.4)
			(end -1.75 0.5)
			(stroke
				(width 0.05)
				(type solid)
			)
			(layer "F.CrtYd")
		)
		(fp_line
			(start 0.85 1.65)
			(end -0.85 1.65)
			(stroke
				(width 0.05)
				(type solid)
			)
			(layer "F.CrtYd")
		)
		(fp_line
			(start -0.85 1.65)
			(end -0.85 1.4)
			(stroke
				(width 0.05)
				(type solid)
			)
			(layer "F.CrtYd")
		)
		(fp_line
			(start -0.437 -1.526)
			(end 0.688 -1.526)
			(stroke
				(width 0.15)
				(type solid)
			)
			(layer "F.Fab")
		)
		(fp_line
			(start -0.437 -1.526)
			(end -0.712 -1.325)
			(stroke
				(width 0.15)
				(type solid)
			)
			(layer "F.Fab")
		)
		(fp_line
			(start -0.712 -1.325)
			(end -0.712 1.523)
			(stroke
				(width 0.15)
				(type solid)
			)
			(layer "F.Fab")
		)
		(fp_line
			(start 0.688 1.519)
			(end 0.688 -1.52)
			(stroke
				(width 0.15)
				(type solid)
			)
			(layer "F.Fab")
		)
		(fp_line
			(start -0.712 1.519)
			(end 0.688 1.519)
			(stroke
				(width 0.15)
				(type solid)
			)
			(layer "F.Fab")
		)
		(fp_text user "License: Apache-2.0"
			(at -1.8 6.8 90)
			(layer "F.Fab")
			(effects
				(font
					(size 0.7 0.7)
					(thickness 0.15)
				)
				(justify left bottom)
			)
		)
		(fp_text user "${REFERENCE}"
			(at -1.837 4 90)
			(layer "F.Fab")
			(effects
				(font
					(size 0.7 0.7)
					(thickness 0.15)
				)
				(justify left bottom)
			)
		)
		(fp_text user "Author: Antmicro"
			(at -1.837 5.3 90)
			(layer "F.Fab")
			(effects
				(font
					(size 0.7 0.7)
					(thickness 0.15)
				)
				(justify left bottom)
			)
		)
		(pad "1" smd roundrect
			(at -1.1 -0.951 90)
			(size 1 0.6)
			(layers "F.Cu" "F.Mask" "F.Paste")
			(roundrect_rratio 0.15)
			(net 127 "Net-(Q903-G)")
			(pinfunction "G")
			(pintype "input")
		)
		(pad "2" smd roundrect
			(at -1.1 0.949 90)
			(size 1 0.6)
			(layers "F.Cu" "F.Mask" "F.Paste")
			(roundrect_rratio 0.15)
			(net 10 "+5V")
			(pinfunction "S")
			(pintype "passive")
		)
		(pad "3" smd roundrect
			(at 1.1 -0.0005 90)
			(size 1 0.6)
			(layers "F.Cu" "F.Mask" "F.Paste")
			(roundrect_rratio 0.15)
			(net 28 "/USB/+5V_{CAP}")
			(pinfunction "D")
			(pintype "passive")
		)
	)
	(footprint "antmicro-footprints:LED_0603_1608Metric_G"
		(layer "F.Cu")
		(at 73.712962 156.1215 180)
		(descr "LED SMD 0603 Green")
		(tags "LED SMD 0603 Green")
		(property "Reference" "D302"
			(at 6.095 0.005 0)
			(layer "F.SilkS")
			(effects
				(font
					(size 0.7 0.7)
					(thickness 0.15)
				)
				(justify right bottom)
			)
		)
		(property "Value" "LED_G_0603_KP-1608CGCK"
			(at -0.001 1.599 0)
			(layer "F.Fab")
			(effects
				(font
					(size 0.7 0.7)
					(thickness 0.15)
				)
				(justify right bottom)
			)
		)
		(property "Datasheet" "http://www.kingbright.com/attachments/file/psearch//000/00/00/KP-1608CGCK(Ver.23B).pdf"
			(at 0 0 180)
			(layer "F.Fab")
			(hide yes)
			(effects
				(font
					(size 1.27 1.27)
					(thickness 0.15)
				)
			)
		)
		(property "MPN" "KP-1608CGCK"
			(at 0 0 180)
			(unlocked yes)
			(layer "F.Fab")
			(hide yes)
			(effects
				(font
					(size 1 1)
					(thickness 0.15)
				)
			)
		)
		(property "Manufacturer" "Kingbright"
			(at 0 0 180)
			(unlocked yes)
			(layer "F.Fab")
			(hide yes)
			(effects
				(font
					(size 1 1)
					(thickness 0.15)
				)
			)
		)
		(property "Color" "Green"
			(at 0 0 180)
			(unlocked yes)
			(layer "F.Fab")
			(hide yes)
			(effects
				(font
					(size 1 1)
					(thickness 0.15)
				)
			)
		)
		(property "Author" "Antmicro"
			(at 0 0 180)
			(unlocked yes)
			(layer "F.Fab")
			(hide yes)
			(effects
				(font
					(size 1 1)
					(thickness 0.15)
				)
			)
		)
		(property "License" "Apache-2.0"
			(at 0 0 180)
			(unlocked yes)
			(layer "F.Fab")
			(hide yes)
			(effects
				(font
					(size 1 1)
					(thickness 0.15)
				)
			)
		)
		(sheetname "/Supply/")
		(sheetfile "supply.kicad_sch")
		(attr smd)
		(fp_line
			(start 0.22 0.35)
			(end -0.22 0.35)
			(stroke
				(width 0.15)
				(type solid)
			)
			(layer "F.SilkS")
		)
		(fp_line
			(start 0.22 -0.35)
			(end -0.22 -0.35)
			(stroke
				(width 0.15)
				(type solid)
			)
			(layer "F.SilkS")
		)
		(fp_line
			(start 0.105328 0.201008)
			(end 0.105328 -0.198992)
			(stroke
				(width 0.1)
				(type solid)
			)
			(layer "F.SilkS")
		)
		(fp_line
			(start 0.105328 0.201008)
			(end -0.094672 0.001008)
			(stroke
				(width 0.1)
				(type solid)
			)
			(layer "F.SilkS")
		)
		(fp_line
			(start 0.105328 0.001008)
			(end 0.24 0.001)
			(stroke
				(width 0.1)
				(type solid)
			)
			(layer "F.SilkS")
		)
		(fp_line
			(start -0.094672 0.201008)
			(end -0.094672 -0.198992)
			(stroke
				(width 0.1)
				(type solid)
			)
			(layer "F.SilkS")
		)
		(fp_line
			(start -0.094672 0.001008)
			(end 0.105328 -0.198992)
			(stroke
				(width 0.1)
				(type solid)
			)
			(layer "F.SilkS")
		)
		(fp_line
			(start -0.094672 0.001008)
			(end -0.24 0.001008)
			(stroke
				(width 0.1)
				(type solid)
			)
			(layer "F.SilkS")
		)
		(fp_line
			(start -1.18 -0.319)
			(end -1.18 0.321)
			(stroke
				(width 0.15)
				(type solid)
			)
			(layer "F.SilkS")
		)
		(fp_rect
			(start 1.25 0.65)
			(end -1.25 -0.65)
			(stroke
				(width 0.05)
				(type solid)
			)
			(fill no)
			(layer "F.CrtYd")
		)
		(fp_line
			(start 0.599 0)
			(end 0.201 0)
			(stroke
				(width 0.15)
				(type solid)
			)
			(layer "F.Fab")
		)
		(fp_line
			(start 0.201 0.2)
			(end 0.201 0)
			(stroke
				(width 0.15)
				(type solid)
			)
			(layer "F.Fab")
		)
		(fp_line
			(start 0.201 0)
			(end 0.201 -0.202)
			(stroke
				(width 0.15)
				(type solid)
			)
			(layer "F.Fab")
		)
		(fp_line
			(start 0.201 -0.202)
			(end -0.101 0)
			(stroke
				(width 0.15)
				(type solid)
			)
			(layer "F.Fab")
		)
		(fp_line
			(start -0.101 0)
			(end 0.201 0.2)
			(stroke
				(width 0.15)
				(type solid)
			)
			(layer "F.Fab")
		)
		(fp_line
			(start -0.199 0.2)
			(end -0.199 0.1)
			(stroke
				(width 0.15)
				(type solid)
			)
			(layer "F.Fab")
		)
		(fp_line
			(start -0.199 0)
			(end -0.597 0)
			(stroke
				(width 0.15)
				(type solid)
			)
			(layer "F.Fab")
		)
		(fp_line
			(start -0.199 -0.202)
			(end -0.199 0.1)
			(stroke
				(width 0.15)
				(type solid)
			)
			(layer "F.Fab")
		)
		(fp_rect
			(start 0.848 0.4)
			(end -0.85 -0.402)
			(stroke
				(width 0.15)
				(type solid)
			)
			(fill no)
			(layer "F.Fab")
		)
		(fp_text user "Author: Antmicro"
			(at -1.4224 4.799 180)
			(layer "F.Fab")
			(effects
				(font
					(size 0.7 0.7)
					(thickness 0.15)
				)
				(justify left bottom)
			)
		)
		(fp_text user "License: Apache-2.0"
			(at -1.4224 3.599 180)
			(layer "F.Fab")
			(effects
				(font
					(size 0.7 0.7)
					(thickness 0.15)
				)
				(justify left bottom)
			)
		)
		(fp_text user "${REFERENCE}"
			(at -1.4224 5.999 180)
			(layer "F.Fab")
			(effects
				(font
					(size 0.7 0.7)
					(thickness 0.15)
				)
				(justify left bottom)
			)
		)
		(pad "1" smd roundrect
			(at -0.7 0)
			(size 0.8 1)
			(layers "F.Cu" "F.Mask" "F.Paste")
			(roundrect_rratio 0.2)
			(net 3 "GND")
			(pinfunction "C")
			(pintype "passive")
		)
		(pad "2" smd roundrect
			(at 0.7 0)
			(size 0.8 1)
			(layers "F.Cu" "F.Mask" "F.Paste")
			(roundrect_rratio 0.2)
			(net 473 "Net-(D302-A)")
			(pinfunction "A")
			(pintype "passive")
		)
	)
	(footprint "antmicro-footprints:R_0402_1005Metric"
		(layer "F.Cu")
		(at 123.805476 162.7165)
		(descr "Resistor SMD 0402")
		(tags "resistor SMD 0402")
		(property "Reference" "R504"
			(at -3.837514 0.4 0)
			(layer "F.SilkS")
			(effects
				(font
					(size 0.7 0.7)
					(thickness 0.15)
				)
				(justify left bottom)
			)
		)
		(property "Value" "R_10k_0402"
			(at -1.011843 1.772047 0)
			(layer "F.Fab")
			(effects
				(font
					(size 0.7 0.7)
					(thickness 0.15)
				)
				(justify left bottom)
			)
		)
		(property "Datasheet" "https://www.bourns.com/docs/product-datasheets/cr.pdf"
			(at 0 0 0)
			(layer "F.Fab")
			(hide yes)
			(effects
				(font
					(size 1.27 1.27)
					(thickness 0.15)
				)
			)
		)
		(property "Manufacturer" "Bourns"
			(at 0 0 0)
			(unlocked yes)
			(layer "F.Fab")
			(hide yes)
			(effects
				(font
					(size 1 1)
					(thickness 0.15)
				)
			)
		)
		(property "MPN" "CR0402-FX-1002GLF"
			(at 0 0 0)
			(unlocked yes)
			(layer "F.Fab")
			(hide yes)
			(effects
				(font
					(size 1 1)
					(thickness 0.15)
				)
			)
		)
		(property "Val" "10k"
			(at 0 0 0)
			(unlocked yes)
			(layer "F.Fab")
			(hide yes)
			(effects
				(font
					(size 1 1)
					(thickness 0.15)
				)
			)
		)
		(property "License" "Apache-2.0"
			(at 0 0 0)
			(unlocked yes)
			(layer "F.Fab")
			(hide yes)
			(effects
				(font
					(size 1 1)
					(thickness 0.15)
				)
			)
		)
		(property "Author" "Antmicro"
			(at 0 0 0)
			(unlocked yes)
			(layer "F.Fab")
			(hide yes)
			(effects
				(font
					(size 1 1)
					(thickness 0.15)
				)
			)
		)
		(property "Tolerance" "1%"
			(at 0 0 0)
			(unlocked yes)
			(layer "F.Fab")
			(hide yes)
			(effects
				(font
					(size 1 1)
					(thickness 0.15)
				)
			)
		)
		(sheetname "/NVMe & microSD/")
		(sheetfile "nvme-micro-sd.kicad_sch")
		(attr smd)
		(fp_rect
			(start -0.925 -0.47)
			(end 0.925 0.47)
			(stroke
				(width 0.05)
				(type default)
			)
			(fill no)
			(layer "F.CrtYd")
		)
		(fp_rect
			(start -0.5 -0.25)
			(end 0.5 0.25)
			(stroke
				(width 0.15)
				(type solid)
			)
			(fill no)
			(layer "F.Fab")
		)
		(fp_text user "License: Apache-2.0"
			(at -0.95 5.169 0)
			(layer "F.Fab")
			(effects
				(font
					(size 0.7 0.7)
					(thickness 0.15)
				)
				(justify left bottom)
			)
		)
		(fp_text user "Author: Antmicro"
			(at -0.95 4.169 0)
			(layer "F.Fab")
			(effects
				(font
					(size 0.7 0.7)
					(thickness 0.15)
				)
				(justify left bottom)
			)
		)
		(fp_text user "${REFERENCE}"
			(at -0.95 3.168 0)
			(layer "F.Fab")
			(effects
				(font
					(size 0.7 0.7)
					(thickness 0.15)
				)
				(justify left bottom)
			)
		)
		(pad "1" smd roundrect
			(at -0.48 0)
			(size 0.59 0.64)
			(layers "F.Cu" "F.Mask" "F.Paste")
			(roundrect_rratio 0.25)
			(net 9 "+3V3")
			(pintype "passive")
		)
		(pad "2" smd roundrect
			(at 0.48 0)
			(size 0.59 0.64)
			(layers "F.Cu" "F.Mask" "F.Paste")
			(roundrect_rratio 0.25)
			(net 5 "/Compute module/SDIO.D1")
			(pintype "passive")
		)
	)
	(footprint "antmicro-footprints:Nexperia_DFN-10_2.5x1mm_P0.5mm"
		(layer "F.Cu")
		(at 106.112462 125.349367)
		(property "Reference" "D706"
			(at -1.3195 1.65 0)
			(layer "F.SilkS")
			(effects
				(font
					(size 0.7 0.7)
					(thickness 0.15)
				)
				(justify left bottom)
			)
		)
		(property "Value" "PUSB3F96X_PASS"
			(at -0.016 1.705 0)
			(layer "F.Fab")
			(effects
				(font
					(size 0.7 0.7)
					(thickness 0.15)
				)
				(justify left bottom)
			)
		)
		(property "Datasheet" "https://mouser.com/datasheet/2/916/PUSB3F96-1600324.pdf"
			(at 0 0 0)
			(layer "F.Fab")
			(hide yes)
			(effects
				(font
					(size 1.27 1.27)
					(thickness 0.15)
				)
			)
		)
		(property "Manufacturer" "Nexperia"
			(at 0 0 0)
			(unlocked yes)
			(layer "F.Fab")
			(hide yes)
			(effects
				(font
					(size 1 1)
					(thickness 0.15)
				)
			)
		)
		(property "MPN" "PUSB3F96X"
			(at 0 0 0)
			(unlocked yes)
			(layer "F.Fab")
			(hide yes)
			(effects
				(font
					(size 1 1)
					(thickness 0.15)
				)
			)
		)
		(property "Author" "Antmicro"
			(at 0 0 0)
			(unlocked yes)
			(layer "F.Fab")
			(hide yes)
			(effects
				(font
					(size 1 1)
					(thickness 0.15)
				)
			)
		)
		(property "License" "Apache-2.0"
			(at 0 0 0)
			(unlocked yes)
			(layer "F.Fab")
			(hide yes)
			(effects
				(font
					(size 1 1)
					(thickness 0.15)
				)
			)
		)
		(sheetname "/Display/")
		(sheetfile "display.kicad_sch")
		(attr smd)
		(fp_line
			(start -1.375 -0.4)
			(end -1.375 0.4)
			(stroke
				(width 0.15)
				(type solid)
			)
			(layer "F.SilkS")
		)
		(fp_line
			(start 1.375 0.4)
			(end 1.375 -0.4)
			(stroke
				(width 0.15)
				(type solid)
			)
			(layer "F.SilkS")
		)
		(fp_circle
			(center -1.4 0.7)
			(end -1.349 0.7)
			(stroke
				(width 0.15)
				(type solid)
			)
			(fill yes)
			(layer "F.SilkS")
		)
		(fp_rect
			(start -1.4 -0.725)
			(end 1.4 0.725)
			(stroke
				(width 0.05)
				(type solid)
			)
			(fill no)
			(layer "F.CrtYd")
		)
		(fp_line
			(start -1.25 -0.5)
			(end -1.25 0.15)
			(stroke
				(width 0.15)
				(type solid)
			)
			(layer "F.Fab")
		)
		(fp_line
			(start -1.25 0.15)
			(end -0.9 0.5)
			(stroke
				(width 0.15)
				(type solid)
			)
			(layer "F.Fab")
		)
		(fp_line
			(start -0.9 0.5)
			(end 1.25 0.5)
			(stroke
				(width 0.15)
				(type solid)
			)
			(layer "F.Fab")
		)
		(fp_line
			(start 1.25 -0.5)
			(end -1.25 -0.5)
			(stroke
				(width 0.15)
				(type solid)
			)
			(layer "F.Fab")
		)
		(fp_line
			(start 1.25 0.5)
			(end 1.25 -0.5)
			(stroke
				(width 0.15)
				(type solid)
			)
			(layer "F.Fab")
		)
		(fp_text user "Author: Antmicro"
			(at -1.367 4.905 0)
			(layer "F.Fab")
			(effects
				(font
					(size 0.7 0.7)
					(thickness 0.15)
				)
				(justify left bottom)
			)
		)
		(fp_text user "License: Apache-2.0"
			(at -1.367 6.105 0)
			(layer "F.Fab")
			(effects
				(font
					(size 0.7 0.7)
					(thickness 0.15)
				)
				(justify left bottom)
			)
		)
		(fp_text user "${REFERENCE}"
			(at -1.367 3.704 0)
			(layer "F.Fab")
			(effects
				(font
					(size 0.7 0.7)
					(thickness 0.15)
				)
				(justify left bottom)
			)
		)
		(pad "1" smd rect
			(at -1 0.3875)
			(size 0.2 0.475)
			(layers "F.Cu" "F.Mask" "F.Paste")
			(net 16 "/Compute module/HDMI.D2_P")
			(pinfunction "CH1")
			(pintype "passive")
			(solder_mask_margin 0.05)
		)
		(pad "2" smd rect
			(at -0.5 0.3875)
			(size 0.2 0.475)
			(layers "F.Cu" "F.Mask" "F.Paste")
			(net 15 "/Compute module/HDMI.D2_N")
			(pinfunction "CH2")
			(pintype "passive")
			(solder_mask_margin 0.05)
		)
		(pad "3" smd rect
			(at 0 0.3875)
			(size 0.2 0.475)
			(layers "F.Cu" "F.Mask" "F.Paste")
			(net 3 "GND")
			(pinfunction "GND")
			(pintype "passive")
			(solder_mask_margin 0.05)
		)
		(pad "4" smd rect
			(at 0.5 0.3875)
			(size 0.2 0.475)
			(layers "F.Cu" "F.Mask" "F.Paste")
			(net 14 "/Compute module/HDMI.D1_P")
			(pinfunction "CH3")
			(pintype "passive")
			(solder_mask_margin 0.05)
		)
		(pad "5" smd rect
			(at 1 0.3875)
			(size 0.2 0.475)
			(layers "F.Cu" "F.Mask" "F.Paste")
			(net 13 "/Compute module/HDMI.D1_N")
			(pinfunction "CH4")
			(pintype "passive")
			(solder_mask_margin 0.05)
		)
		(pad "6" smd rect
			(at 1 -0.3875)
			(size 0.2 0.475)
			(layers "F.Cu" "F.Mask" "F.Paste")
			(net 13 "/Compute module/HDMI.D1_N")
			(pinfunction "CH4")
			(pintype "passive")
			(solder_mask_margin 0.05)
		)
		(pad "7" smd rect
			(at 0.5 -0.3875)
			(size 0.2 0.475)
			(layers "F.Cu" "F.Mask" "F.Paste")
			(net 14 "/Compute module/HDMI.D1_P")
			(pinfunction "CH3")
			(pintype "passive")
			(solder_mask_margin 0.05)
		)
		(pad "8" smd rect
			(at 0 -0.3875)
			(size 0.2 0.475)
			(layers "F.Cu" "F.Mask" "F.Paste")
			(net 3 "GND")
			(pinfunction "GND")
			(pintype "passive")
			(solder_mask_margin 0.05)
		)
		(pad "9" smd rect
			(at -0.501 -0.3875)
			(size 0.2 0.475)
			(layers "F.Cu" "F.Mask" "F.Paste")
			(net 15 "/Compute module/HDMI.D2_N")
			(pinfunction "CH2")
			(pintype "passive")
			(solder_mask_margin 0.05)
		)
		(pad "10" smd rect
			(at -1 -0.3875)
			(size 0.2 0.475)
			(layers "F.Cu" "F.Mask" "F.Paste")
			(net 16 "/Compute module/HDMI.D2_P")
			(pinfunction "CH1")
			(pintype "passive")
			(solder_mask_margin 0.05)
		)
	)
	(footprint "antmicro-footprints:TP_SMD_0.75mm"
		(layer "F.Cu")
		(at 95.1 132.35)
		(property "Reference" "TP908"
			(at 1.8 3.12 0)
			(layer "F.SilkS")
			(effects
				(font
					(size 0.7 0.7)
					(thickness 0.15)
				)
				(justify left bottom)
			)
		)
		(property "Value" "TP_0.75mm_SMD"
			(at 0 1.2 0)
			(layer "F.Fab")
			(effects
				(font
					(size 0.7 0.7)
					(thickness 0.15)
				)
				(justify left bottom)
			)
		)
		(property "MPN" ""
			(at 0 0 0)
			(unlocked yes)
			(layer "F.Fab")
			(hide yes)
			(effects
				(font
					(size 1 1)
					(thickness 0.15)
				)
			)
		)
		(property "Manufacturer" ""
			(at 0 0 0)
			(unlocked yes)
			(layer "F.Fab")
			(hide yes)
			(effects
				(font
					(size 1 1)
					(thickness 0.15)
				)
			)
		)
		(property "Author" "Antmicro"
			(at 0 0 0)
			(unlocked yes)
			(layer "F.Fab")
			(hide yes)
			(effects
				(font
					(size 1 1)
					(thickness 0.15)
				)
			)
		)
		(property "License" "Apache-2.0"
			(at 0 0 0)
			(unlocked yes)
			(layer "F.Fab")
			(hide yes)
			(effects
				(font
					(size 1 1)
					(thickness 0.15)
				)
			)
		)
		(sheetname "/USB/")
		(sheetfile "usb.kicad_sch")
		(attr exclude_from_pos_files exclude_from_bom)
		(fp_circle
			(center 0 0)
			(end 0.475 0)
			(stroke
				(width 0.05)
				(type default)
			)
			(fill no)
			(layer "F.CrtYd")
		)
		(fp_text user "${REFERENCE}"
			(at -0.4 2.7 0)
			(layer "F.Fab")
			(effects
				(font
					(size 0.7 0.7)
					(thickness 0.15)
				)
				(justify left bottom)
			)
		)
		(fp_text user "Author: Antmicro"
			(at -0.4 3.901 0)
			(layer "F.Fab")
			(effects
				(font
					(size 0.7 0.7)
					(thickness 0.15)
				)
				(justify left bottom)
			)
		)
		(fp_text user "License: Apache-2.0"
			(at -0.4 5.101 0)
			(layer "F.Fab")
			(effects
				(font
					(size 0.7 0.7)
					(thickness 0.15)
				)
				(justify left bottom)
			)
		)
		(pad "1" smd circle
			(at 0 0)
			(size 0.75 0.75)
			(layers "F.Cu" "F.Mask")
			(net 385 "Net-(U905-GPIO7)")
			(pinfunction "1")
			(pintype "passive")
		)
	)
	(footprint "antmicro-footprints:SOD-523"
		(layer "F.Cu")
		(at 99.617962 145.3165 180)
		(property "Reference" "D908"
			(at -1.6 -1.45 0)
			(layer "F.SilkS")
			(effects
				(font
					(size 0.7 0.7)
					(thickness 0.15)
				)
				(justify right bottom)
			)
		)
		(property "Value" "RB521S30T1G"
			(at 0 1.499 0)
			(layer "F.Fab")
			(effects
				(font
					(size 0.7 0.7)
					(thickness 0.15)
				)
				(justify right bottom)
			)
		)
		(property "Datasheet" "https://www.onsemi.com/pdf/datasheet/rb521s30t1-d.pdf"
			(at 0 0 180)
			(layer "F.Fab")
			(hide yes)
			(effects
				(font
					(size 1.27 1.27)
					(thickness 0.15)
				)
			)
		)
		(property "MPN" "RB521S30T1G"
			(at 0 0 180)
			(unlocked yes)
			(layer "F.Fab")
			(hide yes)
			(effects
				(font
					(size 1 1)
					(thickness 0.15)
				)
			)
		)
		(property "Manufacturer" "ON Semiconductor"
			(at 0 0 180)
			(unlocked yes)
			(layer "F.Fab")
			(hide yes)
			(effects
				(font
					(size 1 1)
					(thickness 0.15)
				)
			)
		)
		(property "Author" "Antmicro"
			(at 0 0 180)
			(unlocked yes)
			(layer "F.Fab")
			(hide yes)
			(effects
				(font
					(size 1 1)
					(thickness 0.15)
				)
			)
		)
		(property "License" "Apache-2.0"
			(at 0 0 180)
			(unlocked yes)
			(layer "F.Fab")
			(hide yes)
			(effects
				(font
					(size 1 1)
					(thickness 0.15)
				)
			)
		)
		(sheetname "/USB/")
		(sheetfile "usb.kicad_sch")
		(attr smd)
		(fp_line
			(start -0.35 -0.5)
			(end -0.35 0.5)
			(stroke
				(width 0.15)
				(type solid)
			)
			(layer "F.SilkS")
		)
		(fp_rect
			(start -1 -0.6)
			(end 1 0.6)
			(stroke
				(width 0.05)
				(type solid)
			)
			(fill no)
			(layer "F.CrtYd")
		)
		(fp_line
			(start 0.65 -0.425)
			(end 0.65 0.423)
			(stroke
				(width 0.15)
				(type solid)
			)
			(layer "F.Fab")
		)
		(fp_line
			(start -0.35 -0.4)
			(end -0.35 0.4)
			(stroke
				(width 0.15)
				(type solid)
			)
			(layer "F.Fab")
		)
		(fp_line
			(start -0.652 0.423)
			(end 0.65 0.423)
			(stroke
				(width 0.15)
				(type solid)
			)
			(layer "F.Fab")
		)
		(fp_line
			(start -0.652 0.423)
			(end -0.652 -0.425)
			(stroke
				(width 0.15)
				(type solid)
			)
			(layer "F.Fab")
		)
		(fp_line
			(start -0.652 -0.425)
			(end 0.65 -0.425)
			(stroke
				(width 0.15)
				(type solid)
			)
			(layer "F.Fab")
		)
		(fp_text user "${REFERENCE}"
			(at -1.276 3.499 180)
			(layer "F.Fab")
			(effects
				(font
					(size 0.7 0.7)
					(thickness 0.15)
				)
				(justify left bottom)
			)
		)
		(fp_text user "License: Apache-2.0"
			(at -1.276 5.9 180)
			(layer "F.Fab")
			(effects
				(font
					(size 0.7 0.7)
					(thickness 0.15)
				)
				(justify left bottom)
			)
		)
		(fp_text user "Author: Antmicro"
			(at -1.276 4.7 180)
			(layer "F.Fab")
			(effects
				(font
					(size 0.7 0.7)
					(thickness 0.15)
				)
				(justify left bottom)
			)
		)
		(pad "1" smd roundrect
			(at -0.701 0 180)
			(size 0.5 0.6)
			(layers "F.Cu" "F.Mask" "F.Paste")
			(roundrect_rratio 0.25)
			(net 485 "Net-(D908-C)")
			(pinfunction "C")
			(pintype "passive")
		)
		(pad "2" smd roundrect
			(at 0.699 0 180)
			(size 0.5 0.6)
			(layers "F.Cu" "F.Mask" "F.Paste")
			(roundrect_rratio 0.25)
			(net 143 "/CSI/I_{2}C1.SDA")
			(pinfunction "A")
			(pintype "passive")
		)
	)
	(footprint "antmicro-footprints:R_0402_1005Metric"
		(layer "F.Cu")
		(at 110.951464 157.0515 180)
		(descr "Resistor SMD 0402")
		(tags "resistor SMD 0402")
		(property "Reference" "R227"
			(at 1.873502 -2.425 180)
			(layer "F.SilkS")
			(effects
				(font
					(size 0.7 0.7)
					(thickness 0.15)
				)
				(justify left bottom)
			)
		)
		(property "Value" "R_0R_0402"
			(at -1.011843 1.772047 180)
			(layer "F.Fab")
			(effects
				(font
					(size 0.7 0.7)
					(thickness 0.15)
				)
				(justify left bottom)
			)
		)
		(property "Datasheet" "https://industrial.panasonic.com/cdbs/www-data/pdf/RDA0000/AOA0000C301.pdf"
			(at 0 0 180)
			(layer "F.Fab")
			(hide yes)
			(effects
				(font
					(size 1.27 1.27)
					(thickness 0.15)
				)
			)
		)
		(property "Manufacturer" "Panasonic"
			(at 0 0 180)
			(unlocked yes)
			(layer "F.Fab")
			(hide yes)
			(effects
				(font
					(size 1 1)
					(thickness 0.15)
				)
			)
		)
		(property "MPN" "ERJ2GE0R00X"
			(at 0 0 180)
			(unlocked yes)
			(layer "F.Fab")
			(hide yes)
			(effects
				(font
					(size 1 1)
					(thickness 0.15)
				)
			)
		)
		(property "Val" "0R"
			(at 0 0 180)
			(unlocked yes)
			(layer "F.Fab")
			(hide yes)
			(effects
				(font
					(size 1 1)
					(thickness 0.15)
				)
			)
		)
		(property "License" "Apache-2.0"
			(at 0 0 180)
			(unlocked yes)
			(layer "F.Fab")
			(hide yes)
			(effects
				(font
					(size 1 1)
					(thickness 0.15)
				)
			)
		)
		(property "Author" "Antmicro"
			(at 0 0 180)
			(unlocked yes)
			(layer "F.Fab")
			(hide yes)
			(effects
				(font
					(size 1 1)
					(thickness 0.15)
				)
			)
		)
		(property "Tolerance" "~"
			(at 0 0 180)
			(unlocked yes)
			(layer "F.Fab")
			(hide yes)
			(effects
				(font
					(size 1 1)
					(thickness 0.15)
				)
			)
		)
		(property "Current" "1A"
			(at 0 0 180)
			(unlocked yes)
			(layer "F.Fab")
			(hide yes)
			(effects
				(font
					(size 1 1)
					(thickness 0.15)
				)
			)
		)
		(sheetname "/Compute module/")
		(sheetfile "compute-module.kicad_sch")
		(attr smd)
		(fp_rect
			(start -0.925 -0.47)
			(end 0.925 0.47)
			(stroke
				(width 0.05)
				(type default)
			)
			(fill no)
			(layer "F.CrtYd")
		)
		(fp_rect
			(start -0.5 -0.25)
			(end 0.5 0.25)
			(stroke
				(width 0.15)
				(type solid)
			)
			(fill no)
			(layer "F.Fab")
		)
		(fp_text user "License: Apache-2.0"
			(at -0.95 5.169 180)
			(layer "F.Fab")
			(effects
				(font
					(size 0.7 0.7)
					(thickness 0.15)
				)
				(justify left bottom)
			)
		)
		(fp_text user "Author: Antmicro"
			(at -0.95 4.169 180)
			(layer "F.Fab")
			(effects
				(font
					(size 0.7 0.7)
					(thickness 0.15)
				)
				(justify left bottom)
			)
		)
		(fp_text user "${REFERENCE}"
			(at -0.95 3.168 180)
			(layer "F.Fab")
			(effects
				(font
					(size 0.7 0.7)
					(thickness 0.15)
				)
				(justify left bottom)
			)
		)
		(pad "1" smd roundrect
			(at -0.48 0 180)
			(size 0.59 0.64)
			(layers "F.Cu" "F.Mask" "F.Paste")
			(roundrect_rratio 0.25)
			(net 153 "/Compute module/T3_N")
			(pintype "passive")
		)
		(pad "2" smd roundrect
			(at 0.48 0 180)
			(size 0.59 0.64)
			(layers "F.Cu" "F.Mask" "F.Paste")
			(roundrect_rratio 0.25)
			(net 160 "/Compute module/NVMe.TX3_N")
			(pintype "passive")
		)
	)
	(footprint "antmicro-footprints:LED_0603_1608Metric_G"
		(layer "F.Cu")
		(at 75.583462 145.9865 180)
		(descr "LED SMD 0603 Green")
		(tags "LED SMD 0603 Green")
		(property "Reference" "D202"
			(at -1.2845 4.72 0)
			(layer "F.SilkS")
			(effects
				(font
					(size 0.7 0.7)
					(thickness 0.15)
				)
				(justify right bottom)
			)
		)
		(property "Value" "LED_G_0603_KP-1608CGCK"
			(at -0.001 1.599 0)
			(layer "F.Fab")
			(effects
				(font
					(size 0.7 0.7)
					(thickness 0.15)
				)
				(justify right bottom)
			)
		)
		(property "Datasheet" "http://www.kingbright.com/attachments/file/psearch//000/00/00/KP-1608CGCK(Ver.23B).pdf"
			(at 0 0 180)
			(layer "F.Fab")
			(hide yes)
			(effects
				(font
					(size 1.27 1.27)
					(thickness 0.15)
				)
			)
		)
		(property "MPN" "KP-1608CGCK"
			(at 0 0 180)
			(unlocked yes)
			(layer "F.Fab")
			(hide yes)
			(effects
				(font
					(size 1 1)
					(thickness 0.15)
				)
			)
		)
		(property "Manufacturer" "Kingbright"
			(at 0 0 180)
			(unlocked yes)
			(layer "F.Fab")
			(hide yes)
			(effects
				(font
					(size 1 1)
					(thickness 0.15)
				)
			)
		)
		(property "Color" "Green"
			(at 0 0 180)
			(unlocked yes)
			(layer "F.Fab")
			(hide yes)
			(effects
				(font
					(size 1 1)
					(thickness 0.15)
				)
			)
		)
		(property "Author" "Antmicro"
			(at 0 0 180)
			(unlocked yes)
			(layer "F.Fab")
			(hide yes)
			(effects
				(font
					(size 1 1)
					(thickness 0.15)
				)
			)
		)
		(property "License" "Apache-2.0"
			(at 0 0 180)
			(unlocked yes)
			(layer "F.Fab")
			(hide yes)
			(effects
				(font
					(size 1 1)
					(thickness 0.15)
				)
			)
		)
		(sheetname "/Compute module/")
		(sheetfile "compute-module.kicad_sch")
		(attr smd)
		(fp_line
			(start 0.22 0.35)
			(end -0.22 0.35)
			(stroke
				(width 0.15)
				(type solid)
			)
			(layer "F.SilkS")
		)
		(fp_line
			(start 0.22 -0.35)
			(end -0.22 -0.35)
			(stroke
				(width 0.15)
				(type solid)
			)
			(layer "F.SilkS")
		)
		(fp_line
			(start 0.105328 0.201008)
			(end 0.105328 -0.198992)
			(stroke
				(width 0.1)
				(type solid)
			)
			(layer "F.SilkS")
		)
		(fp_line
			(start 0.105328 0.201008)
			(end -0.094672 0.001008)
			(stroke
				(width 0.1)
				(type solid)
			)
			(layer "F.SilkS")
		)
		(fp_line
			(start 0.105328 0.001008)
			(end 0.24 0.001)
			(stroke
				(width 0.1)
				(type solid)
			)
			(layer "F.SilkS")
		)
		(fp_line
			(start -0.094672 0.201008)
			(end -0.094672 -0.198992)
			(stroke
				(width 0.1)
				(type solid)
			)
			(layer "F.SilkS")
		)
		(fp_line
			(start -0.094672 0.001008)
			(end 0.105328 -0.198992)
			(stroke
				(width 0.1)
				(type solid)
			)
			(layer "F.SilkS")
		)
		(fp_line
			(start -0.094672 0.001008)
			(end -0.24 0.001008)
			(stroke
				(width 0.1)
				(type solid)
			)
			(layer "F.SilkS")
		)
		(fp_line
			(start -1.18 -0.319)
			(end -1.18 0.321)
			(stroke
				(width 0.15)
				(type solid)
			)
			(layer "F.SilkS")
		)
		(fp_rect
			(start 1.25 0.65)
			(end -1.25 -0.65)
			(stroke
				(width 0.05)
				(type solid)
			)
			(fill no)
			(layer "F.CrtYd")
		)
		(fp_line
			(start 0.599 0)
			(end 0.201 0)
			(stroke
				(width 0.15)
				(type solid)
			)
			(layer "F.Fab")
		)
		(fp_line
			(start 0.201 0.2)
			(end 0.201 0)
			(stroke
				(width 0.15)
				(type solid)
			)
			(layer "F.Fab")
		)
		(fp_line
			(start 0.201 0)
			(end 0.201 -0.202)
			(stroke
				(width 0.15)
				(type solid)
			)
			(layer "F.Fab")
		)
		(fp_line
			(start 0.201 -0.202)
			(end -0.101 0)
			(stroke
				(width 0.15)
				(type solid)
			)
			(layer "F.Fab")
		)
		(fp_line
			(start -0.101 0)
			(end 0.201 0.2)
			(stroke
				(width 0.15)
				(type solid)
			)
			(layer "F.Fab")
		)
		(fp_line
			(start -0.199 0.2)
			(end -0.199 0.1)
			(stroke
				(width 0.15)
				(type solid)
			)
			(layer "F.Fab")
		)
		(fp_line
			(start -0.199 0)
			(end -0.597 0)
			(stroke
				(width 0.15)
				(type solid)
			)
			(layer "F.Fab")
		)
		(fp_line
			(start -0.199 -0.202)
			(end -0.199 0.1)
			(stroke
				(width 0.15)
				(type solid)
			)
			(layer "F.Fab")
		)
		(fp_rect
			(start 0.848 0.4)
			(end -0.85 -0.402)
			(stroke
				(width 0.15)
				(type solid)
			)
			(fill no)
			(layer "F.Fab")
		)
		(fp_text user "License: Apache-2.0"
			(at -1.4224 3.599 180)
			(layer "F.Fab")
			(effects
				(font
					(size 0.7 0.7)
					(thickness 0.15)
				)
				(justify left bottom)
			)
		)
		(fp_text user "${REFERENCE}"
			(at -1.4224 5.999 180)
			(layer "F.Fab")
			(effects
				(font
					(size 0.7 0.7)
					(thickness 0.15)
				)
				(justify left bottom)
			)
		)
		(fp_text user "Author: Antmicro"
			(at -1.4224 4.799 180)
			(layer "F.Fab")
			(effects
				(font
					(size 0.7 0.7)
					(thickness 0.15)
				)
				(justify left bottom)
			)
		)
		(pad "1" smd roundrect
			(at -0.7 0)
			(size 0.8 1)
			(layers "F.Cu" "F.Mask" "F.Paste")
			(roundrect_rratio 0.2)
			(net 467 "Net-(D202-C)")
			(pinfunction "C")
			(pintype "passive")
		)
		(pad "2" smd roundrect
			(at 0.7 0)
			(size 0.8 1)
			(layers "F.Cu" "F.Mask" "F.Paste")
			(roundrect_rratio 0.2)
			(net 468 "Net-(D202-A)")
			(pinfunction "A")
			(pintype "passive")
		)
	)
	(footprint "antmicro-footprints:TP_SMD_0.75mm"
		(layer "F.Cu")
		(at 74.842962 157.2915)
		(property "Reference" "TP301"
			(at 1.257038 0.7085 90)
			(layer "F.SilkS")
			(effects
				(font
					(size 0.7 0.7)
					(thickness 0.15)
				)
				(justify left bottom)
			)
		)
		(property "Value" "TP_0.75mm_SMD"
			(at 0 1.2 0)
			(layer "F.Fab")
			(effects
				(font
					(size 0.7 0.7)
					(thickness 0.15)
				)
				(justify left bottom)
			)
		)
		(property "MPN" ""
			(at 0 0 0)
			(unlocked yes)
			(layer "F.Fab")
			(hide yes)
			(effects
				(font
					(size 1 1)
					(thickness 0.15)
				)
			)
		)
		(property "Manufacturer" ""
			(at 0 0 0)
			(unlocked yes)
			(layer "F.Fab")
			(hide yes)
			(effects
				(font
					(size 1 1)
					(thickness 0.15)
				)
			)
		)
		(property "Author" "Antmicro"
			(at 0 0 0)
			(unlocked yes)
			(layer "F.Fab")
			(hide yes)
			(effects
				(font
					(size 1 1)
					(thickness 0.15)
				)
			)
		)
		(property "License" "Apache-2.0"
			(at 0 0 0)
			(unlocked yes)
			(layer "F.Fab")
			(hide yes)
			(effects
				(font
					(size 1 1)
					(thickness 0.15)
				)
			)
		)
		(sheetname "/Supply/")
		(sheetfile "supply.kicad_sch")
		(attr exclude_from_pos_files exclude_from_bom)
		(fp_circle
			(center 0 0)
			(end 0.475 0)
			(stroke
				(width 0.05)
				(type default)
			)
			(fill no)
			(layer "F.CrtYd")
		)
		(fp_text user "${REFERENCE}"
			(at -0.4 2.7 0)
			(layer "F.Fab")
			(effects
				(font
					(size 0.7 0.7)
					(thickness 0.15)
				)
				(justify left bottom)
			)
		)
		(fp_text user "License: Apache-2.0"
			(at -0.4 5.101 0)
			(layer "F.Fab")
			(effects
				(font
					(size 0.7 0.7)
					(thickness 0.15)
				)
				(justify left bottom)
			)
		)
		(fp_text user "Author: Antmicro"
			(at -0.4 3.901 0)
			(layer "F.Fab")
			(effects
				(font
					(size 0.7 0.7)
					(thickness 0.15)
				)
				(justify left bottom)
			)
		)
		(pad "1" smd circle
			(at 0 0)
			(size 0.75 0.75)
			(layers "F.Cu" "F.Mask")
			(net 43 "VCC")
			(pinfunction "1")
			(pintype "passive")
		)
	)
	(footprint "antmicro-footprints:USB-C_Receptacle_GCT_USB4105-GF-A"
		(layer "F.Cu")
		(at 79.780962 115.602 180)
		(property "Reference" "J902"
			(at -7.567 3.7555 90)
			(layer "F.SilkS")
			(effects
				(font
					(size 0.7 0.7)
					(thickness 0.15)
				)
				(justify right bottom)
			)
		)
		(property "Value" "USB-C_GCT_USB4105-GF-A"
			(at 0 5 0)
			(layer "F.Fab")
			(effects
				(font
					(size 0.7 0.7)
					(thickness 0.15)
				)
				(justify right bottom)
			)
		)
		(property "Datasheet" "https://gct.co/files/drawings/usb4105.pdf"
			(at 0 0 180)
			(layer "F.Fab")
			(hide yes)
			(effects
				(font
					(size 1.27 1.27)
					(thickness 0.15)
				)
			)
		)
		(property "Manufacturer" "GCT"
			(at 0 0 180)
			(unlocked yes)
			(layer "F.Fab")
			(hide yes)
			(effects
				(font
					(size 1 1)
					(thickness 0.15)
				)
			)
		)
		(property "MPN" "USB4105-GF-A"
			(at 0 0 180)
			(unlocked yes)
			(layer "F.Fab")
			(hide yes)
			(effects
				(font
					(size 1 1)
					(thickness 0.15)
				)
			)
		)
		(property "Author" "Antmicro"
			(at 0 0 180)
			(unlocked yes)
			(layer "F.Fab")
			(hide yes)
			(effects
				(font
					(size 1 1)
					(thickness 0.15)
				)
			)
		)
		(property "License" "Apache-2.0"
			(at 0 0 180)
			(unlocked yes)
			(layer "F.Fab")
			(hide yes)
			(effects
				(font
					(size 1 1)
					(thickness 0.15)
				)
			)
		)
		(sheetname "/USB/")
		(sheetfile "usb.kicad_sch")
		(attr smd)
		(fp_line
			(start 4.788 3.854)
			(end 4.788 2.575)
			(stroke
				(width 0.15)
				(type solid)
			)
			(layer "F.SilkS")
		)
		(fp_line
			(start 4.788 -1.395)
			(end 4.788 -0.145)
			(stroke
				(width 0.15)
				(type solid)
			)
			(layer "F.SilkS")
		)
		(fp_line
			(start -4.79 3.854)
			(end 4.788 3.854)
			(stroke
				(width 0.15)
				(type solid)
			)
			(layer "F.SilkS")
		)
		(fp_line
			(start -4.79 2.575)
			(end -4.79 3.854)
			(stroke
				(width 0.15)
				(type solid)
			)
			(layer "F.SilkS")
		)
		(fp_line
			(start -4.79 -1.395)
			(end -4.79 -0.145)
			(stroke
				(width 0.15)
				(type solid)
			)
			(layer "F.SilkS")
		)
		(fp_circle
			(center -3.8 -4.27071)
			(end -3.75 -4.22071)
			(stroke
				(width 0.15)
				(type solid)
			)
			(fill yes)
			(layer "F.SilkS")
		)
		(fp_rect
			(start -5.1 -4.4)
			(end 5.1 3.9)
			(stroke
				(width 0.05)
				(type solid)
			)
			(fill no)
			(layer "F.CrtYd")
		)
		(fp_line
			(start 4.788 3.854)
			(end -4.79 3.854)
			(stroke
				(width 0.15)
				(type solid)
			)
			(layer "F.Fab")
		)
		(fp_line
			(start 4.788 -3.676)
			(end 4.788 3.854)
			(stroke
				(width 0.15)
				(type solid)
			)
			(layer "F.Fab")
		)
		(fp_line
			(start -4.702 3.854)
			(end 4.788 3.854)
			(stroke
				(width 0.15)
				(type solid)
			)
			(layer "F.Fab")
		)
		(fp_line
			(start -4.79 3.854)
			(end -4.79 -3.676)
			(stroke
				(width 0.15)
				(type solid)
			)
			(layer "F.Fab")
		)
		(fp_line
			(start -4.79 -3.676)
			(end 4.788 -3.676)
			(stroke
				(width 0.15)
				(type solid)
			)
			(layer "F.Fab")
		)
		(fp_text user "License: Apache-2.0"
			(at -4.79 8.855 180)
			(layer "F.Fab")
			(effects
				(font
					(size 0.7 0.7)
					(thickness 0.15)
				)
				(justify left bottom)
			)
		)
		(fp_text user "PCB-EDGE"
			(at -4.79 5.853 180)
			(layer "F.Fab")
			(effects
				(font
					(size 0.7 0.7)
					(thickness 0.15)
				)
				(justify left bottom)
			)
		)
		(fp_text user "Author: Antmicro"
			(at -4.79 7.853 180)
			(layer "F.Fab")
			(effects
				(font
					(size 0.7 0.7)
					(thickness 0.15)
				)
				(justify left bottom)
			)
		)
		(fp_text user "${REFERENCE}"
			(at -4.79 6.853 180)
			(layer "F.Fab")
			(effects
				(font
					(size 0.7 0.7)
					(thickness 0.15)
				)
				(justify left bottom)
			)
		)
		(pad "" np_thru_hole circle
			(at -2.891 -2.426 180)
			(size 0.65 0.65)
			(drill 0.65)
			(layers "*.Cu" "*.Mask")
		)
		(pad "" np_thru_hole circle
			(at 2.89 -2.426 180)
			(size 0.65 0.65)
			(drill 0.65)
			(layers "*.Cu" "*.Mask")
		)
		(pad "A1" smd roundrect
			(at -3.202 -3.5 180)
			(size 0.6 1.15)
			(layers "F.Cu" "F.Mask" "F.Paste")
			(roundrect_rratio 0.25)
			(net 3 "GND")
			(pinfunction "GND")
			(pintype "power_in")
		)
		(pad "A4" smd roundrect
			(at -2.4 -3.5 180)
			(size 0.6 1.15)
			(layers "F.Cu" "F.Mask" "F.Paste")
			(roundrect_rratio 0.25)
			(net 26 "/USB/USBD_VBUS")
			(pinfunction "VBUS")
			(pintype "power_in")
		)
		(pad "A5" smd roundrect
			(at -1.25 -3.5 180)
			(size 0.3 1.15)
			(layers "F.Cu" "F.Mask" "F.Paste")
			(roundrect_rratio 0.25)
			(net 207 "/USB/USBD_CC1")
			(pinfunction "CC_{1}")
			(pintype "bidirectional")
		)
		(pad "A6" smd roundrect
			(at -0.25 -3.5 180)
			(size 0.3 1.15)
			(layers "F.Cu" "F.Mask" "F.Paste")
			(roundrect_rratio 0.25)
			(net 209 "/USB/DD_P")
			(pinfunction "D_{A}+")
			(pintype "bidirectional")
		)
		(pad "A7" smd roundrect
			(at 0.248 -3.5 180)
			(size 0.3 1.15)
			(layers "F.Cu" "F.Mask" "F.Paste")
			(roundrect_rratio 0.25)
			(net 210 "/USB/DD_N")
			(pinfunction "D_{A}-")
			(pintype "bidirectional")
		)
		(pad "A8" smd roundrect
			(at 1.249 -3.5 180)
			(size 0.3 1.15)
			(layers "F.Cu" "F.Mask" "F.Paste")
			(roundrect_rratio 0.25)
			(net 324 "unconnected-(J902-SBU_{1}-PadA8)")
			(pinfunction "SBU_{1}")
			(pintype "bidirectional+no_connect")
		)
		(pad "A9" smd roundrect
			(at 2.398 -3.5 180)
			(size 0.6 1.15)
			(layers "F.Cu" "F.Mask" "F.Paste")
			(roundrect_rratio 0.25)
			(net 26 "/USB/USBD_VBUS")
			(pinfunction "VBUS")
			(pintype "passive")
		)
		(pad "A12" smd roundrect
			(at 3.2 -3.5 180)
			(size 0.6 1.15)
			(layers "F.Cu" "F.Mask" "F.Paste")
			(roundrect_rratio 0.25)
			(net 3 "GND")
			(pinfunction "GND")
			(pintype "passive")
		)
		(pad "B1" smd roundrect
			(at 3.2 -3.5 180)
			(size 0.6 1.15)
			(layers "F.Cu" "F.Mask" "F.Paste")
			(roundrect_rratio 0.25)
			(net 3 "GND")
			(pinfunction "GND")
			(pintype "passive")
		)
		(pad "B4" smd roundrect
			(at 2.398 -3.5 180)
			(size 0.6 1.15)
			(layers "F.Cu" "F.Mask" "F.Paste")
			(roundrect_rratio 0.25)
			(net 26 "/USB/USBD_VBUS")
			(pinfunction "VBUS")
			(pintype "passive")
		)
		(pad "B5" smd roundrect
			(at 1.749 -3.5 180)
			(size 0.3 1.15)
			(layers "F.Cu" "F.Mask" "F.Paste")
			(roundrect_rratio 0.25)
			(net 208 "/USB/USBD_CC2")
			(pinfunction "CC_{2}")
			(pintype "bidirectional")
		)
		(pad "B6" smd roundrect
			(at 0.748 -3.5 180)
			(size 0.3 1.15)
			(layers "F.Cu" "F.Mask" "F.Paste")
			(roundrect_rratio 0.25)
			(net 209 "/USB/DD_P")
			(pinfunction "D_{B}+")
			(pintype "bidirectional")
		)
		(pad "B7" smd roundrect
			(at -0.75 -3.5 180)
			(size 0.3 1.15)
			(layers "F.Cu" "F.Mask" "F.Paste")
			(roundrect_rratio 0.25)
			(net 210 "/USB/DD_N")
			(pinfunction "D_{B}-")
			(pintype "bidirectional")
		)
		(pad "B8" smd roundrect
			(at -1.75 -3.5 180)
			(size 0.3 1.15)
			(layers "F.Cu" "F.Mask" "F.Paste")
			(roundrect_rratio 0.25)
			(net 323 "unconnected-(J902-SBU_{2}-PadB8)")
			(pinfunction "SBU_{2}")
			(pintype "bidirectional+no_connect")
		)
		(pad "B9" smd roundrect
			(at -2.4 -3.5 180)
			(size 0.6 1.15)
			(layers "F.Cu" "F.Mask" "F.Paste")
			(roundrect_rratio 0.25)
			(net 26 "/USB/USBD_VBUS")
			(pinfunction "VBUS")
			(pintype "passive")
		)
		(pad "B12" smd roundrect
			(at -3.202 -3.5 180)
			(size 0.6 1.15)
			(layers "F.Cu" "F.Mask" "F.Paste")
			(roundrect_rratio 0.25)
			(net 3 "GND")
			(pinfunction "GND")
			(pintype "passive")
		)
		(pad "SH" thru_hole oval
			(at -4.321 -2.926 180)
			(size 1.05 2.1)
			(drill oval 0.6 1.7)
			(layers "*.Cu" "*.Mask")
			(remove_unused_layers no)
			(net 3 "GND")
			(pinfunction "SH")
			(pintype "passive")
		)
		(pad "SH" thru_hole oval
			(at -4.321 1.255 180)
			(size 1 2)
			(drill oval 0.6 1.4)
			(layers "*.Cu" "*.Mask")
			(remove_unused_layers no)
			(net 3 "GND")
			(pinfunction "SH")
			(pintype "passive")
		)
		(pad "SH" thru_hole oval
			(at 4.32 -2.926 180)
			(size 1.05 2.1)
			(drill oval 0.6 1.7)
			(layers "*.Cu" "*.Mask")
			(remove_unused_layers no)
			(net 3 "GND")
			(pinfunction "SH")
			(pintype "passive")
		)
		(pad "SH" thru_hole oval
			(at 4.32 1.255 180)
			(size 1 2)
			(drill oval 0.6 1.4)
			(layers "*.Cu" "*.Mask")
			(remove_unused_layers no)
			(net 3 "GND")
			(pinfunction "SH")
			(pintype "passive")
		)
	)
	(footprint "antmicro-footprints:R_0402_1005Metric"
		(layer "F.Cu")
		(at 73.442962 157.2915)
		(descr "Resistor SMD 0402")
		(tags "resistor SMD 0402")
		(property "Reference" "R310"
			(at -8.635 -0.215 0)
			(layer "F.SilkS")
			(effects
				(font
					(size 0.7 0.7)
					(thickness 0.15)
				)
				(justify left bottom)
			)
		)
		(property "Value" "R_10k_0402"
			(at -1.011843 1.772047 0)
			(layer "F.Fab")
			(effects
				(font
					(size 0.7 0.7)
					(thickness 0.15)
				)
				(justify left bottom)
			)
		)
		(property "Datasheet" "https://www.bourns.com/docs/product-datasheets/cr.pdf"
			(at 0 0 0)
			(layer "F.Fab")
			(hide yes)
			(effects
				(font
					(size 1.27 1.27)
					(thickness 0.15)
				)
			)
		)
		(property "Manufacturer" "Bourns"
			(at 0 0 0)
			(unlocked yes)
			(layer "F.Fab")
			(hide yes)
			(effects
				(font
					(size 1 1)
					(thickness 0.15)
				)
			)
		)
		(property "MPN" "CR0402-FX-1002GLF"
			(at 0 0 0)
			(unlocked yes)
			(layer "F.Fab")
			(hide yes)
			(effects
				(font
					(size 1 1)
					(thickness 0.15)
				)
			)
		)
		(property "Val" "10k"
			(at 0 0 0)
			(unlocked yes)
			(layer "F.Fab")
			(hide yes)
			(effects
				(font
					(size 1 1)
					(thickness 0.15)
				)
			)
		)
		(property "License" "Apache-2.0"
			(at 0 0 0)
			(unlocked yes)
			(layer "F.Fab")
			(hide yes)
			(effects
				(font
					(size 1 1)
					(thickness 0.15)
				)
			)
		)
		(property "Author" "Antmicro"
			(at 0 0 0)
			(unlocked yes)
			(layer "F.Fab")
			(hide yes)
			(effects
				(font
					(size 1 1)
					(thickness 0.15)
				)
			)
		)
		(property "Tolerance" "1%"
			(at 0 0 0)
			(unlocked yes)
			(layer "F.Fab")
			(hide yes)
			(effects
				(font
					(size 1 1)
					(thickness 0.15)
				)
			)
		)
		(sheetname "/Supply/")
		(sheetfile "supply.kicad_sch")
		(attr smd)
		(fp_rect
			(start -0.925 -0.47)
			(end 0.925 0.47)
			(stroke
				(width 0.05)
				(type default)
			)
			(fill no)
			(layer "F.CrtYd")
		)
		(fp_rect
			(start -0.5 -0.25)
			(end 0.5 0.25)
			(stroke
				(width 0.15)
				(type solid)
			)
			(fill no)
			(layer "F.Fab")
		)
		(fp_text user "${REFERENCE}"
			(at -0.95 3.168 0)
			(layer "F.Fab")
			(effects
				(font
					(size 0.7 0.7)
					(thickness 0.15)
				)
				(justify left bottom)
			)
		)
		(fp_text user "Author: Antmicro"
			(at -0.95 4.169 0)
			(layer "F.Fab")
			(effects
				(font
					(size 0.7 0.7)
					(thickness 0.15)
				)
				(justify left bottom)
			)
		)
		(fp_text user "License: Apache-2.0"
			(at -0.95 5.169 0)
			(layer "F.Fab")
			(effects
				(font
					(size 0.7 0.7)
					(thickness 0.15)
				)
				(justify left bottom)
			)
		)
		(pad "1" smd roundrect
			(at -0.48 0)
			(size 0.59 0.64)
			(layers "F.Cu" "F.Mask" "F.Paste")
			(roundrect_rratio 0.25)
			(net 473 "Net-(D302-A)")
			(pintype "passive")
		)
		(pad "2" smd roundrect
			(at 0.48 0)
			(size 0.59 0.64)
			(layers "F.Cu" "F.Mask" "F.Paste")
			(roundrect_rratio 0.25)
			(net 43 "VCC")
			(pintype "passive")
		)
	)
	(footprint "antmicro-footprints:TP_SMD_0.75mm"
		(layer "F.Cu")
		(at 141.107962 129.7765 180)
		(property "Reference" "TP207"
			(at 0.32 -0.74 180)
			(layer "F.SilkS")
			(effects
				(font
					(size 0.7 0.7)
					(thickness 0.15)
				)
				(justify right bottom)
			)
		)
		(property "Value" "TP_0.75mm_SMD"
			(at 0 1.2 0)
			(layer "F.Fab")
			(effects
				(font
					(size 0.7 0.7)
					(thickness 0.15)
				)
				(justify right bottom)
			)
		)
		(property "Author" "Antmicro"
			(at 0 0 180)
			(unlocked yes)
			(layer "F.Fab")
			(hide yes)
			(effects
				(font
					(size 1 1)
					(thickness 0.15)
				)
			)
		)
		(property "License" "Apache-2.0"
			(at 0 0 180)
			(unlocked yes)
			(layer "F.Fab")
			(hide yes)
			(effects
				(font
					(size 1 1)
					(thickness 0.15)
				)
			)
		)
		(property "MPN" ""
			(at 0 0 180)
			(unlocked yes)
			(layer "F.Fab")
			(hide yes)
			(effects
				(font
					(size 1 1)
					(thickness 0.15)
				)
			)
		)
		(property "Manufacturer" ""
			(at 0 0 180)
			(unlocked yes)
			(layer "F.Fab")
			(hide yes)
			(effects
				(font
					(size 1 1)
					(thickness 0.15)
				)
			)
		)
		(sheetname "/Compute module/")
		(sheetfile "compute-module.kicad_sch")
		(attr exclude_from_pos_files exclude_from_bom)
		(fp_circle
			(center 0 0)
			(end 0.475 0)
			(stroke
				(width 0.05)
				(type default)
			)
			(fill no)
			(layer "F.CrtYd")
		)
		(fp_text user "Author: Antmicro"
			(at -0.4 3.901 180)
			(layer "F.Fab")
			(effects
				(font
					(size 0.7 0.7)
					(thickness 0.15)
				)
				(justify left bottom)
			)
		)
		(fp_text user "License: Apache-2.0"
			(at -0.4 5.101 180)
			(layer "F.Fab")
			(effects
				(font
					(size 0.7 0.7)
					(thickness 0.15)
				)
				(justify left bottom)
			)
		)
		(fp_text user "${REFERENCE}"
			(at -0.4 2.7 180)
			(layer "F.Fab")
			(effects
				(font
					(size 0.7 0.7)
					(thickness 0.15)
				)
				(justify left bottom)
			)
		)
		(pad "1" smd circle
			(at 0 0 180)
			(size 0.75 0.75)
			(layers "F.Cu" "F.Mask")
			(net 250 "/Compute module/~{RPi_BOOT}")
			(pinfunction "1")
			(pintype "passive")
		)
	)
	(footprint "antmicro-footprints:R_0402_1005Metric"
		(layer "F.Cu")
		(at 83.187962 161.5165 180)
		(descr "Resistor SMD 0402")
		(tags "resistor SMD 0402")
		(property "Reference" "R201"
			(at -3.83 -0.475 0)
			(layer "F.SilkS")
			(effects
				(font
					(size 0.7 0.7)
					(thickness 0.15)
				)
				(justify right bottom)
			)
		)
		(property "Value" "R_0R_0402"
			(at -1.011843 1.772047 0)
			(layer "F.Fab")
			(effects
				(font
					(size 0.7 0.7)
					(thickness 0.15)
				)
				(justify right bottom)
			)
		)
		(property "Datasheet" "https://industrial.panasonic.com/cdbs/www-data/pdf/RDA0000/AOA0000C301.pdf"
			(at 0 0 180)
			(layer "F.Fab")
			(hide yes)
			(effects
				(font
					(size 1.27 1.27)
					(thickness 0.15)
				)
			)
		)
		(property "Manufacturer" "Panasonic"
			(at 0 0 180)
			(unlocked yes)
			(layer "F.Fab")
			(hide yes)
			(effects
				(font
					(size 1 1)
					(thickness 0.15)
				)
			)
		)
		(property "MPN" "ERJ2GE0R00X"
			(at 0 0 180)
			(unlocked yes)
			(layer "F.Fab")
			(hide yes)
			(effects
				(font
					(size 1 1)
					(thickness 0.15)
				)
			)
		)
		(property "Val" "0R"
			(at 0 0 180)
			(unlocked yes)
			(layer "F.Fab")
			(hide yes)
			(effects
				(font
					(size 1 1)
					(thickness 0.15)
				)
			)
		)
		(property "License" "Apache-2.0"
			(at 0 0 180)
			(unlocked yes)
			(layer "F.Fab")
			(hide yes)
			(effects
				(font
					(size 1 1)
					(thickness 0.15)
				)
			)
		)
		(property "Author" "Antmicro"
			(at 0 0 180)
			(unlocked yes)
			(layer "F.Fab")
			(hide yes)
			(effects
				(font
					(size 1 1)
					(thickness 0.15)
				)
			)
		)
		(property "Tolerance" "~"
			(at 0 0 180)
			(unlocked yes)
			(layer "F.Fab")
			(hide yes)
			(effects
				(font
					(size 1 1)
					(thickness 0.15)
				)
			)
		)
		(property "Current" "1A"
			(at 0 0 180)
			(unlocked yes)
			(layer "F.Fab")
			(hide yes)
			(effects
				(font
					(size 1 1)
					(thickness 0.15)
				)
			)
		)
		(sheetname "/Compute module/")
		(sheetfile "compute-module.kicad_sch")
		(attr smd)
		(fp_rect
			(start -0.925 -0.47)
			(end 0.925 0.47)
			(stroke
				(width 0.05)
				(type default)
			)
			(fill no)
			(layer "F.CrtYd")
		)
		(fp_rect
			(start -0.5 -0.25)
			(end 0.5 0.25)
			(stroke
				(width 0.15)
				(type solid)
			)
			(fill no)
			(layer "F.Fab")
		)
		(fp_text user "${REFERENCE}"
			(at -0.95 3.168 180)
			(layer "F.Fab")
			(effects
				(font
					(size 0.7 0.7)
					(thickness 0.15)
				)
				(justify left bottom)
			)
		)
		(fp_text user "Author: Antmicro"
			(at -0.95 4.169 180)
			(layer "F.Fab")
			(effects
				(font
					(size 0.7 0.7)
					(thickness 0.15)
				)
				(justify left bottom)
			)
		)
		(fp_text user "License: Apache-2.0"
			(at -0.95 5.169 180)
			(layer "F.Fab")
			(effects
				(font
					(size 0.7 0.7)
					(thickness 0.15)
				)
				(justify left bottom)
			)
		)
		(pad "1" smd roundrect
			(at -0.48 0 180)
			(size 0.59 0.64)
			(layers "F.Cu" "F.Mask" "F.Paste")
			(roundrect_rratio 0.25)
			(net 18 "V_{IO}")
			(pintype "passive")
		)
		(pad "2" smd roundrect
			(at 0.48 0 180)
			(size 0.59 0.64)
			(layers "F.Cu" "F.Mask" "F.Paste")
			(roundrect_rratio 0.25)
			(net 132 "/Compute module/CM4_3V3")
			(pintype "passive")
		)
	)
	(footprint "antmicro-footprints:SOD-123FL"
		(layer "F.Cu")
		(at 40.547962 121.0465 180)
		(property "Reference" "D301"
			(at 2.69 -2.11 180)
			(layer "F.SilkS")
			(effects
				(font
					(size 0.7 0.7)
					(thickness 0.15)
				)
				(justify left bottom)
			)
		)
		(property "Value" "SMF4L15A"
			(at 0 1.967 180)
			(layer "F.Fab")
			(effects
				(font
					(size 0.7 0.7)
					(thickness 0.15)
				)
				(justify left bottom)
			)
		)
		(property "Datasheet" "https://www.littelfuse.com/media?resourcetype=datasheets&itemid=d2ba8fab-1de3-4176-8530-f36ecb0b8799&filename=smf4l"
			(at 0 0 180)
			(layer "F.Fab")
			(hide yes)
			(effects
				(font
					(size 1.27 1.27)
					(thickness 0.15)
				)
			)
		)
		(property "Manufacturer" "Littelfuse"
			(at 0 0 180)
			(unlocked yes)
			(layer "F.Fab")
			(hide yes)
			(effects
				(font
					(size 1 1)
					(thickness 0.15)
				)
			)
		)
		(property "MPN" "SMF4L15A"
			(at 0 0 180)
			(unlocked yes)
			(layer "F.Fab")
			(hide yes)
			(effects
				(font
					(size 1 1)
					(thickness 0.15)
				)
			)
		)
		(property "Author" "Antmicro"
			(at 0 0 180)
			(unlocked yes)
			(layer "F.Fab")
			(hide yes)
			(effects
				(font
					(size 1 1)
					(thickness 0.15)
				)
			)
		)
		(property "License" "Apache-2.0"
			(at 0 0 180)
			(unlocked yes)
			(layer "F.Fab")
			(hide yes)
			(effects
				(font
					(size 1 1)
					(thickness 0.15)
				)
			)
		)
		(sheetname "/Supply/")
		(sheetfile "supply.kicad_sch")
		(attr smd)
		(fp_line
			(start 0 -1.1)
			(end -2.3 -1.1)
			(stroke
				(width 0.15)
				(type solid)
			)
			(layer "F.SilkS")
		)
		(fp_line
			(start -2.3 1.1)
			(end 0 1.1)
			(stroke
				(width 0.15)
				(type solid)
			)
			(layer "F.SilkS")
		)
		(fp_line
			(start -2.3 -1.1)
			(end -2.3 1.1)
			(stroke
				(width 0.15)
				(type solid)
			)
			(layer "F.SilkS")
		)
		(fp_rect
			(start -2.35 -1.125)
			(end 2.35 1.125)
			(stroke
				(width 0.05)
				(type solid)
			)
			(fill no)
			(layer "F.CrtYd")
		)
		(fp_rect
			(start -0.775 -0.875)
			(end -0.525 0.875)
			(stroke
				(width 0.15)
				(type solid)
			)
			(fill yes)
			(layer "F.Fab")
		)
		(fp_rect
			(start -1.825 -0.875)
			(end 1.824 0.873)
			(stroke
				(width 0.15)
				(type solid)
			)
			(fill no)
			(layer "F.Fab")
		)
		(fp_text user "License: Apache-2.0"
			(at -2.406 6.368 180)
			(layer "F.Fab")
			(effects
				(font
					(size 0.7 0.7)
					(thickness 0.15)
				)
				(justify left bottom)
			)
		)
		(fp_text user "Author: Antmicro"
			(at -2.406 5.168 180)
			(layer "F.Fab")
			(effects
				(font
					(size 0.7 0.7)
					(thickness 0.15)
				)
				(justify left bottom)
			)
		)
		(fp_text user "${REFERENCE}"
			(at -2.406 3.967 180)
			(layer "F.Fab")
			(effects
				(font
					(size 0.7 0.7)
					(thickness 0.15)
				)
				(justify left bottom)
			)
		)
		(pad "1" smd roundrect
			(at -1.43 0 180)
			(size 1.34 1.8)
			(layers "F.Cu" "F.Mask" "F.Paste")
			(roundrect_rratio 0.14)
			(net 472 "Net-(D301-C)")
			(pinfunction "C")
			(pintype "passive")
		)
		(pad "2" smd roundrect
			(at 1.429 0 180)
			(size 1.34 1.8)
			(layers "F.Cu" "F.Mask" "F.Paste")
			(roundrect_rratio 0.14)
			(net 3 "GND")
			(pinfunction "A")
			(pintype "passive")
		)
	)
	(footprint "antmicro-footprints:TP_SMD_0.75mm"
		(layer "F.Cu")
		(at 39.3 165.85)
		(property "Reference" "TP306"
			(at 0.45 3.9 90)
			(layer "F.SilkS")
			(effects
				(font
					(size 0.7 0.7)
					(thickness 0.15)
				)
				(justify left bottom)
			)
		)
		(property "Value" "TP_0.75mm_SMD"
			(at 0 1.2 0)
			(layer "F.Fab")
			(effects
				(font
					(size 0.7 0.7)
					(thickness 0.15)
				)
				(justify left bottom)
			)
		)
		(property "MPN" ""
			(at 0 0 0)
			(unlocked yes)
			(layer "F.Fab")
			(hide yes)
			(effects
				(font
					(size 1 1)
					(thickness 0.15)
				)
			)
		)
		(property "Manufacturer" ""
			(at 0 0 0)
			(unlocked yes)
			(layer "F.Fab")
			(hide yes)
			(effects
				(font
					(size 1 1)
					(thickness 0.15)
				)
			)
		)
		(property "Author" "Antmicro"
			(at 0 0 0)
			(unlocked yes)
			(layer "F.Fab")
			(hide yes)
			(effects
				(font
					(size 1 1)
					(thickness 0.15)
				)
			)
		)
		(property "License" "Apache-2.0"
			(at 0 0 0)
			(unlocked yes)
			(layer "F.Fab")
			(hide yes)
			(effects
				(font
					(size 1 1)
					(thickness 0.15)
				)
			)
		)
		(sheetname "/Supply/")
		(sheetfile "supply.kicad_sch")
		(attr exclude_from_pos_files exclude_from_bom)
		(fp_circle
			(center 0 0)
			(end 0.475 0)
			(stroke
				(width 0.05)
				(type default)
			)
			(fill no)
			(layer "F.CrtYd")
		)
		(fp_text user "License: Apache-2.0"
			(at -0.4 5.101 0)
			(layer "F.Fab")
			(effects
				(font
					(size 0.7 0.7)
					(thickness 0.15)
				)
				(justify left bottom)
			)
		)
		(fp_text user "${REFERENCE}"
			(at -0.4 2.7 0)
			(layer "F.Fab")
			(effects
				(font
					(size 0.7 0.7)
					(thickness 0.15)
				)
				(justify left bottom)
			)
		)
		(fp_text user "Author: Antmicro"
			(at -0.4 3.901 0)
			(layer "F.Fab")
			(effects
				(font
					(size 0.7 0.7)
					(thickness 0.15)
				)
				(justify left bottom)
			)
		)
		(pad "1" smd circle
			(at 0 0)
			(size 0.75 0.75)
			(layers "F.Cu" "F.Mask")
			(net 472 "Net-(D301-C)")
			(pinfunction "1")
			(pintype "passive")
		)
	)
	(footprint "antmicro-footprints:R_0402_1005Metric"
		(layer "F.Cu")
		(at 133.387962 154.5665)
		(descr "Resistor SMD 0402")
		(tags "resistor SMD 0402")
		(property "Reference" "R607"
			(at -2.687962 -0.6165 0)
			(layer "F.SilkS")
			(effects
				(font
					(size 0.7 0.7)
					(thickness 0.15)
				)
				(justify left bottom)
			)
		)
		(property "Value" "R_470R_0402"
			(at -1.011843 1.772047 0)
			(layer "F.Fab")
			(effects
				(font
					(size 0.7 0.7)
					(thickness 0.15)
				)
				(justify left bottom)
			)
		)
		(property "Datasheet" "https://www.bourns.com/docs/product-datasheets/cr.pdf"
			(at 0 0 0)
			(layer "F.Fab")
			(hide yes)
			(effects
				(font
					(size 1.27 1.27)
					(thickness 0.15)
				)
			)
		)
		(property "Manufacturer" "Bourns"
			(at 0 0 0)
			(unlocked yes)
			(layer "F.Fab")
			(hide yes)
			(effects
				(font
					(size 1 1)
					(thickness 0.15)
				)
			)
		)
		(property "MPN" "CR0402-FX-4700GLF"
			(at 0 0 0)
			(unlocked yes)
			(layer "F.Fab")
			(hide yes)
			(effects
				(font
					(size 1 1)
					(thickness 0.15)
				)
			)
		)
		(property "Val" "470R"
			(at 0 0 0)
			(unlocked yes)
			(layer "F.Fab")
			(hide yes)
			(effects
				(font
					(size 1 1)
					(thickness 0.15)
				)
			)
		)
		(property "License" "Apache-2.0"
			(at 0 0 0)
			(unlocked yes)
			(layer "F.Fab")
			(hide yes)
			(effects
				(font
					(size 1 1)
					(thickness 0.15)
				)
			)
		)
		(property "Author" "Antmicro"
			(at 0 0 0)
			(unlocked yes)
			(layer "F.Fab")
			(hide yes)
			(effects
				(font
					(size 1 1)
					(thickness 0.15)
				)
			)
		)
		(property "Tolerance" "1%"
			(at 0 0 0)
			(unlocked yes)
			(layer "F.Fab")
			(hide yes)
			(effects
				(font
					(size 1 1)
					(thickness 0.15)
				)
			)
		)
		(sheetname "/CSI/")
		(sheetfile "csi.kicad_sch")
		(attr smd)
		(fp_rect
			(start -0.925 -0.47)
			(end 0.925 0.47)
			(stroke
				(width 0.05)
				(type default)
			)
			(fill no)
			(layer "F.CrtYd")
		)
		(fp_rect
			(start -0.5 -0.25)
			(end 0.5 0.25)
			(stroke
				(width 0.15)
				(type solid)
			)
			(fill no)
			(layer "F.Fab")
		)
		(fp_text user "Author: Antmicro"
			(at -0.95 4.169 0)
			(layer "F.Fab")
			(effects
				(font
					(size 0.7 0.7)
					(thickness 0.15)
				)
				(justify left bottom)
			)
		)
		(fp_text user "License: Apache-2.0"
			(at -0.95 5.169 0)
			(layer "F.Fab")
			(effects
				(font
					(size 0.7 0.7)
					(thickness 0.15)
				)
				(justify left bottom)
			)
		)
		(fp_text user "${REFERENCE}"
			(at -0.95 3.168 0)
			(layer "F.Fab")
			(effects
				(font
					(size 0.7 0.7)
					(thickness 0.15)
				)
				(justify left bottom)
			)
		)
		(pad "1" smd roundrect
			(at -0.48 0)
			(size 0.59 0.64)
			(layers "F.Cu" "F.Mask" "F.Paste")
			(roundrect_rratio 0.25)
			(net 480 "Net-(D602-A)")
			(pintype "passive")
		)
		(pad "2" smd roundrect
			(at 0.48 0)
			(size 0.59 0.64)
			(layers "F.Cu" "F.Mask" "F.Paste")
			(roundrect_rratio 0.25)
			(net 19 "/CSI/CSI_3V3")
			(pintype "passive")
		)
	)
	(footprint "antmicro-footprints:C_0402_1005Metric"
		(layer "F.Cu")
		(at 87.467962 146.5665 -90)
		(descr "Capacitor SMD 0402")
		(tags "capacitor SMD 0402")
		(property "Reference" "C926"
			(at 0.7 -0.65 90)
			(layer "F.SilkS")
			(effects
				(font
					(size 0.7 0.7)
					(thickness 0.15)
				)
				(justify right bottom)
			)
		)
		(property "Value" "C_18p_0402"
			(at -1.022927 2.155213 90)
			(layer "F.Fab")
			(effects
				(font
					(size 0.7 0.7)
					(thickness 0.15)
				)
				(justify right bottom)
			)
		)
		(property "Datasheet" "https://product.samsungsem.com/mlcc/CL05C180JB51PN.do"
			(at 0 0 270)
			(layer "F.Fab")
			(hide yes)
			(effects
				(font
					(size 1.27 1.27)
					(thickness 0.15)
				)
			)
		)
		(property "Manufacturer" "Samsung Electro-Mechanics"
			(at 0 0 270)
			(unlocked yes)
			(layer "F.Fab")
			(hide yes)
			(effects
				(font
					(size 1 1)
					(thickness 0.15)
				)
			)
		)
		(property "MPN" "CL05C180JB51PNC"
			(at 0 0 270)
			(unlocked yes)
			(layer "F.Fab")
			(hide yes)
			(effects
				(font
					(size 1 1)
					(thickness 0.15)
				)
			)
		)
		(property "Val" "18p"
			(at 0 0 270)
			(unlocked yes)
			(layer "F.Fab")
			(hide yes)
			(effects
				(font
					(size 1 1)
					(thickness 0.15)
				)
			)
		)
		(property "License" "Apache-2.0"
			(at 0 0 270)
			(unlocked yes)
			(layer "F.Fab")
			(hide yes)
			(effects
				(font
					(size 1 1)
					(thickness 0.15)
				)
			)
		)
		(property "Author" "Antmicro"
			(at 0 0 270)
			(unlocked yes)
			(layer "F.Fab")
			(hide yes)
			(effects
				(font
					(size 1 1)
					(thickness 0.15)
				)
			)
		)
		(property "Voltage" ""
			(at 0 0 270)
			(unlocked yes)
			(layer "F.Fab")
			(hide yes)
			(effects
				(font
					(size 1 1)
					(thickness 0.15)
				)
			)
		)
		(property "Dielectric" ""
			(at 0 0 270)
			(unlocked yes)
			(layer "F.Fab")
			(hide yes)
			(effects
				(font
					(size 1 1)
					(thickness 0.15)
				)
			)
		)
		(sheetname "/USB/")
		(sheetfile "usb.kicad_sch")
		(attr smd)
		(fp_rect
			(start -0.925 -0.47)
			(end 0.925 0.47)
			(stroke
				(width 0.05)
				(type default)
			)
			(fill no)
			(layer "F.CrtYd")
		)
		(fp_line
			(start -0.494 0.248)
			(end -0.494 -0.25)
			(stroke
				(width 0.15)
				(type solid)
			)
			(layer "F.Fab")
		)
		(fp_line
			(start 0.504 0.248)
			(end -0.494 0.248)
			(stroke
				(width 0.15)
				(type solid)
			)
			(layer "F.Fab")
		)
		(fp_line
			(start -0.494 -0.25)
			(end 0.504 -0.25)
			(stroke
				(width 0.15)
				(type solid)
			)
			(layer "F.Fab")
		)
		(fp_line
			(start 0.504 -0.25)
			(end 0.504 0.248)
			(stroke
				(width 0.15)
				(type solid)
			)
			(layer "F.Fab")
		)
		(fp_text user "License: Apache-2.0"
			(at -0.939 5.799 270)
			(layer "F.Fab")
			(effects
				(font
					(size 0.7 0.7)
					(thickness 0.15)
				)
				(justify left bottom)
			)
		)
		(fp_text user "${REFERENCE}"
			(at -0.939 4.599 270)
			(layer "F.Fab")
			(effects
				(font
					(size 0.7 0.7)
					(thickness 0.15)
				)
				(justify left bottom)
			)
		)
		(fp_text user "Author: Antmicro"
			(at -0.939 3.399 270)
			(layer "F.Fab")
			(effects
				(font
					(size 0.7 0.7)
					(thickness 0.15)
				)
				(justify left bottom)
			)
		)
		(pad "1" smd roundrect
			(at -0.48 0 270)
			(size 0.59 0.64)
			(layers "F.Cu" "F.Mask" "F.Paste")
			(roundrect_rratio 0.25)
			(net 114 "Net-(U905-OSCI)")
			(pintype "passive")
		)
		(pad "2" smd roundrect
			(at 0.48 0 270)
			(size 0.59 0.64)
			(layers "F.Cu" "F.Mask" "F.Paste")
			(roundrect_rratio 0.25)
			(net 3 "GND")
			(pintype "passive")
		)
	)
	(footprint "antmicro-footprints:R_0603_1608Metric"
		(layer "F.Cu")
		(at 50.557962 125.2365)
		(descr "Resistor SMD 0603")
		(tags "resistor SMD 0603")
		(property "Reference" "R404"
			(at -1.39 -0.82 0)
			(layer "F.SilkS")
			(effects
				(font
					(size 0.7 0.7)
					(thickness 0.15)
				)
				(justify left bottom)
			)
		)
		(property "Value" "R_63R4_0603"
			(at 0 1.6 0)
			(layer "F.Fab")
			(effects
				(font
					(size 0.7 0.7)
					(thickness 0.15)
				)
				(justify left bottom)
			)
		)
		(property "Datasheet" "https://www.bourns.com/docs/product-datasheets/cr.pdf"
			(at 0 0 0)
			(layer "F.Fab")
			(hide yes)
			(effects
				(font
					(size 1.27 1.27)
					(thickness 0.15)
				)
			)
		)
		(property "Manufacturer" "Bourns"
			(at 0 0 0)
			(unlocked yes)
			(layer "F.Fab")
			(hide yes)
			(effects
				(font
					(size 1 1)
					(thickness 0.15)
				)
			)
		)
		(property "MPN" "CR0603-FX-63R4ELF"
			(at 0 0 0)
			(unlocked yes)
			(layer "F.Fab")
			(hide yes)
			(effects
				(font
					(size 1 1)
					(thickness 0.15)
				)
			)
		)
		(property "Val" "63R4"
			(at 0 0 0)
			(unlocked yes)
			(layer "F.Fab")
			(hide yes)
			(effects
				(font
					(size 1 1)
					(thickness 0.15)
				)
			)
		)
		(property "License" "Apache-2.0"
			(at 0 0 0)
			(unlocked yes)
			(layer "F.Fab")
			(hide yes)
			(effects
				(font
					(size 1 1)
					(thickness 0.15)
				)
			)
		)
		(property "Author" "Antmicro"
			(at 0 0 0)
			(unlocked yes)
			(layer "F.Fab")
			(hide yes)
			(effects
				(font
					(size 1 1)
					(thickness 0.15)
				)
			)
		)
		(property "Tolerance" "1%"
			(at 0 0 0)
			(unlocked yes)
			(layer "F.Fab")
			(hide yes)
			(effects
				(font
					(size 1 1)
					(thickness 0.15)
				)
			)
		)
		(sheetname "/Ethernet/")
		(sheetfile "ethernet.kicad_sch")
		(attr smd)
		(fp_line
			(start -0.15 -0.4)
			(end 0.15 -0.4)
			(stroke
				(width 0.15)
				(type solid)
			)
			(layer "F.SilkS")
		)
		(fp_line
			(start -0.15 0.4)
			(end 0.15 0.4)
			(stroke
				(width 0.15)
				(type solid)
			)
			(layer "F.SilkS")
		)
		(fp_rect
			(start -1.25 -0.65)
			(end 1.25 0.65)
			(stroke
				(width 0.05)
				(type solid)
			)
			(fill no)
			(layer "F.CrtYd")
		)
		(fp_rect
			(start -0.8 -0.4)
			(end 0.8 0.4)
			(stroke
				(width 0.15)
				(type solid)
			)
			(fill no)
			(layer "F.Fab")
		)
		(fp_text user "Author: Antmicro"
			(at -1.25 4.9 0)
			(layer "F.Fab")
			(effects
				(font
					(size 0.7 0.7)
					(thickness 0.15)
				)
				(justify left bottom)
			)
		)
		(fp_text user "${REFERENCE}"
			(at -1.25 3.898 0)
			(layer "F.Fab")
			(effects
				(font
					(size 0.7 0.7)
					(thickness 0.15)
				)
				(justify left bottom)
			)
		)
		(fp_text user "License: Apache-2.0"
			(at -1.25 5.9 0)
			(layer "F.Fab")
			(effects
				(font
					(size 0.7 0.7)
					(thickness 0.15)
				)
				(justify left bottom)
			)
		)
		(pad "1" smd roundrect
			(at -0.7 0)
			(size 0.8 1)
			(layers "F.Cu" "F.Mask" "F.Paste")
			(roundrect_rratio 0.2)
			(net 90 "/Ethernet/VSS")
			(pintype "passive")
		)
		(pad "2" smd roundrect
			(at 0.7 0)
			(size 0.8 1)
			(layers "F.Cu" "F.Mask" "F.Paste")
			(roundrect_rratio 0.2)
			(net 359 "/Ethernet/CLSA")
			(pintype "passive")
		)
	)
	(footprint "antmicro-footprints:C_0402_1005Metric"
		(layer "F.Cu")
		(at 89.667962 131.4765 180)
		(descr "Capacitor SMD 0402")
		(tags "capacitor SMD 0402")
		(property "Reference" "C910"
			(at -1.39 4.060736 0)
			(layer "F.SilkS")
			(effects
				(font
					(size 0.7 0.7)
					(thickness 0.15)
				)
				(justify right bottom)
			)
		)
		(property "Value" "C_100n_0402"
			(at -1.022927 2.155213 0)
			(layer "F.Fab")
			(effects
				(font
					(size 0.7 0.7)
					(thickness 0.15)
				)
				(justify right bottom)
			)
		)
		(property "Datasheet" "https://www.murata.com/products/productdetail?partno=GRM155R61H104KE14%23"
			(at 0 0 180)
			(layer "F.Fab")
			(hide yes)
			(effects
				(font
					(size 1.27 1.27)
					(thickness 0.15)
				)
			)
		)
		(property "Manufacturer" "Murata"
			(at 0 0 180)
			(unlocked yes)
			(layer "F.Fab")
			(hide yes)
			(effects
				(font
					(size 1 1)
					(thickness 0.15)
				)
			)
		)
		(property "MPN" "GRM155R61H104KE14D"
			(at 0 0 180)
			(unlocked yes)
			(layer "F.Fab")
			(hide yes)
			(effects
				(font
					(size 1 1)
					(thickness 0.15)
				)
			)
		)
		(property "Val" "100n"
			(at 0 0 180)
			(unlocked yes)
			(layer "F.Fab")
			(hide yes)
			(effects
				(font
					(size 1 1)
					(thickness 0.15)
				)
			)
		)
		(property "License" "Apache-2.0"
			(at 0 0 180)
			(unlocked yes)
			(layer "F.Fab")
			(hide yes)
			(effects
				(font
					(size 1 1)
					(thickness 0.15)
				)
			)
		)
		(property "Author" "Antmicro"
			(at 0 0 180)
			(unlocked yes)
			(layer "F.Fab")
			(hide yes)
			(effects
				(font
					(size 1 1)
					(thickness 0.15)
				)
			)
		)
		(property "Voltage" "50V"
			(at 0 0 180)
			(unlocked yes)
			(layer "F.Fab")
			(hide yes)
			(effects
				(font
					(size 1 1)
					(thickness 0.15)
				)
			)
		)
		(property "Dielectric" "X5R"
			(at 0 0 180)
			(unlocked yes)
			(layer "F.Fab")
			(hide yes)
			(effects
				(font
					(size 1 1)
					(thickness 0.15)
				)
			)
		)
		(sheetname "/USB/")
		(sheetfile "usb.kicad_sch")
		(attr smd)
		(fp_rect
			(start -0.925 -0.47)
			(end 0.925 0.47)
			(stroke
				(width 0.05)
				(type default)
			)
			(fill no)
			(layer "F.CrtYd")
		)
		(fp_line
			(start 0.504 0.248)
			(end -0.494 0.248)
			(stroke
				(width 0.15)
				(type solid)
			)
			(layer "F.Fab")
		)
		(fp_line
			(start 0.504 -0.25)
			(end 0.504 0.248)
			(stroke
				(width 0.15)
				(type solid)
			)
			(layer "F.Fab")
		)
		(fp_line
			(start -0.494 0.248)
			(end -0.494 -0.25)
			(stroke
				(width 0.15)
				(type solid)
			)
			(layer "F.Fab")
		)
		(fp_line
			(start -0.494 -0.25)
			(end 0.504 -0.25)
			(stroke
				(width 0.15)
				(type solid)
			)
			(layer "F.Fab")
		)
		(fp_text user "License: Apache-2.0"
			(at -0.939 5.799 180)
			(layer "F.Fab")
			(effects
				(font
					(size 0.7 0.7)
					(thickness 0.15)
				)
				(justify left bottom)
			)
		)
		(fp_text user "Author: Antmicro"
			(at -0.939 3.399 180)
			(layer "F.Fab")
			(effects
				(font
					(size 0.7 0.7)
					(thickness 0.15)
				)
				(justify left bottom)
			)
		)
		(fp_text user "${REFERENCE}"
			(at -0.939 4.599 180)
			(layer "F.Fab")
			(effects
				(font
					(size 0.7 0.7)
					(thickness 0.15)
				)
				(justify left bottom)
			)
		)
		(pad "1" smd roundrect
			(at -0.48 0 180)
			(size 0.59 0.64)
			(layers "F.Cu" "F.Mask" "F.Paste")
			(roundrect_rratio 0.25)
			(net 211 "/USB/VCC_PD")
			(pintype "passive")
		)
		(pad "2" smd roundrect
			(at 0.48 0 180)
			(size 0.59 0.64)
			(layers "F.Cu" "F.Mask" "F.Paste")
			(roundrect_rratio 0.25)
			(net 3 "GND")
			(pintype "passive")
		)
	)
	(footprint "antmicro-footprints:R_0402_1005Metric"
		(layer "F.Cu")
		(at 88.792962 122.1165)
		(descr "Resistor SMD 0402")
		(tags "resistor SMD 0402")
		(property "Reference" "R901"
			(at -1.175 1.3 0)
			(layer "F.SilkS")
			(effects
				(font
					(size 0.7 0.7)
					(thickness 0.15)
				)
				(justify left bottom)
			)
		)
		(property "Value" "R_1k_0402"
			(at -1.011843 1.772047 0)
			(layer "F.Fab")
			(effects
				(font
					(size 0.7 0.7)
					(thickness 0.15)
				)
				(justify left bottom)
			)
		)
		(property "Datasheet" "https://www.bourns.com/docs/product-datasheets/cr.pdf"
			(at 0 0 0)
			(layer "F.Fab")
			(hide yes)
			(effects
				(font
					(size 1.27 1.27)
					(thickness 0.15)
				)
			)
		)
		(property "MPN" "CR0402-FX-1001GLF"
			(at 0 0 0)
			(unlocked yes)
			(layer "F.Fab")
			(hide yes)
			(effects
				(font
					(size 1 1)
					(thickness 0.15)
				)
			)
		)
		(property "Manufacturer" "Bourns"
			(at 0 0 0)
			(unlocked yes)
			(layer "F.Fab")
			(hide yes)
			(effects
				(font
					(size 1 1)
					(thickness 0.15)
				)
			)
		)
		(property "License" "Apache-2.0"
			(at 0 0 0)
			(unlocked yes)
			(layer "F.Fab")
			(hide yes)
			(effects
				(font
					(size 1 1)
					(thickness 0.15)
				)
			)
		)
		(property "Author" "Antmicro"
			(at 0 0 0)
			(unlocked yes)
			(layer "F.Fab")
			(hide yes)
			(effects
				(font
					(size 1 1)
					(thickness 0.15)
				)
			)
		)
		(property "Val" "1k"
			(at 0 0 0)
			(unlocked yes)
			(layer "F.Fab")
			(hide yes)
			(effects
				(font
					(size 1 1)
					(thickness 0.15)
				)
			)
		)
		(property "Tolerance" "1%"
			(at 0 0 0)
			(unlocked yes)
			(layer "F.Fab")
			(hide yes)
			(effects
				(font
					(size 1 1)
					(thickness 0.15)
				)
			)
		)
		(sheetname "/USB/")
		(sheetfile "usb.kicad_sch")
		(attr smd)
		(fp_rect
			(start -0.925 -0.47)
			(end 0.925 0.47)
			(stroke
				(width 0.05)
				(type default)
			)
			(fill no)
			(layer "F.CrtYd")
		)
		(fp_rect
			(start -0.5 -0.25)
			(end 0.5 0.25)
			(stroke
				(width 0.15)
				(type solid)
			)
			(fill no)
			(layer "F.Fab")
		)
		(fp_text user "License: Apache-2.0"
			(at -0.95 5.169 0)
			(layer "F.Fab")
			(effects
				(font
					(size 0.7 0.7)
					(thickness 0.15)
				)
				(justify left bottom)
			)
		)
		(fp_text user "Author: Antmicro"
			(at -0.95 4.169 0)
			(layer "F.Fab")
			(effects
				(font
					(size 0.7 0.7)
					(thickness 0.15)
				)
				(justify left bottom)
			)
		)
		(fp_text user "${REFERENCE}"
			(at -0.95 3.168 0)
			(layer "F.Fab")
			(effects
				(font
					(size 0.7 0.7)
					(thickness 0.15)
				)
				(justify left bottom)
			)
		)
		(pad "1" smd roundrect
			(at -0.48 0)
			(size 0.59 0.64)
			(layers "F.Cu" "F.Mask" "F.Paste")
			(roundrect_rratio 0.25)
			(net 482 "Net-(D905-A)")
			(pintype "passive")
		)
		(pad "2" smd roundrect
			(at 0.48 0)
			(size 0.59 0.64)
			(layers "F.Cu" "F.Mask" "F.Paste")
			(roundrect_rratio 0.25)
			(net 24 "/Compute module/USBA_VBUS")
			(pintype "passive")
		)
	)
	(footprint "antmicro-footprints:R_0402_1005Metric"
		(layer "F.Cu")
		(at 91.242962 155.6415 -90)
		(descr "Resistor SMD 0402")
		(tags "resistor SMD 0402")
		(property "Reference" "R235"
			(at -1.535 0.395 90)
			(layer "F.SilkS")
			(effects
				(font
					(size 0.7 0.7)
					(thickness 0.15)
				)
				(justify right bottom)
			)
		)
		(property "Value" "R_10k_0402"
			(at -1.011843 1.772047 90)
			(layer "F.Fab")
			(effects
				(font
					(size 0.7 0.7)
					(thickness 0.15)
				)
				(justify right bottom)
			)
		)
		(property "Datasheet" "https://www.bourns.com/docs/product-datasheets/cr.pdf"
			(at 0 0 270)
			(layer "F.Fab")
			(hide yes)
			(effects
				(font
					(size 1.27 1.27)
					(thickness 0.15)
				)
			)
		)
		(property "MPN" "CR0402-FX-1002GLF"
			(at 0 0 270)
			(unlocked yes)
			(layer "F.Fab")
			(hide yes)
			(effects
				(font
					(size 1 1)
					(thickness 0.15)
				)
			)
		)
		(property "Manufacturer" "Bourns"
			(at 0 0 270)
			(unlocked yes)
			(layer "F.Fab")
			(hide yes)
			(effects
				(font
					(size 1 1)
					(thickness 0.15)
				)
			)
		)
		(property "License" "Apache-2.0"
			(at 0 0 270)
			(unlocked yes)
			(layer "F.Fab")
			(hide yes)
			(effects
				(font
					(size 1 1)
					(thickness 0.15)
				)
			)
		)
		(property "Author" "Antmicro"
			(at 0 0 270)
			(unlocked yes)
			(layer "F.Fab")
			(hide yes)
			(effects
				(font
					(size 1 1)
					(thickness 0.15)
				)
			)
		)
		(property "Val" "10k"
			(at 0 0 270)
			(unlocked yes)
			(layer "F.Fab")
			(hide yes)
			(effects
				(font
					(size 1 1)
					(thickness 0.15)
				)
			)
		)
		(property "Tolerance" "1%"
			(at 0 0 270)
			(unlocked yes)
			(layer "F.Fab")
			(hide yes)
			(effects
				(font
					(size 1 1)
					(thickness 0.15)
				)
			)
		)
		(sheetname "/Compute module/")
		(sheetfile "compute-module.kicad_sch")
		(attr smd)
		(fp_rect
			(start -0.925 -0.47)
			(end 0.925 0.47)
			(stroke
				(width 0.05)
				(type default)
			)
			(fill no)
			(layer "F.CrtYd")
		)
		(fp_rect
			(start -0.5 -0.25)
			(end 0.5 0.25)
			(stroke
				(width 0.15)
				(type solid)
			)
			(fill no)
			(layer "F.Fab")
		)
		(fp_text user "License: Apache-2.0"
			(at -0.95 5.169 270)
			(layer "F.Fab")
			(effects
				(font
					(size 0.7 0.7)
					(thickness 0.15)
				)
				(justify left bottom)
			)
		)
		(fp_text user "Author: Antmicro"
			(at -0.95 4.169 270)
			(layer "F.Fab")
			(effects
				(font
					(size 0.7 0.7)
					(thickness 0.15)
				)
				(justify left bottom)
			)
		)
		(fp_text user "${REFERENCE}"
			(at -0.95 3.168 270)
			(layer "F.Fab")
			(effects
				(font
					(size 0.7 0.7)
					(thickness 0.15)
				)
				(justify left bottom)
			)
		)
		(pad "1" smd roundrect
			(at -0.48 0 270)
			(size 0.59 0.64)
			(layers "F.Cu" "F.Mask" "F.Paste")
			(roundrect_rratio 0.25)
			(net 348 "Net-(U204-~{RESET})")
			(pintype "passive")
		)
		(pad "2" smd roundrect
			(at 0.48 0 270)
			(size 0.59 0.64)
			(layers "F.Cu" "F.Mask" "F.Paste")
			(roundrect_rratio 0.25)
			(net 9 "+3V3")
			(pintype "passive")
		)
	)
	(footprint "antmicro-footprints:TSOT23-6"
		(layer "F.Cu")
		(at 96.712292 127.0165)
		(property "Reference" "U901"
			(at -2.062292 2.1335 90)
			(layer "F.SilkS")
			(effects
				(font
					(size 0.7 0.7)
					(thickness 0.15)
				)
				(justify left bottom)
			)
		)
		(property "Value" "AP22615A_TSOT26"
			(at 0 2.6 0)
			(layer "F.Fab")
			(effects
				(font
					(size 0.7 0.7)
					(thickness 0.15)
				)
				(justify left bottom)
			)
		)
		(property "Datasheet" "https://www.mouser.com/datasheet/2/115/DIOD_S_A0008958405_1-2543193.pdf"
			(at 0 0 0)
			(layer "F.Fab")
			(hide yes)
			(effects
				(font
					(size 1.27 1.27)
					(thickness 0.15)
				)
			)
		)
		(property "MPN" "AP22615AWU-7"
			(at 0 0 0)
			(unlocked yes)
			(layer "F.Fab")
			(hide yes)
			(effects
				(font
					(size 1 1)
					(thickness 0.15)
				)
			)
		)
		(property "Manufacturer" "Diodes Incorporated"
			(at 0 0 0)
			(unlocked yes)
			(layer "F.Fab")
			(hide yes)
			(effects
				(font
					(size 1 1)
					(thickness 0.15)
				)
			)
		)
		(property "Author" "Antmicro"
			(at 0 0 0)
			(unlocked yes)
			(layer "F.Fab")
			(hide yes)
			(effects
				(font
					(size 1 1)
					(thickness 0.15)
				)
			)
		)
		(property "License" "Apache-2.0"
			(at 0 0 0)
			(unlocked yes)
			(layer "F.Fab")
			(hide yes)
			(effects
				(font
					(size 1 1)
					(thickness 0.15)
				)
			)
		)
		(sheetname "/USB/")
		(sheetfile "usb.kicad_sch")
		(attr smd)
		(fp_line
			(start -1 -1.5)
			(end -1 -1.375)
			(stroke
				(width 0.15)
				(type solid)
			)
			(layer "F.SilkS")
		)
		(fp_line
			(start -1 1.55)
			(end -1 1.4)
			(stroke
				(width 0.15)
				(type solid)
			)
			(layer "F.SilkS")
		)
		(fp_line
			(start 1 -1.497)
			(end -1 -1.5)
			(stroke
				(width 0.15)
				(type solid)
			)
			(layer "F.SilkS")
		)
		(fp_line
			(start 1 -1.497)
			(end 1 -1.375)
			(stroke
				(width 0.15)
				(type solid)
			)
			(layer "F.SilkS")
		)
		(fp_line
			(start 1 1.55)
			(end -1 1.55)
			(stroke
				(width 0.15)
				(type solid)
			)
			(layer "F.SilkS")
		)
		(fp_line
			(start 1 1.55)
			(end 1 1.4)
			(stroke
				(width 0.15)
				(type solid)
			)
			(layer "F.SilkS")
		)
		(fp_circle
			(center -1.44 -1.5)
			(end -1.39 -1.5)
			(stroke
				(width 0.15)
				(type solid)
			)
			(fill yes)
			(layer "F.SilkS")
		)
		(fp_rect
			(start 1.93 -1.7)
			(end -1.93 1.7)
			(stroke
				(width 0.05)
				(type solid)
			)
			(fill no)
			(layer "F.CrtYd")
		)
		(fp_line
			(start -0.45 -1.521)
			(end -0.876 -1.096)
			(stroke
				(width 0.15)
				(type solid)
			)
			(layer "F.Fab")
		)
		(fp_rect
			(start 0.875 1.528)
			(end -0.875 -1.525)
			(stroke
				(width 0.15)
				(type solid)
			)
			(fill no)
			(layer "F.Fab")
		)
		(fp_text user "License: Apache-2.0"
			(at -1.93 6.199 0)
			(layer "F.Fab")
			(effects
				(font
					(size 0.7 0.7)
					(thickness 0.15)
				)
				(justify left bottom)
			)
		)
		(fp_text user "${REFERENCE}"
			(at -1.93 3.8 0)
			(layer "F.Fab")
			(effects
				(font
					(size 0.7 0.7)
					(thickness 0.15)
				)
				(justify left bottom)
			)
		)
		(fp_text user "Author: Antmicro"
			(at -1.93 5 0)
			(layer "F.Fab")
			(effects
				(font
					(size 0.7 0.7)
					(thickness 0.15)
				)
				(justify left bottom)
			)
		)
		(pad "1" smd rect
			(at -1.301 -0.947 270)
			(size 0.7 1.2)
			(layers "F.Cu" "F.Mask" "F.Paste")
			(net 24 "/Compute module/USBA_VBUS")
			(pinfunction "OUT")
			(pintype "power_out")
		)
		(pad "2" smd rect
			(at -1.301 0.004 270)
			(size 0.7 1.2)
			(layers "F.Cu" "F.Mask" "F.Paste")
			(net 3 "GND")
			(pinfunction "GND")
			(pintype "power_in")
		)
		(pad "3" smd rect
			(at -1.301 0.954 270)
			(size 0.7 1.2)
			(layers "F.Cu" "F.Mask" "F.Paste")
			(net 405 "unconnected-(U901-FLG-Pad3)")
			(pinfunction "FLG")
			(pintype "output+no_connect")
		)
		(pad "4" smd rect
			(at 1.299 0.954 270)
			(size 0.7 1.2)
			(layers "F.Cu" "F.Mask" "F.Paste")
			(net 288 "/USB/USBA_OUT_EN")
			(pinfunction "EN")
			(pintype "input")
		)
		(pad "5" smd rect
			(at 1.299 0.004 270)
			(size 0.7 1.2)
			(layers "F.Cu" "F.Mask" "F.Paste")
			(net 376 "Net-(U901-ISET)")
			(pinfunction "ISET")
			(pintype "passive")
		)
		(pad "6" smd rect
			(at 1.299 -0.947 270)
			(size 0.7 1.2)
			(layers "F.Cu" "F.Mask" "F.Paste")
			(net 28 "/USB/+5V_{CAP}")
			(pinfunction "IN")
			(pintype "power_in")
		)
	)
	(footprint "antmicro-footprints:TP_SMD_0.75mm"
		(layer "F.Cu")
		(at 87.23 130.53 180)
		(property "Reference" "TP915"
			(at -1.03 3.62 0)
			(layer "F.SilkS")
			(effects
				(font
					(size 0.7 0.7)
					(thickness 0.15)
				)
				(justify right bottom)
			)
		)
		(property "Value" "TP_0.75mm_SMD"
			(at 0 1.2 0)
			(layer "F.Fab")
			(effects
				(font
					(size 0.7 0.7)
					(thickness 0.15)
				)
				(justify right bottom)
			)
		)
		(property "MPN" ""
			(at 0 0 180)
			(unlocked yes)
			(layer "F.Fab")
			(hide yes)
			(effects
				(font
					(size 1 1)
					(thickness 0.15)
				)
			)
		)
		(property "Manufacturer" ""
			(at 0 0 180)
			(unlocked yes)
			(layer "F.Fab")
			(hide yes)
			(effects
				(font
					(size 1 1)
					(thickness 0.15)
				)
			)
		)
		(property "Author" "Antmicro"
			(at 0 0 180)
			(unlocked yes)
			(layer "F.Fab")
			(hide yes)
			(effects
				(font
					(size 1 1)
					(thickness 0.15)
				)
			)
		)
		(property "License" "Apache-2.0"
			(at 0 0 180)
			(unlocked yes)
			(layer "F.Fab")
			(hide yes)
			(effects
				(font
					(size 1 1)
					(thickness 0.15)
				)
			)
		)
		(sheetname "/USB/")
		(sheetfile "usb.kicad_sch")
		(attr exclude_from_pos_files exclude_from_bom)
		(fp_circle
			(center 0 0)
			(end 0.475 0)
			(stroke
				(width 0.05)
				(type default)
			)
			(fill no)
			(layer "F.CrtYd")
		)
		(fp_text user "${REFERENCE}"
			(at -0.4 2.7 180)
			(layer "F.Fab")
			(effects
				(font
					(size 0.7 0.7)
					(thickness 0.15)
				)
				(justify left bottom)
			)
		)
		(fp_text user "License: Apache-2.0"
			(at -0.4 5.101 180)
			(layer "F.Fab")
			(effects
				(font
					(size 0.7 0.7)
					(thickness 0.15)
				)
				(justify left bottom)
			)
		)
		(fp_text user "Author: Antmicro"
			(at -0.4 3.901 180)
			(layer "F.Fab")
			(effects
				(font
					(size 0.7 0.7)
					(thickness 0.15)
				)
				(justify left bottom)
			)
		)
		(pad "1" smd circle
			(at 0 0 180)
			(size 0.75 0.75)
			(layers "F.Cu" "F.Mask")
			(net 440 "Net-(U905-PD2_CC2)")
			(pinfunction "1")
			(pintype "passive")
		)
	)
	(footprint "antmicro-footprints:R_0402_1005Metric"
		(layer "F.Cu")
		(at 123.805476 163.6665)
		(descr "Resistor SMD 0402")
		(tags "resistor SMD 0402")
		(property "Reference" "R506"
			(at -3.837514 0.53 0)
			(layer "F.SilkS")
			(effects
				(font
					(size 0.7 0.7)
					(thickness 0.15)
				)
				(justify left bottom)
			)
		)
		(property "Value" "R_10k_0402"
			(at -1.011843 1.772047 0)
			(layer "F.Fab")
			(effects
				(font
					(size 0.7 0.7)
					(thickness 0.15)
				)
				(justify left bottom)
			)
		)
		(property "Datasheet" "https://www.bourns.com/docs/product-datasheets/cr.pdf"
			(at 0 0 0)
			(layer "F.Fab")
			(hide yes)
			(effects
				(font
					(size 1.27 1.27)
					(thickness 0.15)
				)
			)
		)
		(property "Manufacturer" "Bourns"
			(at 0 0 0)
			(unlocked yes)
			(layer "F.Fab")
			(hide yes)
			(effects
				(font
					(size 1 1)
					(thickness 0.15)
				)
			)
		)
		(property "MPN" "CR0402-FX-1002GLF"
			(at 0 0 0)
			(unlocked yes)
			(layer "F.Fab")
			(hide yes)
			(effects
				(font
					(size 1 1)
					(thickness 0.15)
				)
			)
		)
		(property "Val" "10k"
			(at 0 0 0)
			(unlocked yes)
			(layer "F.Fab")
			(hide yes)
			(effects
				(font
					(size 1 1)
					(thickness 0.15)
				)
			)
		)
		(property "License" "Apache-2.0"
			(at 0 0 0)
			(unlocked yes)
			(layer "F.Fab")
			(hide yes)
			(effects
				(font
					(size 1 1)
					(thickness 0.15)
				)
			)
		)
		(property "Author" "Antmicro"
			(at 0 0 0)
			(unlocked yes)
			(layer "F.Fab")
			(hide yes)
			(effects
				(font
					(size 1 1)
					(thickness 0.15)
				)
			)
		)
		(property "Tolerance" "1%"
			(at 0 0 0)
			(unlocked yes)
			(layer "F.Fab")
			(hide yes)
			(effects
				(font
					(size 1 1)
					(thickness 0.15)
				)
			)
		)
		(sheetname "/NVMe & microSD/")
		(sheetfile "nvme-micro-sd.kicad_sch")
		(attr smd)
		(fp_rect
			(start -0.925 -0.47)
			(end 0.925 0.47)
			(stroke
				(width 0.05)
				(type default)
			)
			(fill no)
			(layer "F.CrtYd")
		)
		(fp_rect
			(start -0.5 -0.25)
			(end 0.5 0.25)
			(stroke
				(width 0.15)
				(type solid)
			)
			(fill no)
			(layer "F.Fab")
		)
		(fp_text user "Author: Antmicro"
			(at -0.95 4.169 0)
			(layer "F.Fab")
			(effects
				(font
					(size 0.7 0.7)
					(thickness 0.15)
				)
				(justify left bottom)
			)
		)
		(fp_text user "${REFERENCE}"
			(at -0.95 3.168 0)
			(layer "F.Fab")
			(effects
				(font
					(size 0.7 0.7)
					(thickness 0.15)
				)
				(justify left bottom)
			)
		)
		(fp_text user "License: Apache-2.0"
			(at -0.95 5.169 0)
			(layer "F.Fab")
			(effects
				(font
					(size 0.7 0.7)
					(thickness 0.15)
				)
				(justify left bottom)
			)
		)
		(pad "1" smd roundrect
			(at -0.48 0)
			(size 0.59 0.64)
			(layers "F.Cu" "F.Mask" "F.Paste")
			(roundrect_rratio 0.25)
			(net 9 "+3V3")
			(pintype "passive")
		)
		(pad "2" smd roundrect
			(at 0.48 0)
			(size 0.59 0.64)
			(layers "F.Cu" "F.Mask" "F.Paste")
			(roundrect_rratio 0.25)
			(net 6 "/Compute module/SDIO.D0")
			(pintype "passive")
		)
	)
	(footprint "antmicro-footprints:XDFN-2_1x0.60mm"
		(layer "F.Cu")
		(at 132.367962 126.3915 180)
		(property "Reference" "D204"
			(at -0.89 -1.385 0)
			(layer "F.SilkS")
			(effects
				(font
					(size 0.7 0.7)
					(thickness 0.15)
				)
				(justify right bottom)
			)
		)
		(property "Value" "TPD1E0B04_XDFN-2"
			(at 0 1.5 0)
			(layer "F.Fab")
			(effects
				(font
					(size 0.7 0.7)
					(thickness 0.15)
				)
				(justify right bottom)
			)
		)
		(property "Datasheet" "https://www.ti.com/general/docs/suppproductinfo.tsp?distId=26&gotoUrl=https://www.ti.com/lit/gpn/tpd1e0b04"
			(at 0 0 180)
			(layer "F.Fab")
			(hide yes)
			(effects
				(font
					(size 1.27 1.27)
					(thickness 0.15)
				)
			)
		)
		(property "MPN" "TPD1E0B04DPYR"
			(at 264.735924 252.783 0)
			(layer "F.Fab")
			(hide yes)
			(effects
				(font
					(size 1 1)
					(thickness 0.15)
				)
			)
		)
		(property "Manufacturer" "Texas Instruments"
			(at 264.735924 252.783 0)
			(layer "F.Fab")
			(hide yes)
			(effects
				(font
					(size 1 1)
					(thickness 0.15)
				)
			)
		)
		(property "Author" "Antmicro"
			(at 0 0 180)
			(unlocked yes)
			(layer "F.Fab")
			(hide yes)
			(effects
				(font
					(size 1 1)
					(thickness 0.15)
				)
			)
		)
		(property "License" "Apache-2.0"
			(at 0 0 180)
			(unlocked yes)
			(layer "F.Fab")
			(hide yes)
			(effects
				(font
					(size 1 1)
					(thickness 0.15)
				)
			)
		)
		(sheetname "/Compute module/")
		(sheetfile "compute-module.kicad_sch")
		(attr smd)
		(fp_rect
			(start -0.725 -0.475)
			(end 0.725 0.475)
			(stroke
				(width 0.05)
				(type solid)
			)
			(fill no)
			(layer "F.CrtYd")
		)
		(fp_rect
			(start -0.55 -0.35)
			(end 0.55 0.35)
			(stroke
				(width 0.15)
				(type solid)
			)
			(fill no)
			(layer "F.Fab")
		)
		(fp_text user "${REFERENCE}"
			(at -0.8 3.2 180)
			(layer "F.Fab")
			(effects
				(font
					(size 0.7 0.7)
					(thickness 0.15)
				)
				(justify left bottom)
			)
		)
		(fp_text user "Author: Antmicro"
			(at -0.8 4.4 180)
			(layer "F.Fab")
			(effects
				(font
					(size 0.7 0.7)
					(thickness 0.15)
				)
				(justify left bottom)
			)
		)
		(fp_text user "License: Apache-2.0"
			(at -0.8 5.6 180)
			(layer "F.Fab")
			(effects
				(font
					(size 0.7 0.7)
					(thickness 0.15)
				)
				(justify left bottom)
			)
		)
		(pad "1" smd roundrect
			(at -0.351 0 180)
			(size 0.3 0.5)
			(layers "F.Cu" "F.Mask" "F.Paste")
			(roundrect_rratio 0.25)
			(net 3 "GND")
			(pinfunction "C")
			(pintype "passive")
		)
		(pad "2" smd roundrect
			(at 0.349 0 180)
			(size 0.3 0.5)
			(layers "F.Cu" "F.Mask" "F.Paste")
			(roundrect_rratio 0.25)
			(net 4 "Net-(D204-A)")
			(pinfunction "A")
			(pintype "passive")
		)
	)
	(footprint "antmicro-footprints:R_0402_1005Metric"
		(layer "F.Cu")
		(at 75.242962 132.1915)
		(descr "Resistor SMD 0402")
		(tags "resistor SMD 0402")
		(property "Reference" "R921"
			(at -7.592962 2.3585 0)
			(layer "F.SilkS")
			(effects
				(font
					(size 0.7 0.7)
					(thickness 0.15)
				)
				(justify left bottom)
			)
		)
		(property "Value" "R_470R_0402"
			(at -1.011843 1.772047 0)
			(layer "F.Fab")
			(effects
				(font
					(size 0.7 0.7)
					(thickness 0.15)
				)
				(justify left bottom)
			)
		)
		(property "Datasheet" "https://www.bourns.com/docs/product-datasheets/cr.pdf"
			(at 0 0 0)
			(layer "F.Fab")
			(hide yes)
			(effects
				(font
					(size 1.27 1.27)
					(thickness 0.15)
				)
			)
		)
		(property "MPN" "CR0402-FX-4700GLF"
			(at 0 0 0)
			(unlocked yes)
			(layer "F.Fab")
			(hide yes)
			(effects
				(font
					(size 1 1)
					(thickness 0.15)
				)
			)
		)
		(property "Manufacturer" "Bourns"
			(at 0 0 0)
			(unlocked yes)
			(layer "F.Fab")
			(hide yes)
			(effects
				(font
					(size 1 1)
					(thickness 0.15)
				)
			)
		)
		(property "License" "Apache-2.0"
			(at 0 0 0)
			(unlocked yes)
			(layer "F.Fab")
			(hide yes)
			(effects
				(font
					(size 1 1)
					(thickness 0.15)
				)
			)
		)
		(property "Author" "Antmicro"
			(at 0 0 0)
			(unlocked yes)
			(layer "F.Fab")
			(hide yes)
			(effects
				(font
					(size 1 1)
					(thickness 0.15)
				)
			)
		)
		(property "Val" "470R"
			(at 0 0 0)
			(unlocked yes)
			(layer "F.Fab")
			(hide yes)
			(effects
				(font
					(size 1 1)
					(thickness 0.15)
				)
			)
		)
		(property "Tolerance" "1%"
			(at 0 0 0)
			(unlocked yes)
			(layer "F.Fab")
			(hide yes)
			(effects
				(font
					(size 1 1)
					(thickness 0.15)
				)
			)
		)
		(sheetname "/USB/")
		(sheetfile "usb.kicad_sch")
		(attr smd)
		(fp_rect
			(start -0.925 -0.47)
			(end 0.925 0.47)
			(stroke
				(width 0.05)
				(type default)
			)
			(fill no)
			(layer "F.CrtYd")
		)
		(fp_rect
			(start -0.5 -0.25)
			(end 0.5 0.25)
			(stroke
				(width 0.15)
				(type solid)
			)
			(fill no)
			(layer "F.Fab")
		)
		(fp_text user "Author: Antmicro"
			(at -0.95 4.169 0)
			(layer "F.Fab")
			(effects
				(font
					(size 0.7 0.7)
					(thickness 0.15)
				)
				(justify left bottom)
			)
		)
		(fp_text user "License: Apache-2.0"
			(at -0.95 5.169 0)
			(layer "F.Fab")
			(effects
				(font
					(size 0.7 0.7)
					(thickness 0.15)
				)
				(justify left bottom)
			)
		)
		(fp_text user "${REFERENCE}"
			(at -0.95 3.168 0)
			(layer "F.Fab")
			(effects
				(font
					(size 0.7 0.7)
					(thickness 0.15)
				)
				(justify left bottom)
			)
		)
		(pad "1" smd roundrect
			(at -0.48 0)
			(size 0.59 0.64)
			(layers "F.Cu" "F.Mask" "F.Paste")
			(roundrect_rratio 0.25)
			(net 489 "Net-(D912-A)")
			(pintype "passive")
		)
		(pad "2" smd roundrect
			(at 0.48 0)
			(size 0.59 0.64)
			(layers "F.Cu" "F.Mask" "F.Paste")
			(roundrect_rratio 0.25)
			(net 27 "/USB/USB_3V3")
			(pintype "passive")
		)
	)
	(footprint "antmicro-footprints:R_0402_1005Metric"
		(layer "F.Cu")
		(at 101.167962 132.9415)
		(descr "Resistor SMD 0402")
		(tags "resistor SMD 0402")
		(property "Reference" "R928"
			(at 0.905 0.45 0)
			(layer "F.SilkS")
			(effects
				(font
					(size 0.7 0.7)
					(thickness 0.15)
				)
				(justify left bottom)
			)
		)
		(property "Value" "R_10k_0402"
			(at -1.011843 1.772047 0)
			(layer "F.Fab")
			(effects
				(font
					(size 0.7 0.7)
					(thickness 0.15)
				)
				(justify left bottom)
			)
		)
		(property "Datasheet" "https://www.bourns.com/docs/product-datasheets/cr.pdf"
			(at 0 0 0)
			(layer "F.Fab")
			(hide yes)
			(effects
				(font
					(size 1.27 1.27)
					(thickness 0.15)
				)
			)
		)
		(property "Manufacturer" "Bourns"
			(at 0 0 0)
			(unlocked yes)
			(layer "F.Fab")
			(hide yes)
			(effects
				(font
					(size 1 1)
					(thickness 0.15)
				)
			)
		)
		(property "MPN" "CR0402-FX-1002GLF"
			(at 0 0 0)
			(unlocked yes)
			(layer "F.Fab")
			(hide yes)
			(effects
				(font
					(size 1 1)
					(thickness 0.15)
				)
			)
		)
		(property "Val" "10k"
			(at 0 0 0)
			(unlocked yes)
			(layer "F.Fab")
			(hide yes)
			(effects
				(font
					(size 1 1)
					(thickness 0.15)
				)
			)
		)
		(property "License" "Apache-2.0"
			(at 0 0 0)
			(unlocked yes)
			(layer "F.Fab")
			(hide yes)
			(effects
				(font
					(size 1 1)
					(thickness 0.15)
				)
			)
		)
		(property "Author" "Antmicro"
			(at 0 0 0)
			(unlocked yes)
			(layer "F.Fab")
			(hide yes)
			(effects
				(font
					(size 1 1)
					(thickness 0.15)
				)
			)
		)
		(property "Tolerance" "1%"
			(at 0 0 0)
			(unlocked yes)
			(layer "F.Fab")
			(hide yes)
			(effects
				(font
					(size 1 1)
					(thickness 0.15)
				)
			)
		)
		(sheetname "/USB/")
		(sheetfile "usb.kicad_sch")
		(attr smd)
		(fp_rect
			(start -0.925 -0.47)
			(end 0.925 0.47)
			(stroke
				(width 0.05)
				(type default)
			)
			(fill no)
			(layer "F.CrtYd")
		)
		(fp_rect
			(start -0.5 -0.25)
			(end 0.5 0.25)
			(stroke
				(width 0.15)
				(type solid)
			)
			(fill no)
			(layer "F.Fab")
		)
		(fp_text user "${REFERENCE}"
			(at -0.95 3.168 0)
			(layer "F.Fab")
			(effects
				(font
					(size 0.7 0.7)
					(thickness 0.15)
				)
				(justify left bottom)
			)
		)
		(fp_text user "Author: Antmicro"
			(at -0.95 4.169 0)
			(layer "F.Fab")
			(effects
				(font
					(size 0.7 0.7)
					(thickness 0.15)
				)
				(justify left bottom)
			)
		)
		(fp_text user "License: Apache-2.0"
			(at -0.95 5.169 0)
			(layer "F.Fab")
			(effects
				(font
					(size 0.7 0.7)
					(thickness 0.15)
				)
				(justify left bottom)
			)
		)
		(pad "1" smd roundrect
			(at -0.48 0)
			(size 0.59 0.64)
			(layers "F.Cu" "F.Mask" "F.Paste")
			(roundrect_rratio 0.25)
			(net 127 "Net-(Q903-G)")
			(pintype "passive")
		)
		(pad "2" smd roundrect
			(at 0.48 0)
			(size 0.59 0.64)
			(layers "F.Cu" "F.Mask" "F.Paste")
			(roundrect_rratio 0.25)
			(net 10 "+5V")
			(pintype "passive")
		)
	)
	(footprint "antmicro-footprints:TP_SMD_0.75mm"
		(layer "F.Cu")
		(at 80.3 137.65)
		(property "Reference" "TP916"
			(at -1.75 3.95 90)
			(layer "F.SilkS")
			(effects
				(font
					(size 0.7 0.7)
					(thickness 0.15)
				)
				(justify left bottom)
			)
		)
		(property "Value" "TP_0.75mm_SMD"
			(at 0 1.2 0)
			(layer "F.Fab")
			(effects
				(font
					(size 0.7 0.7)
					(thickness 0.15)
				)
				(justify left bottom)
			)
		)
		(property "MPN" ""
			(at 0 0 0)
			(unlocked yes)
			(layer "F.Fab")
			(hide yes)
			(effects
				(font
					(size 1 1)
					(thickness 0.15)
				)
			)
		)
		(property "Manufacturer" ""
			(at 0 0 0)
			(unlocked yes)
			(layer "F.Fab")
			(hide yes)
			(effects
				(font
					(size 1 1)
					(thickness 0.15)
				)
			)
		)
		(property "Author" "Antmicro"
			(at 0 0 0)
			(unlocked yes)
			(layer "F.Fab")
			(hide yes)
			(effects
				(font
					(size 1 1)
					(thickness 0.15)
				)
			)
		)
		(property "License" "Apache-2.0"
			(at 0 0 0)
			(unlocked yes)
			(layer "F.Fab")
			(hide yes)
			(effects
				(font
					(size 1 1)
					(thickness 0.15)
				)
			)
		)
		(sheetname "/USB/")
		(sheetfile "usb.kicad_sch")
		(attr exclude_from_pos_files exclude_from_bom)
		(fp_circle
			(center 0 0)
			(end 0.475 0)
			(stroke
				(width 0.05)
				(type default)
			)
			(fill no)
			(layer "F.CrtYd")
		)
		(fp_text user "License: Apache-2.0"
			(at -0.4 5.101 0)
			(layer "F.Fab")
			(effects
				(font
					(size 0.7 0.7)
					(thickness 0.15)
				)
				(justify left bottom)
			)
		)
		(fp_text user "${REFERENCE}"
			(at -0.4 2.7 0)
			(layer "F.Fab")
			(effects
				(font
					(size 0.7 0.7)
					(thickness 0.15)
				)
				(justify left bottom)
			)
		)
		(fp_text user "Author: Antmicro"
			(at -0.4 3.901 0)
			(layer "F.Fab")
			(effects
				(font
					(size 0.7 0.7)
					(thickness 0.15)
				)
				(justify left bottom)
			)
		)
		(pad "1" smd circle
			(at 0 0)
			(size 0.75 0.75)
			(layers "F.Cu" "F.Mask")
			(net 441 "Net-(U905-GPIO4)")
			(pinfunction "1")
			(pintype "passive")
		)
	)
	(footprint "antmicro-footprints:C_0402_1005Metric"
		(layer "F.Cu")
		(at 76.617962 176.6165 90)
		(descr "Capacitor SMD 0402")
		(tags "capacitor SMD 0402")
		(property "Reference" "C815"
			(at 0.9755 -1.98 180)
			(layer "F.SilkS")
			(effects
				(font
					(size 0.7 0.7)
					(thickness 0.15)
				)
				(justify left bottom)
			)
		)
		(property "Value" "C_10p_0402"
			(at -1.022927 2.155213 90)
			(layer "F.Fab")
			(effects
				(font
					(size 0.7 0.7)
					(thickness 0.15)
				)
				(justify left bottom)
			)
		)
		(property "Datasheet" "https://www.murata.com/products/productdetail?partno=GCM1555C1H100GA16%23"
			(at 0 0 90)
			(layer "F.Fab")
			(hide yes)
			(effects
				(font
					(size 1.27 1.27)
					(thickness 0.15)
				)
			)
		)
		(property "MPN" "GCM1555C1H100GA16D"
			(at 0 0 90)
			(unlocked yes)
			(layer "F.Fab")
			(hide yes)
			(effects
				(font
					(size 1 1)
					(thickness 0.15)
				)
			)
		)
		(property "Manufacturer" "Murata"
			(at 0 0 90)
			(unlocked yes)
			(layer "F.Fab")
			(hide yes)
			(effects
				(font
					(size 1 1)
					(thickness 0.15)
				)
			)
		)
		(property "License" "Apache-2.0"
			(at 0 0 90)
			(unlocked yes)
			(layer "F.Fab")
			(hide yes)
			(effects
				(font
					(size 1 1)
					(thickness 0.15)
				)
			)
		)
		(property "Author" "Antmicro"
			(at 0 0 90)
			(unlocked yes)
			(layer "F.Fab")
			(hide yes)
			(effects
				(font
					(size 1 1)
					(thickness 0.15)
				)
			)
		)
		(property "Val" "10p"
			(at 0 0 90)
			(unlocked yes)
			(layer "F.Fab")
			(hide yes)
			(effects
				(font
					(size 1 1)
					(thickness 0.15)
				)
			)
		)
		(property "Voltage" "50V"
			(at 0 0 90)
			(unlocked yes)
			(layer "F.Fab")
			(hide yes)
			(effects
				(font
					(size 1 1)
					(thickness 0.15)
				)
			)
		)
		(property "Dielectric" "C0G"
			(at 0 0 90)
			(unlocked yes)
			(layer "F.Fab")
			(hide yes)
			(effects
				(font
					(size 1 1)
					(thickness 0.15)
				)
			)
		)
		(sheetname "/Peripherals/")
		(sheetfile "peripherals.kicad_sch")
		(attr smd)
		(fp_rect
			(start -0.925 -0.47)
			(end 0.925 0.47)
			(stroke
				(width 0.05)
				(type default)
			)
			(fill no)
			(layer "F.CrtYd")
		)
		(fp_line
			(start 0.504 -0.25)
			(end 0.504 0.248)
			(stroke
				(width 0.15)
				(type solid)
			)
			(layer "F.Fab")
		)
		(fp_line
			(start -0.494 -0.25)
			(end 0.504 -0.25)
			(stroke
				(width 0.15)
				(type solid)
			)
			(layer "F.Fab")
		)
		(fp_line
			(start 0.504 0.248)
			(end -0.494 0.248)
			(stroke
				(width 0.15)
				(type solid)
			)
			(layer "F.Fab")
		)
		(fp_line
			(start -0.494 0.248)
			(end -0.494 -0.25)
			(stroke
				(width 0.15)
				(type solid)
			)
			(layer "F.Fab")
		)
		(fp_text user "${REFERENCE}"
			(at -0.939 4.599 90)
			(layer "F.Fab")
			(effects
				(font
					(size 0.7 0.7)
					(thickness 0.15)
				)
				(justify left bottom)
			)
		)
		(fp_text user "License: Apache-2.0"
			(at -0.939 5.799 90)
			(layer "F.Fab")
			(effects
				(font
					(size 0.7 0.7)
					(thickness 0.15)
				)
				(justify left bottom)
			)
		)
		(fp_text user "Author: Antmicro"
			(at -0.939 3.399 90)
			(layer "F.Fab")
			(effects
				(font
					(size 0.7 0.7)
					(thickness 0.15)
				)
				(justify left bottom)
			)
		)
		(pad "1" smd roundrect
			(at -0.48 0 90)
			(size 0.59 0.64)
			(layers "F.Cu" "F.Mask" "F.Paste")
			(roundrect_rratio 0.25)
			(net 3 "GND")
			(pintype "passive")
		)
		(pad "2" smd roundrect
			(at 0.48 0 90)
			(size 0.59 0.64)
			(layers "F.Cu" "F.Mask" "F.Paste")
			(roundrect_rratio 0.25)
			(net 108 "Net-(U801-CLK_XTAL1)")
			(pintype "passive")
		)
	)
	(footprint "antmicro-footprints:TP_SMD_0.75mm"
		(layer "F.Cu")
		(at 98.775 124.375)
		(property "Reference" "TP901"
			(at -3.525 -0.225 0)
			(layer "F.SilkS")
			(effects
				(font
					(size 0.7 0.7)
					(thickness 0.15)
				)
				(justify left bottom)
			)
		)
		(property "Value" "TP_0.75mm_SMD"
			(at 0 1.2 0)
			(layer "F.Fab")
			(effects
				(font
					(size 0.7 0.7)
					(thickness 0.15)
				)
				(justify left bottom)
			)
		)
		(property "MPN" ""
			(at 0 0 0)
			(unlocked yes)
			(layer "F.Fab")
			(hide yes)
			(effects
				(font
					(size 1 1)
					(thickness 0.15)
				)
			)
		)
		(property "Manufacturer" ""
			(at 0 0 0)
			(unlocked yes)
			(layer "F.Fab")
			(hide yes)
			(effects
				(font
					(size 1 1)
					(thickness 0.15)
				)
			)
		)
		(property "Author" "Antmicro"
			(at 0 0 0)
			(unlocked yes)
			(layer "F.Fab")
			(hide yes)
			(effects
				(font
					(size 1 1)
					(thickness 0.15)
				)
			)
		)
		(property "License" "Apache-2.0"
			(at 0 0 0)
			(unlocked yes)
			(layer "F.Fab")
			(hide yes)
			(effects
				(font
					(size 1 1)
					(thickness 0.15)
				)
			)
		)
		(sheetname "/USB/")
		(sheetfile "usb.kicad_sch")
		(attr exclude_from_pos_files exclude_from_bom)
		(fp_circle
			(center 0 0)
			(end 0.475 0)
			(stroke
				(width 0.05)
				(type default)
			)
			(fill no)
			(layer "F.CrtYd")
		)
		(fp_text user "Author: Antmicro"
			(at -0.4 3.901 0)
			(layer "F.Fab")
			(effects
				(font
					(size 0.7 0.7)
					(thickness 0.15)
				)
				(justify left bottom)
			)
		)
		(fp_text user "${REFERENCE}"
			(at -0.4 2.7 0)
			(layer "F.Fab")
			(effects
				(font
					(size 0.7 0.7)
					(thickness 0.15)
				)
				(justify left bottom)
			)
		)
		(fp_text user "License: Apache-2.0"
			(at -0.4 5.101 0)
			(layer "F.Fab")
			(effects
				(font
					(size 0.7 0.7)
					(thickness 0.15)
				)
				(justify left bottom)
			)
		)
		(pad "1" smd circle
			(at 0 0)
			(size 0.75 0.75)
			(layers "F.Cu" "F.Mask")
			(net 433 "Net-(U906-DIR)")
			(pinfunction "1")
			(pintype "passive")
		)
	)
	(footprint "antmicro-footprints:R_0402_1005Metric"
		(layer "F.Cu")
		(at 100.267962 149.6165 90)
		(descr "Resistor SMD 0402")
		(tags "resistor SMD 0402")
		(property "Reference" "R204"
			(at -3.5585 0.282038 90)
			(layer "F.SilkS")
			(effects
				(font
					(size 0.7 0.7)
					(thickness 0.15)
				)
				(justify left bottom)
			)
		)
		(property "Value" "R_100k_0402"
			(at -1.011843 1.772047 90)
			(layer "F.Fab")
			(effects
				(font
					(size 0.7 0.7)
					(thickness 0.15)
				)
				(justify left bottom)
			)
		)
		(property "Datasheet" "https://www.bourns.com/docs/product-datasheets/cr.pdf"
			(at 0 0 90)
			(layer "F.Fab")
			(hide yes)
			(effects
				(font
					(size 1.27 1.27)
					(thickness 0.15)
				)
			)
		)
		(property "MPN" "CR0402-FX-1003GLF"
			(at 0 0 90)
			(unlocked yes)
			(layer "F.Fab")
			(hide yes)
			(effects
				(font
					(size 1 1)
					(thickness 0.15)
				)
			)
		)
		(property "Manufacturer" "Bourns"
			(at 0 0 90)
			(unlocked yes)
			(layer "F.Fab")
			(hide yes)
			(effects
				(font
					(size 1 1)
					(thickness 0.15)
				)
			)
		)
		(property "License" "Apache-2.0"
			(at 0 0 90)
			(unlocked yes)
			(layer "F.Fab")
			(hide yes)
			(effects
				(font
					(size 1 1)
					(thickness 0.15)
				)
			)
		)
		(property "Author" "Antmicro"
			(at 0 0 90)
			(unlocked yes)
			(layer "F.Fab")
			(hide yes)
			(effects
				(font
					(size 1 1)
					(thickness 0.15)
				)
			)
		)
		(property "Val" "100k"
			(at 0 0 90)
			(unlocked yes)
			(layer "F.Fab")
			(hide yes)
			(effects
				(font
					(size 1 1)
					(thickness 0.15)
				)
			)
		)
		(property "Tolerance" "1%"
			(at 0 0 90)
			(unlocked yes)
			(layer "F.Fab")
			(hide yes)
			(effects
				(font
					(size 1 1)
					(thickness 0.15)
				)
			)
		)
		(sheetname "/Compute module/")
		(sheetfile "compute-module.kicad_sch")
		(attr smd)
		(fp_rect
			(start -0.925 -0.47)
			(end 0.925 0.47)
			(stroke
				(width 0.05)
				(type default)
			)
			(fill no)
			(layer "F.CrtYd")
		)
		(fp_rect
			(start -0.5 -0.25)
			(end 0.5 0.25)
			(stroke
				(width 0.15)
				(type solid)
			)
			(fill no)
			(layer "F.Fab")
		)
		(fp_text user "License: Apache-2.0"
			(at -0.95 5.169 90)
			(layer "F.Fab")
			(effects
				(font
					(size 0.7 0.7)
					(thickness 0.15)
				)
				(justify left bottom)
			)
		)
		(fp_text user "Author: Antmicro"
			(at -0.95 4.169 90)
			(layer "F.Fab")
			(effects
				(font
					(size 0.7 0.7)
					(thickness 0.15)
				)
				(justify left bottom)
			)
		)
		(fp_text user "${REFERENCE}"
			(at -0.95 3.168 90)
			(layer "F.Fab")
			(effects
				(font
					(size 0.7 0.7)
					(thickness 0.15)
				)
				(justify left bottom)
			)
		)
		(pad "1" smd roundrect
			(at -0.48 0 90)
			(size 0.59 0.64)
			(layers "F.Cu" "F.Mask" "F.Paste")
			(roundrect_rratio 0.25)
			(net 3 "GND")
			(pintype "passive")
		)
		(pad "2" smd roundrect
			(at 0.48 0 90)
			(size 0.59 0.64)
			(layers "F.Cu" "F.Mask" "F.Paste")
			(roundrect_rratio 0.25)
			(net 231 "/Compute module/PolarfireID")
			(pintype "passive")
		)
	)
	(footprint "antmicro-footprints:SOT-523"
		(layer "F.Cu")
		(at 141.727962 128.0815 180)
		(property "Reference" "Q207"
			(at 1.35 1.255 90)
			(layer "F.SilkS")
			(effects
				(font
					(size 0.7 0.7)
					(thickness 0.15)
				)
				(justify right bottom)
			)
		)
		(property "Value" "PJE138K"
			(at 0.1 1.824 0)
			(layer "F.Fab")
			(effects
				(font
					(size 0.7 0.7)
					(thickness 0.15)
				)
				(justify right bottom)
			)
		)
		(property "Datasheet" "https://www.mouser.com/datasheet/2/1057/PJE138K-1876698.pdf"
			(at 0 0 180)
			(layer "F.Fab")
			(hide yes)
			(effects
				(font
					(size 1.27 1.27)
					(thickness 0.15)
				)
			)
		)
		(property "MPN" "PJE138K_R1_00001"
			(at 0 0 180)
			(unlocked yes)
			(layer "F.Fab")
			(hide yes)
			(effects
				(font
					(size 1 1)
					(thickness 0.15)
				)
			)
		)
		(property "Manufacturer" "PANJIT"
			(at 0 0 180)
			(unlocked yes)
			(layer "F.Fab")
			(hide yes)
			(effects
				(font
					(size 1 1)
					(thickness 0.15)
				)
			)
		)
		(property "Author" "Antmicro"
			(at 0 0 180)
			(unlocked yes)
			(layer "F.Fab")
			(hide yes)
			(effects
				(font
					(size 1 1)
					(thickness 0.15)
				)
			)
		)
		(property "License" "Apache-2.0"
			(at 0 0 180)
			(unlocked yes)
			(layer "F.Fab")
			(hide yes)
			(effects
				(font
					(size 1 1)
					(thickness 0.15)
				)
			)
		)
		(sheetname "/Compute module/")
		(sheetfile "compute-module.kicad_sch")
		(attr smd)
		(fp_line
			(start -0.277 -0.551)
			(end -0.277 -0.75)
			(stroke
				(width 0.15)
				(type solid)
			)
			(layer "F.SilkS")
		)
		(fp_line
			(start -0.725 -0.551)
			(end -0.277 -0.551)
			(stroke
				(width 0.15)
				(type solid)
			)
			(layer "F.SilkS")
		)
		(fp_line
			(start -0.927 -0.051)
			(end -0.927 -0.351)
			(stroke
				(width 0.15)
				(type solid)
			)
			(layer "F.SilkS")
		)
		(fp_line
			(start -0.927 -0.351)
			(end -0.725 -0.551)
			(stroke
				(width 0.15)
				(type solid)
			)
			(layer "F.SilkS")
		)
		(fp_circle
			(center -0.9652 0.9652)
			(end -0.9152 0.9652)
			(stroke
				(width 0.15)
				(type solid)
			)
			(fill yes)
			(layer "F.SilkS")
		)
		(fp_line
			(start 1.1 -1.16)
			(end 1.1 1.15)
			(stroke
				(width 0.05)
				(type solid)
			)
			(layer "F.CrtYd")
		)
		(fp_line
			(start -1.12 1.15)
			(end 1.1 1.15)
			(stroke
				(width 0.05)
				(type solid)
			)
			(layer "F.CrtYd")
		)
		(fp_line
			(start -1.12 -1.16)
			(end 1.1 -1.16)
			(stroke
				(width 0.05)
				(type solid)
			)
			(layer "F.CrtYd")
		)
		(fp_line
			(start -1.12 -1.16)
			(end -1.12 1.15)
			(stroke
				(width 0.05)
				(type solid)
			)
			(layer "F.CrtYd")
		)
		(fp_line
			(start 0.8 0.424)
			(end -0.802 0.424)
			(stroke
				(width 0.15)
				(type solid)
			)
			(layer "F.Fab")
		)
		(fp_line
			(start 0.8 -0.425)
			(end 0.8 0.424)
			(stroke
				(width 0.15)
				(type solid)
			)
			(layer "F.Fab")
		)
		(fp_line
			(start 0.8 -0.425)
			(end -0.652 -0.425)
			(stroke
				(width 0.15)
				(type solid)
			)
			(layer "F.Fab")
		)
		(fp_line
			(start -0.652 -0.425)
			(end -0.802 -0.276)
			(stroke
				(width 0.15)
				(type solid)
			)
			(layer "F.Fab")
		)
		(fp_line
			(start -0.802 -0.276)
			(end -0.802 0.424)
			(stroke
				(width 0.15)
				(type solid)
			)
			(layer "F.Fab")
		)
		(fp_circle
			(center -0.9652 0.9652)
			(end -0.9144 0.9652)
			(stroke
				(width 0.15)
				(type solid)
			)
			(fill no)
			(layer "F.Fab")
		)
		(fp_text user "License: Apache-2.0"
			(at -1.12 5.024 180)
			(layer "F.Fab")
			(effects
				(font
					(size 0.7 0.7)
					(thickness 0.15)
				)
				(justify left bottom)
			)
		)
		(fp_text user "${REFERENCE}"
			(at -1.12 3.824 180)
			(layer "F.Fab")
			(effects
				(font
					(size 0.7 0.7)
					(thickness 0.15)
				)
				(justify left bottom)
			)
		)
		(fp_text user "Author: Antmicro"
			(at -1.12 6.224 180)
			(layer "F.Fab")
			(effects
				(font
					(size 0.7 0.7)
					(thickness 0.15)
				)
				(justify left bottom)
			)
		)
		(pad "1" smd rect
			(at -0.5 0.65 180)
			(size 0.4 0.51)
			(layers "F.Cu" "F.Mask" "F.Paste")
			(net 329 "Net-(Q207-G)")
			(pinfunction "G")
			(pintype "input")
		)
		(pad "2" smd rect
			(at 0.498 0.65 180)
			(size 0.4 0.51)
			(layers "F.Cu" "F.Mask" "F.Paste")
			(net 3 "GND")
			(pinfunction "S")
			(pintype "passive")
		)
		(pad "3" smd rect
			(at 0 -0.652 180)
			(size 0.4 0.51)
			(layers "F.Cu" "F.Mask" "F.Paste")
			(net 250 "/Compute module/~{RPi_BOOT}")
			(pinfunction "D")
			(pintype "passive")
		)
	)
	(footprint "antmicro-footprints:C_0402_1005Metric"
		(layer "F.Cu")
		(at 129.267962 118.6665)
		(descr "Capacitor SMD 0402")
		(tags "capacitor SMD 0402")
		(property "Reference" "C202"
			(at -3.78 -0.1 0)
			(layer "F.SilkS")
			(effects
				(font
					(size 0.7 0.7)
					(thickness 0.15)
				)
				(justify left bottom)
			)
		)
		(property "Value" "C_100n_0402"
			(at -1.022927 2.155213 0)
			(layer "F.Fab")
			(effects
				(font
					(size 0.7 0.7)
					(thickness 0.15)
				)
				(justify left bottom)
			)
		)
		(property "Datasheet" "https://www.murata.com/products/productdetail?partno=GRM155R61H104KE14%23"
			(at 0 0 0)
			(layer "F.Fab")
			(hide yes)
			(effects
				(font
					(size 1.27 1.27)
					(thickness 0.15)
				)
			)
		)
		(property "Manufacturer" "Murata"
			(at 0 0 0)
			(unlocked yes)
			(layer "F.Fab")
			(hide yes)
			(effects
				(font
					(size 1 1)
					(thickness 0.15)
				)
			)
		)
		(property "MPN" "GRM155R61H104KE14D"
			(at 0 0 0)
			(unlocked yes)
			(layer "F.Fab")
			(hide yes)
			(effects
				(font
					(size 1 1)
					(thickness 0.15)
				)
			)
		)
		(property "Val" "100n"
			(at 0 0 0)
			(unlocked yes)
			(layer "F.Fab")
			(hide yes)
			(effects
				(font
					(size 1 1)
					(thickness 0.15)
				)
			)
		)
		(property "License" "Apache-2.0"
			(at 0 0 0)
			(unlocked yes)
			(layer "F.Fab")
			(hide yes)
			(effects
				(font
					(size 1 1)
					(thickness 0.15)
				)
			)
		)
		(property "Author" "Antmicro"
			(at 0 0 0)
			(unlocked yes)
			(layer "F.Fab")
			(hide yes)
			(effects
				(font
					(size 1 1)
					(thickness 0.15)
				)
			)
		)
		(property "Voltage" "50V"
			(at 0 0 0)
			(unlocked yes)
			(layer "F.Fab")
			(hide yes)
			(effects
				(font
					(size 1 1)
					(thickness 0.15)
				)
			)
		)
		(property "Dielectric" "X5R"
			(at 0 0 0)
			(unlocked yes)
			(layer "F.Fab")
			(hide yes)
			(effects
				(font
					(size 1 1)
					(thickness 0.15)
				)
			)
		)
		(sheetname "/Compute module/")
		(sheetfile "compute-module.kicad_sch")
		(attr smd)
		(fp_rect
			(start -0.925 -0.47)
			(end 0.925 0.47)
			(stroke
				(width 0.05)
				(type default)
			)
			(fill no)
			(layer "F.CrtYd")
		)
		(fp_line
			(start -0.494 -0.25)
			(end 0.504 -0.25)
			(stroke
				(width 0.15)
				(type solid)
			)
			(layer "F.Fab")
		)
		(fp_line
			(start -0.494 0.248)
			(end -0.494 -0.25)
			(stroke
				(width 0.15)
				(type solid)
			)
			(layer "F.Fab")
		)
		(fp_line
			(start 0.504 -0.25)
			(end 0.504 0.248)
			(stroke
				(width 0.15)
				(type solid)
			)
			(layer "F.Fab")
		)
		(fp_line
			(start 0.504 0.248)
			(end -0.494 0.248)
			(stroke
				(width 0.15)
				(type solid)
			)
			(layer "F.Fab")
		)
		(fp_text user "Author: Antmicro"
			(at -0.939 3.399 0)
			(layer "F.Fab")
			(effects
				(font
					(size 0.7 0.7)
					(thickness 0.15)
				)
				(justify left bottom)
			)
		)
		(fp_text user "${REFERENCE}"
			(at -0.939 4.599 0)
			(layer "F.Fab")
			(effects
				(font
					(size 0.7 0.7)
					(thickness 0.15)
				)
				(justify left bottom)
			)
		)
		(fp_text user "License: Apache-2.0"
			(at -0.939 5.799 0)
			(layer "F.Fab")
			(effects
				(font
					(size 0.7 0.7)
					(thickness 0.15)
				)
				(justify left bottom)
			)
		)
		(pad "1" smd roundrect
			(at -0.48 0)
			(size 0.59 0.64)
			(layers "F.Cu" "F.Mask" "F.Paste")
			(roundrect_rratio 0.25)
			(net 3 "GND")
			(pintype "passive")
		)
		(pad "2" smd roundrect
			(at 0.48 0)
			(size 0.59 0.64)
			(layers "F.Cu" "F.Mask" "F.Paste")
			(roundrect_rratio 0.25)
			(net 4 "Net-(D204-A)")
			(pintype "passive")
		)
	)
	(footprint "antmicro-footprints:Choke_Murata-DLW21"
		(layer "F.Cu")
		(at 83.992962 122.6665)
		(property "Reference" "T902"
			(at 1.175 0.81 0)
			(layer "F.SilkS")
			(effects
				(font
					(size 0.7 0.7)
					(thickness 0.15)
				)
				(justify left bottom)
			)
		)
		(property "Value" "Choke_DLW21SN900SQ2L"
			(at 0.4 1.778 0)
			(layer "F.Fab")
			(effects
				(font
					(size 0.7 0.7)
					(thickness 0.15)
				)
				(justify left bottom)
			)
		)
		(property "Datasheet" "https://www.murata.com/en-us/products/productdetail?partno=DLW21SN900SQ2%23"
			(at 0 0 0)
			(layer "F.Fab")
			(hide yes)
			(effects
				(font
					(size 1.27 1.27)
					(thickness 0.15)
				)
			)
		)
		(property "Manufacturer" "Murata"
			(at 0 0 0)
			(unlocked yes)
			(layer "F.Fab")
			(hide yes)
			(effects
				(font
					(size 1 1)
					(thickness 0.15)
				)
			)
		)
		(property "MPN" "DLW21SN900SQ2L"
			(at 0 0 0)
			(unlocked yes)
			(layer "F.Fab")
			(hide yes)
			(effects
				(font
					(size 1 1)
					(thickness 0.15)
				)
			)
		)
		(property "IMax" "0.33 A"
			(at 0 0 0)
			(unlocked yes)
			(layer "F.Fab")
			(hide yes)
			(effects
				(font
					(size 1 1)
					(thickness 0.15)
				)
			)
		)
		(property "Author" "Antmicro"
			(at 0 0 0)
			(unlocked yes)
			(layer "F.Fab")
			(hide yes)
			(effects
				(font
					(size 1 1)
					(thickness 0.15)
				)
			)
		)
		(property "License" "Apache-2.0"
			(at 0 0 0)
			(unlocked yes)
			(layer "F.Fab")
			(hide yes)
			(effects
				(font
					(size 1 1)
					(thickness 0.15)
				)
			)
		)
		(property ki_fp_filters "IND_ACM9070_TDK")
		(sheetname "/USB/")
		(sheetfile "usb.kicad_sch")
		(attr smd)
		(fp_line
			(start -1 -0.8)
			(end 1 -0.8)
			(stroke
				(width 0.15)
				(type solid)
			)
			(layer "F.SilkS")
		)
		(fp_line
			(start 1 0.8)
			(end -1 0.8)
			(stroke
				(width 0.15)
				(type solid)
			)
			(layer "F.SilkS")
		)
		(fp_circle
			(center -1.475 0.775)
			(end -1.425 0.775)
			(stroke
				(width 0.15)
				(type solid)
			)
			(fill yes)
			(layer "F.SilkS")
		)
		(fp_rect
			(start -1.55 -0.85)
			(end 1.55 0.85)
			(stroke
				(width 0.05)
				(type solid)
			)
			(fill no)
			(layer "F.CrtYd")
		)
		(fp_line
			(start -1 0.35)
			(end -0.75 0.6)
			(stroke
				(width 0.15)
				(type solid)
			)
			(layer "F.Fab")
		)
		(fp_rect
			(start -1 -0.6)
			(end 1 0.6)
			(stroke
				(width 0.15)
				(type solid)
			)
			(fill no)
			(layer "F.Fab")
		)
		(fp_text user "License: Apache-2.0"
			(at -1.55 6.178 0)
			(layer "F.Fab")
			(effects
				(font
					(size 0.7 0.7)
					(thickness 0.15)
				)
				(justify left bottom)
			)
		)
		(fp_text user "Author: Antmicro"
			(at -1.55 4.978 0)
			(layer "F.Fab")
			(effects
				(font
					(size 0.7 0.7)
					(thickness 0.15)
				)
				(justify left bottom)
			)
		)
		(fp_text user "${REFERENCE}"
			(at -1.55 3.778 0)
			(layer "F.Fab")
			(effects
				(font
					(size 0.7 0.7)
					(thickness 0.15)
				)
				(justify left bottom)
			)
		)
		(pad "1" smd roundrect
			(at -0.85 0.4)
			(size 0.9 0.4)
			(layers "F.Cu" "F.Mask" "F.Paste")
			(roundrect_rratio 0.1)
			(net 209 "/USB/DD_P")
			(pinfunction "1")
			(pintype "passive")
		)
		(pad "2" smd roundrect
			(at 0.85 0.4)
			(size 0.9 0.4)
			(layers "F.Cu" "F.Mask" "F.Paste")
			(roundrect_rratio 0.1)
			(net 278 "/USB/USBD.D_P")
			(pinfunction "2")
			(pintype "passive")
		)
		(pad "3" smd roundrect
			(at 0.85 -0.4)
			(size 0.9 0.4)
			(layers "F.Cu" "F.Mask" "F.Paste")
			(roundrect_rratio 0.1)
			(net 277 "/USB/USBD.D_N")
			(pinfunction "3")
			(pintype "passive")
		)
		(pad "4" smd roundrect
			(at -0.85 -0.4)
			(size 0.9 0.4)
			(layers "F.Cu" "F.Mask" "F.Paste")
			(roundrect_rratio 0.1)
			(net 210 "/USB/DD_N")
			(pinfunction "4")
			(pintype "passive")
		)
	)
	(footprint "antmicro-footprints:R_0402_1005Metric"
		(layer "F.Cu")
		(at 132.937962 161.4965 90)
		(descr "Resistor SMD 0402")
		(tags "resistor SMD 0402")
		(property "Reference" "R605"
			(at -1.23 -1.81 90)
			(layer "F.SilkS")
			(effects
				(font
					(size 0.7 0.7)
					(thickness 0.15)
				)
				(justify left bottom)
			)
		)
		(property "Value" "R_4k7_0402"
			(at -1.011843 1.772047 90)
			(layer "F.Fab")
			(effects
				(font
					(size 0.7 0.7)
					(thickness 0.15)
				)
				(justify left bottom)
			)
		)
		(property "Datasheet" "https://www.bourns.com/docs/product-datasheets/cr.pdf"
			(at 0 0 90)
			(layer "F.Fab")
			(hide yes)
			(effects
				(font
					(size 1.27 1.27)
					(thickness 0.15)
				)
			)
		)
		(property "Manufacturer" "Bourns"
			(at 0 0 90)
			(unlocked yes)
			(layer "F.Fab")
			(hide yes)
			(effects
				(font
					(size 1 1)
					(thickness 0.15)
				)
			)
		)
		(property "MPN" "CR0402-FX-4701GLF"
			(at 0 0 90)
			(unlocked yes)
			(layer "F.Fab")
			(hide yes)
			(effects
				(font
					(size 1 1)
					(thickness 0.15)
				)
			)
		)
		(property "Val" "4k7"
			(at 0 0 90)
			(unlocked yes)
			(layer "F.Fab")
			(hide yes)
			(effects
				(font
					(size 1 1)
					(thickness 0.15)
				)
			)
		)
		(property "License" "Apache-2.0"
			(at 0 0 90)
			(unlocked yes)
			(layer "F.Fab")
			(hide yes)
			(effects
				(font
					(size 1 1)
					(thickness 0.15)
				)
			)
		)
		(property "Author" "Antmicro"
			(at 0 0 90)
			(unlocked yes)
			(layer "F.Fab")
			(hide yes)
			(effects
				(font
					(size 1 1)
					(thickness 0.15)
				)
			)
		)
		(property "Tolerance" "1%"
			(at 0 0 90)
			(unlocked yes)
			(layer "F.Fab")
			(hide yes)
			(effects
				(font
					(size 1 1)
					(thickness 0.15)
				)
			)
		)
		(sheetname "/CSI/")
		(sheetfile "csi.kicad_sch")
		(attr smd)
		(fp_rect
			(start -0.925 -0.47)
			(end 0.925 0.47)
			(stroke
				(width 0.05)
				(type default)
			)
			(fill no)
			(layer "F.CrtYd")
		)
		(fp_rect
			(start -0.5 -0.25)
			(end 0.5 0.25)
			(stroke
				(width 0.15)
				(type solid)
			)
			(fill no)
			(layer "F.Fab")
		)
		(fp_text user "${REFERENCE}"
			(at -0.95 3.168 90)
			(layer "F.Fab")
			(effects
				(font
					(size 0.7 0.7)
					(thickness 0.15)
				)
				(justify left bottom)
			)
		)
		(fp_text user "License: Apache-2.0"
			(at -0.95 5.169 90)
			(layer "F.Fab")
			(effects
				(font
					(size 0.7 0.7)
					(thickness 0.15)
				)
				(justify left bottom)
			)
		)
		(fp_text user "Author: Antmicro"
			(at -0.95 4.169 90)
			(layer "F.Fab")
			(effects
				(font
					(size 0.7 0.7)
					(thickness 0.15)
				)
				(justify left bottom)
			)
		)
		(pad "1" smd roundrect
			(at -0.48 0 90)
			(size 0.59 0.64)
			(layers "F.Cu" "F.Mask" "F.Paste")
			(roundrect_rratio 0.25)
			(net 3 "GND")
			(pintype "passive")
		)
		(pad "2" smd roundrect
			(at 0.48 0 90)
			(size 0.59 0.64)
			(layers "F.Cu" "F.Mask" "F.Paste")
			(roundrect_rratio 0.25)
			(net 373 "Net-(U602-ISET)")
			(pintype "passive")
		)
	)
	(footprint "antmicro-footprints:R_0402_1005Metric"
		(layer "F.Cu")
		(at 46.542962 130.7665)
		(descr "Resistor SMD 0402")
		(tags "resistor SMD 0402")
		(property "Reference" "R402"
			(at -3.975 0.4 0)
			(layer "F.SilkS")
			(effects
				(font
					(size 0.7 0.7)
					(thickness 0.15)
				)
				(justify left bottom)
			)
		)
		(property "Value" "R_49k9_0402"
			(at -1.011843 1.772047 0)
			(layer "F.Fab")
			(effects
				(font
					(size 0.7 0.7)
					(thickness 0.15)
				)
				(justify left bottom)
			)
		)
		(property "Datasheet" "https://www.bourns.com/docs/product-datasheets/cr.pdf"
			(at 0 0 0)
			(layer "F.Fab")
			(hide yes)
			(effects
				(font
					(size 1.27 1.27)
					(thickness 0.15)
				)
			)
		)
		(property "Manufacturer" "Bourns"
			(at 0 0 0)
			(unlocked yes)
			(layer "F.Fab")
			(hide yes)
			(effects
				(font
					(size 1 1)
					(thickness 0.15)
				)
			)
		)
		(property "MPN" "CR0402-FX-4992GLF"
			(at 0 0 0)
			(unlocked yes)
			(layer "F.Fab")
			(hide yes)
			(effects
				(font
					(size 1 1)
					(thickness 0.15)
				)
			)
		)
		(property "Val" "49k9"
			(at 0 0 0)
			(unlocked yes)
			(layer "F.Fab")
			(hide yes)
			(effects
				(font
					(size 1 1)
					(thickness 0.15)
				)
			)
		)
		(property "License" "Apache-2.0"
			(at 0 0 0)
			(unlocked yes)
			(layer "F.Fab")
			(hide yes)
			(effects
				(font
					(size 1 1)
					(thickness 0.15)
				)
			)
		)
		(property "Author" "Antmicro"
			(at 0 0 0)
			(unlocked yes)
			(layer "F.Fab")
			(hide yes)
			(effects
				(font
					(size 1 1)
					(thickness 0.15)
				)
			)
		)
		(property "Tolerance" "1%"
			(at 0 0 0)
			(unlocked yes)
			(layer "F.Fab")
			(hide yes)
			(effects
				(font
					(size 1 1)
					(thickness 0.15)
				)
			)
		)
		(sheetname "/Ethernet/")
		(sheetfile "ethernet.kicad_sch")
		(attr smd)
		(fp_rect
			(start -0.925 -0.47)
			(end 0.925 0.47)
			(stroke
				(width 0.05)
				(type default)
			)
			(fill no)
			(layer "F.CrtYd")
		)
		(fp_rect
			(start -0.5 -0.25)
			(end 0.5 0.25)
			(stroke
				(width 0.15)
				(type solid)
			)
			(fill no)
			(layer "F.Fab")
		)
		(fp_text user "Author: Antmicro"
			(at -0.95 4.169 0)
			(layer "F.Fab")
			(effects
				(font
					(size 0.7 0.7)
					(thickness 0.15)
				)
				(justify left bottom)
			)
		)
		(fp_text user "${REFERENCE}"
			(at -0.95 3.168 0)
			(layer "F.Fab")
			(effects
				(font
					(size 0.7 0.7)
					(thickness 0.15)
				)
				(justify left bottom)
			)
		)
		(fp_text user "License: Apache-2.0"
			(at -0.95 5.169 0)
			(layer "F.Fab")
			(effects
				(font
					(size 0.7 0.7)
					(thickness 0.15)
				)
				(justify left bottom)
			)
		)
		(pad "1" smd roundrect
			(at -0.48 0)
			(size 0.59 0.64)
			(layers "F.Cu" "F.Mask" "F.Paste")
			(roundrect_rratio 0.25)
			(net 90 "/Ethernet/VSS")
			(pintype "passive")
		)
		(pad "2" smd roundrect
			(at 0.48 0)
			(size 0.59 0.64)
			(layers "F.Cu" "F.Mask" "F.Paste")
			(roundrect_rratio 0.25)
			(net 357 "/Ethernet/REF")
			(pintype "passive")
		)
	)
	(footprint "antmicro-footprints:C_0402_1005Metric"
		(layer "F.Cu")
		(at 83.567962 151.1915 90)
		(descr "Capacitor SMD 0402")
		(tags "capacitor SMD 0402")
		(property "Reference" "C207"
			(at -1.105 -0.58 90)
			(layer "F.SilkS")
			(effects
				(font
					(size 0.7 0.7)
					(thickness 0.15)
				)
				(justify left bottom)
			)
		)
		(property "Value" "C_100n_0402"
			(at -1.022927 2.155213 90)
			(layer "F.Fab")
			(effects
				(font
					(size 0.7 0.7)
					(thickness 0.15)
				)
				(justify left bottom)
			)
		)
		(property "Datasheet" "https://www.murata.com/products/productdetail?partno=GRM155R61H104KE14%23"
			(at 0 0 90)
			(layer "F.Fab")
			(hide yes)
			(effects
				(font
					(size 1.27 1.27)
					(thickness 0.15)
				)
			)
		)
		(property "MPN" "GRM155R61H104KE14D"
			(at 0 0 90)
			(unlocked yes)
			(layer "F.Fab")
			(hide yes)
			(effects
				(font
					(size 1 1)
					(thickness 0.15)
				)
			)
		)
		(property "Manufacturer" "Murata"
			(at 0 0 90)
			(unlocked yes)
			(layer "F.Fab")
			(hide yes)
			(effects
				(font
					(size 1 1)
					(thickness 0.15)
				)
			)
		)
		(property "License" "Apache-2.0"
			(at 0 0 90)
			(unlocked yes)
			(layer "F.Fab")
			(hide yes)
			(effects
				(font
					(size 1 1)
					(thickness 0.15)
				)
			)
		)
		(property "Author" "Antmicro"
			(at 0 0 90)
			(unlocked yes)
			(layer "F.Fab")
			(hide yes)
			(effects
				(font
					(size 1 1)
					(thickness 0.15)
				)
			)
		)
		(property "Val" "100n"
			(at 0 0 90)
			(unlocked yes)
			(layer "F.Fab")
			(hide yes)
			(effects
				(font
					(size 1 1)
					(thickness 0.15)
				)
			)
		)
		(property "Voltage" "50V"
			(at 0 0 90)
			(unlocked yes)
			(layer "F.Fab")
			(hide yes)
			(effects
				(font
					(size 1 1)
					(thickness 0.15)
				)
			)
		)
		(property "Dielectric" "X5R"
			(at 0 0 90)
			(unlocked yes)
			(layer "F.Fab")
			(hide yes)
			(effects
				(font
					(size 1 1)
					(thickness 0.15)
				)
			)
		)
		(sheetname "/Compute module/")
		(sheetfile "compute-module.kicad_sch")
		(attr smd)
		(fp_rect
			(start -0.925 -0.47)
			(end 0.925 0.47)
			(stroke
				(width 0.05)
				(type default)
			)
			(fill no)
			(layer "F.CrtYd")
		)
		(fp_line
			(start 0.504 -0.25)
			(end 0.504 0.248)
			(stroke
				(width 0.15)
				(type solid)
			)
			(layer "F.Fab")
		)
		(fp_line
			(start -0.494 -0.25)
			(end 0.504 -0.25)
			(stroke
				(width 0.15)
				(type solid)
			)
			(layer "F.Fab")
		)
		(fp_line
			(start 0.504 0.248)
			(end -0.494 0.248)
			(stroke
				(width 0.15)
				(type solid)
			)
			(layer "F.Fab")
		)
		(fp_line
			(start -0.494 0.248)
			(end -0.494 -0.25)
			(stroke
				(width 0.15)
				(type solid)
			)
			(layer "F.Fab")
		)
		(fp_text user "Author: Antmicro"
			(at -0.939 3.399 90)
			(layer "F.Fab")
			(effects
				(font
					(size 0.7 0.7)
					(thickness 0.15)
				)
				(justify left bottom)
			)
		)
		(fp_text user "${REFERENCE}"
			(at -0.939 4.599 90)
			(layer "F.Fab")
			(effects
				(font
					(size 0.7 0.7)
					(thickness 0.15)
				)
				(justify left bottom)
			)
		)
		(fp_text user "License: Apache-2.0"
			(at -0.939 5.799 90)
			(layer "F.Fab")
			(effects
				(font
					(size 0.7 0.7)
					(thickness 0.15)
				)
				(justify left bottom)
			)
		)
		(pad "1" smd roundrect
			(at -0.48 0 90)
			(size 0.59 0.64)
			(layers "F.Cu" "F.Mask" "F.Paste")
			(roundrect_rratio 0.25)
			(net 3 "GND")
			(pintype "passive")
		)
		(pad "2" smd roundrect
			(at 0.48 0 90)
			(size 0.59 0.64)
			(layers "F.Cu" "F.Mask" "F.Paste")
			(roundrect_rratio 0.25)
			(net 9 "+3V3")
			(pintype "passive")
		)
	)
	(footprint "antmicro-footprints:R_0402_1005Metric"
		(layer "F.Cu")
		(at 123.792962 166.9165)
		(descr "Resistor SMD 0402")
		(tags "resistor SMD 0402")
		(property "Reference" "R509"
			(at -3.825 0.4 0)
			(layer "F.SilkS")
			(effects
				(font
					(size 0.7 0.7)
					(thickness 0.15)
				)
				(justify left bottom)
			)
		)
		(property "Value" "R_10k_0402"
			(at -1.011843 1.772047 0)
			(layer "F.Fab")
			(effects
				(font
					(size 0.7 0.7)
					(thickness 0.15)
				)
				(justify left bottom)
			)
		)
		(property "Datasheet" "https://www.bourns.com/docs/product-datasheets/cr.pdf"
			(at 0 0 0)
			(layer "F.Fab")
			(hide yes)
			(effects
				(font
					(size 1.27 1.27)
					(thickness 0.15)
				)
			)
		)
		(property "Manufacturer" "Bourns"
			(at 0 0 0)
			(unlocked yes)
			(layer "F.Fab")
			(hide yes)
			(effects
				(font
					(size 1 1)
					(thickness 0.15)
				)
			)
		)
		(property "MPN" "CR0402-FX-1002GLF"
			(at 0 0 0)
			(unlocked yes)
			(layer "F.Fab")
			(hide yes)
			(effects
				(font
					(size 1 1)
					(thickness 0.15)
				)
			)
		)
		(property "Val" "10k"
			(at 0 0 0)
			(unlocked yes)
			(layer "F.Fab")
			(hide yes)
			(effects
				(font
					(size 1 1)
					(thickness 0.15)
				)
			)
		)
		(property "License" "Apache-2.0"
			(at 0 0 0)
			(unlocked yes)
			(layer "F.Fab")
			(hide yes)
			(effects
				(font
					(size 1 1)
					(thickness 0.15)
				)
			)
		)
		(property "Author" "Antmicro"
			(at 0 0 0)
			(unlocked yes)
			(layer "F.Fab")
			(hide yes)
			(effects
				(font
					(size 1 1)
					(thickness 0.15)
				)
			)
		)
		(property "Tolerance" "1%"
			(at 0 0 0)
			(unlocked yes)
			(layer "F.Fab")
			(hide yes)
			(effects
				(font
					(size 1 1)
					(thickness 0.15)
				)
			)
		)
		(sheetname "/NVMe & microSD/")
		(sheetfile "nvme-micro-sd.kicad_sch")
		(attr smd)
		(fp_rect
			(start -0.925 -0.47)
			(end 0.925 0.47)
			(stroke
				(width 0.05)
				(type default)
			)
			(fill no)
			(layer "F.CrtYd")
		)
		(fp_rect
			(start -0.5 -0.25)
			(end 0.5 0.25)
			(stroke
				(width 0.15)
				(type solid)
			)
			(fill no)
			(layer "F.Fab")
		)
		(fp_text user "License: Apache-2.0"
			(at -0.95 5.169 0)
			(layer "F.Fab")
			(effects
				(font
					(size 0.7 0.7)
					(thickness 0.15)
				)
				(justify left bottom)
			)
		)
		(fp_text user "Author: Antmicro"
			(at -0.95 4.169 0)
			(layer "F.Fab")
			(effects
				(font
					(size 0.7 0.7)
					(thickness 0.15)
				)
				(justify left bottom)
			)
		)
		(fp_text user "${REFERENCE}"
			(at -0.95 3.168 0)
			(layer "F.Fab")
			(effects
				(font
					(size 0.7 0.7)
					(thickness 0.15)
				)
				(justify left bottom)
			)
		)
		(pad "1" smd roundrect
			(at -0.48 0)
			(size 0.59 0.64)
			(layers "F.Cu" "F.Mask" "F.Paste")
			(roundrect_rratio 0.25)
			(net 9 "+3V3")
			(pintype "passive")
		)
		(pad "2" smd roundrect
			(at 0.48 0)
			(size 0.59 0.64)
			(layers "F.Cu" "F.Mask" "F.Paste")
			(roundrect_rratio 0.25)
			(net 11 "/Compute module/SDIO.D3")
			(pintype "passive")
		)
	)
	(footprint "antmicro-footprints:TP_SMD_0.75mm"
		(layer "F.Cu")
		(at 118.142962 126.2415 180)
		(property "Reference" "TP503"
			(at -3.85 -0.5 0)
			(layer "F.SilkS")
			(effects
				(font
					(size 0.7 0.7)
					(thickness 0.15)
				)
				(justify right bottom)
			)
		)
		(property "Value" "TP_0.75mm_SMD"
			(at 0 1.2 0)
			(layer "F.Fab")
			(effects
				(font
					(size 0.7 0.7)
					(thickness 0.15)
				)
				(justify right bottom)
			)
		)
		(property "MPN" ""
			(at 0 0 180)
			(unlocked yes)
			(layer "F.Fab")
			(hide yes)
			(effects
				(font
					(size 1 1)
					(thickness 0.15)
				)
			)
		)
		(property "Manufacturer" ""
			(at 0 0 180)
			(unlocked yes)
			(layer "F.Fab")
			(hide yes)
			(effects
				(font
					(size 1 1)
					(thickness 0.15)
				)
			)
		)
		(property "Author" "Antmicro"
			(at 0 0 180)
			(unlocked yes)
			(layer "F.Fab")
			(hide yes)
			(effects
				(font
					(size 1 1)
					(thickness 0.15)
				)
			)
		)
		(property "License" "Apache-2.0"
			(at 0 0 180)
			(unlocked yes)
			(layer "F.Fab")
			(hide yes)
			(effects
				(font
					(size 1 1)
					(thickness 0.15)
				)
			)
		)
		(sheetname "/NVMe & microSD/")
		(sheetfile "nvme-micro-sd.kicad_sch")
		(attr exclude_from_pos_files exclude_from_bom)
		(fp_circle
			(center 0 0)
			(end 0.475 0)
			(stroke
				(width 0.05)
				(type default)
			)
			(fill no)
			(layer "F.CrtYd")
		)
		(fp_text user "Author: Antmicro"
			(at -0.4 3.901 180)
			(layer "F.Fab")
			(effects
				(font
					(size 0.7 0.7)
					(thickness 0.15)
				)
				(justify left bottom)
			)
		)
		(fp_text user "License: Apache-2.0"
			(at -0.4 5.101 180)
			(layer "F.Fab")
			(effects
				(font
					(size 0.7 0.7)
					(thickness 0.15)
				)
				(justify left bottom)
			)
		)
		(fp_text user "${REFERENCE}"
			(at -0.4 2.7 180)
			(layer "F.Fab")
			(effects
				(font
					(size 0.7 0.7)
					(thickness 0.15)
				)
				(justify left bottom)
			)
		)
		(pad "1" smd circle
			(at 0 0 180)
			(size 0.75 0.75)
			(layers "F.Cu" "F.Mask")
			(net 192 "Net-(J501-SMB_DATA)")
			(pinfunction "1")
			(pintype "passive")
		)
	)
	(footprint "antmicro-footprints:Nexperia_DFN-10_2.5x1mm_P0.5mm"
		(layer "F.Cu")
		(at 142.292962 150.3415 90)
		(property "Reference" "D801"
			(at -5.575 1.225 90)
			(layer "F.SilkS")
			(effects
				(font
					(size 0.7 0.7)
					(thickness 0.15)
				)
				(justify left bottom)
			)
		)
		(property "Value" "PUSB3F96X_PASS"
			(at -0.016 1.705 90)
			(layer "F.Fab")
			(effects
				(font
					(size 0.7 0.7)
					(thickness 0.15)
				)
				(justify left bottom)
			)
		)
		(property "Datasheet" "https://mouser.com/datasheet/2/916/PUSB3F96-1600324.pdf"
			(at 0 0 90)
			(layer "F.Fab")
			(hide yes)
			(effects
				(font
					(size 1.27 1.27)
					(thickness 0.15)
				)
			)
		)
		(property "Manufacturer" "Nexperia"
			(at 0 0 90)
			(unlocked yes)
			(layer "F.Fab")
			(hide yes)
			(effects
				(font
					(size 1 1)
					(thickness 0.15)
				)
			)
		)
		(property "MPN" "PUSB3F96X"
			(at 0 0 90)
			(unlocked yes)
			(layer "F.Fab")
			(hide yes)
			(effects
				(font
					(size 1 1)
					(thickness 0.15)
				)
			)
		)
		(property "Author" "Antmicro"
			(at 0 0 90)
			(unlocked yes)
			(layer "F.Fab")
			(hide yes)
			(effects
				(font
					(size 1 1)
					(thickness 0.15)
				)
			)
		)
		(property "License" "Apache-2.0"
			(at 0 0 90)
			(unlocked yes)
			(layer "F.Fab")
			(hide yes)
			(effects
				(font
					(size 1 1)
					(thickness 0.15)
				)
			)
		)
		(sheetname "/Peripherals/")
		(sheetfile "peripherals.kicad_sch")
		(attr smd)
		(fp_line
			(start -1.375 -0.4)
			(end -1.375 0.4)
			(stroke
				(width 0.15)
				(type solid)
			)
			(layer "F.SilkS")
		)
		(fp_line
			(start 1.375 0.4)
			(end 1.375 -0.4)
			(stroke
				(width 0.15)
				(type solid)
			)
			(layer "F.SilkS")
		)
		(fp_circle
			(center -1.4 0.7)
			(end -1.349 0.7)
			(stroke
				(width 0.15)
				(type solid)
			)
			(fill yes)
			(layer "F.SilkS")
		)
		(fp_rect
			(start -1.4 -0.725)
			(end 1.4 0.725)
			(stroke
				(width 0.05)
				(type solid)
			)
			(fill no)
			(layer "F.CrtYd")
		)
		(fp_line
			(start 1.25 -0.5)
			(end -1.25 -0.5)
			(stroke
				(width 0.15)
				(type solid)
			)
			(layer "F.Fab")
		)
		(fp_line
			(start -1.25 -0.5)
			(end -1.25 0.15)
			(stroke
				(width 0.15)
				(type solid)
			)
			(layer "F.Fab")
		)
		(fp_line
			(start -1.25 0.15)
			(end -0.9 0.5)
			(stroke
				(width 0.15)
				(type solid)
			)
			(layer "F.Fab")
		)
		(fp_line
			(start 1.25 0.5)
			(end 1.25 -0.5)
			(stroke
				(width 0.15)
				(type solid)
			)
			(layer "F.Fab")
		)
		(fp_line
			(start -0.9 0.5)
			(end 1.25 0.5)
			(stroke
				(width 0.15)
				(type solid)
			)
			(layer "F.Fab")
		)
		(fp_text user "License: Apache-2.0"
			(at -1.367 6.105 90)
			(layer "F.Fab")
			(effects
				(font
					(size 0.7 0.7)
					(thickness 0.15)
				)
				(justify left bottom)
			)
		)
		(fp_text user "Author: Antmicro"
			(at -1.367 4.905 90)
			(layer "F.Fab")
			(effects
				(font
					(size 0.7 0.7)
					(thickness 0.15)
				)
				(justify left bottom)
			)
		)
		(fp_text user "${REFERENCE}"
			(at -1.367 3.704 90)
			(layer "F.Fab")
			(effects
				(font
					(size 0.7 0.7)
					(thickness 0.15)
				)
				(justify left bottom)
			)
		)
		(pad "1" smd rect
			(at -1 0.3875 90)
			(size 0.2 0.475)
			(layers "F.Cu" "F.Mask" "F.Paste")
			(net 9 "+3V3")
			(pinfunction "CH1")
			(pintype "passive")
			(solder_mask_margin 0.05)
		)
		(pad "2" smd rect
			(at -0.5 0.3875 90)
			(size 0.2 0.475)
			(layers "F.Cu" "F.Mask" "F.Paste")
			(net 243 "/Compute module/GPIO.2")
			(pinfunction "CH2")
			(pintype "passive")
			(solder_mask_margin 0.05)
		)
		(pad "3" smd rect
			(at 0 0.3875 90)
			(size 0.2 0.475)
			(layers "F.Cu" "F.Mask" "F.Paste")
			(net 3 "GND")
			(pinfunction "GND")
			(pintype "passive")
			(solder_mask_margin 0.05)
		)
		(pad "4" smd rect
			(at 0.5 0.3875 90)
			(size 0.2 0.475)
			(layers "F.Cu" "F.Mask" "F.Paste")
			(net 242 "/Compute module/GPIO.3")
			(pinfunction "CH3")
			(pintype "passive")
			(solder_mask_margin 0.05)
		)
		(pad "5" smd rect
			(at 1 0.3875 90)
			(size 0.2 0.475)
			(layers "F.Cu" "F.Mask" "F.Paste")
			(net 240 "/Compute module/GPIO.4{slash}TXD3")
			(pinfunction "CH4")
			(pintype "passive")
			(solder_mask_margin 0.05)
		)
		(pad "6" smd rect
			(at 1 -0.3875 90)
			(size 0.2 0.475)
			(layers "F.Cu" "F.Mask" "F.Paste")
			(net 240 "/Compute module/GPIO.4{slash}TXD3")
			(pinfunction "CH4")
			(pintype "passive")
			(solder_mask_margin 0.05)
		)
		(pad "7" smd rect
			(at 0.5 -0.3875 90)
			(size 0.2 0.475)
			(layers "F.Cu" "F.Mask" "F.Paste")
			(net 242 "/Compute module/GPIO.3")
			(pinfunction "CH3")
			(pintype "passive")
			(solder_mask_margin 0.05)
		)
		(pad "8" smd rect
			(at 0 -0.3875 90)
			(size 0.2 0.475)
			(layers "F.Cu" "F.Mask" "F.Paste")
			(net 3 "GND")
			(pinfunction "GND")
			(pintype "passive")
			(solder_mask_margin 0.05)
		)
		(pad "9" smd rect
			(at -0.501 -0.3875 90)
			(size 0.2 0.475)
			(layers "F.Cu" "F.Mask" "F.Paste")
			(net 243 "/Compute module/GPIO.2")
			(pinfunction "CH2")
			(pintype "passive")
			(solder_mask_margin 0.05)
		)
		(pad "10" smd rect
			(at -1 -0.3875 90)
			(size 0.2 0.475)
			(layers "F.Cu" "F.Mask" "F.Paste")
			(net 9 "+3V3")
			(pinfunction "CH1")
			(pintype "passive")
			(solder_mask_margin 0.05)
		)
	)
	(footprint "antmicro-footprints:Nexperia_DFN-10_2.5x1mm_P0.5mm"
		(layer "F.Cu")
		(at 122.987962 118.8965)
		(property "Reference" "D805"
			(at -2.99 2.18 0)
			(layer "F.SilkS")
			(effects
				(font
					(size 0.7 0.7)
					(thickness 0.15)
				)
				(justify left bottom)
			)
		)
		(property "Value" "PUSB3F96X_PASS"
			(at -0.016 1.705 0)
			(layer "F.Fab")
			(effects
				(font
					(size 0.7 0.7)
					(thickness 0.15)
				)
				(justify left bottom)
			)
		)
		(property "Datasheet" "https://mouser.com/datasheet/2/916/PUSB3F96-1600324.pdf"
			(at 0 0 0)
			(layer "F.Fab")
			(hide yes)
			(effects
				(font
					(size 1.27 1.27)
					(thickness 0.15)
				)
			)
		)
		(property "Manufacturer" "Nexperia"
			(at 0 0 0)
			(unlocked yes)
			(layer "F.Fab")
			(hide yes)
			(effects
				(font
					(size 1 1)
					(thickness 0.15)
				)
			)
		)
		(property "MPN" "PUSB3F96X"
			(at 0 0 0)
			(unlocked yes)
			(layer "F.Fab")
			(hide yes)
			(effects
				(font
					(size 1 1)
					(thickness 0.15)
				)
			)
		)
		(property "Author" "Antmicro"
			(at 0 0 0)
			(unlocked yes)
			(layer "F.Fab")
			(hide yes)
			(effects
				(font
					(size 1 1)
					(thickness 0.15)
				)
			)
		)
		(property "License" "Apache-2.0"
			(at 0 0 0)
			(unlocked yes)
			(layer "F.Fab")
			(hide yes)
			(effects
				(font
					(size 1 1)
					(thickness 0.15)
				)
			)
		)
		(sheetname "/Peripherals/")
		(sheetfile "peripherals.kicad_sch")
		(attr smd)
		(fp_line
			(start -1.375 -0.4)
			(end -1.375 0.4)
			(stroke
				(width 0.15)
				(type solid)
			)
			(layer "F.SilkS")
		)
		(fp_line
			(start 1.375 0.4)
			(end 1.375 -0.4)
			(stroke
				(width 0.15)
				(type solid)
			)
			(layer "F.SilkS")
		)
		(fp_circle
			(center -1.4 0.7)
			(end -1.349 0.7)
			(stroke
				(width 0.15)
				(type solid)
			)
			(fill yes)
			(layer "F.SilkS")
		)
		(fp_rect
			(start -1.4 -0.725)
			(end 1.4 0.725)
			(stroke
				(width 0.05)
				(type solid)
			)
			(fill no)
			(layer "F.CrtYd")
		)
		(fp_line
			(start -1.25 -0.5)
			(end -1.25 0.15)
			(stroke
				(width 0.15)
				(type solid)
			)
			(layer "F.Fab")
		)
		(fp_line
			(start -1.25 0.15)
			(end -0.9 0.5)
			(stroke
				(width 0.15)
				(type solid)
			)
			(layer "F.Fab")
		)
		(fp_line
			(start -0.9 0.5)
			(end 1.25 0.5)
			(stroke
				(width 0.15)
				(type solid)
			)
			(layer "F.Fab")
		)
		(fp_line
			(start 1.25 -0.5)
			(end -1.25 -0.5)
			(stroke
				(width 0.15)
				(type solid)
			)
			(layer "F.Fab")
		)
		(fp_line
			(start 1.25 0.5)
			(end 1.25 -0.5)
			(stroke
				(width 0.15)
				(type solid)
			)
			(layer "F.Fab")
		)
		(fp_text user "License: Apache-2.0"
			(at -1.367 6.105 0)
			(layer "F.Fab")
			(effects
				(font
					(size 0.7 0.7)
					(thickness 0.15)
				)
				(justify left bottom)
			)
		)
		(fp_text user "${REFERENCE}"
			(at -1.367 3.704 0)
			(layer "F.Fab")
			(effects
				(font
					(size 0.7 0.7)
					(thickness 0.15)
				)
				(justify left bottom)
			)
		)
		(fp_text user "Author: Antmicro"
			(at -1.367 4.905 0)
			(layer "F.Fab")
			(effects
				(font
					(size 0.7 0.7)
					(thickness 0.15)
				)
				(justify left bottom)
			)
		)
		(pad "1" smd rect
			(at -1 0.3875)
			(size 0.2 0.475)
			(layers "F.Cu" "F.Mask" "F.Paste")
			(net 142 "/CSI/I_{2}C1.SCL")
			(pinfunction "CH1")
			(pintype "passive")
			(solder_mask_margin 0.05)
		)
		(pad "2" smd rect
			(at -0.5 0.3875)
			(size 0.2 0.475)
			(layers "F.Cu" "F.Mask" "F.Paste")
			(net 143 "/CSI/I_{2}C1.SDA")
			(pinfunction "CH2")
			(pintype "passive")
			(solder_mask_margin 0.05)
		)
		(pad "3" smd rect
			(at 0 0.3875)
			(size 0.2 0.475)
			(layers "F.Cu" "F.Mask" "F.Paste")
			(net 3 "GND")
			(pinfunction "GND")
			(pintype "passive")
			(solder_mask_margin 0.05)
		)
		(pad "4" smd rect
			(at 0.5 0.3875)
			(size 0.2 0.475)
			(layers "F.Cu" "F.Mask" "F.Paste")
			(net 9 "+3V3")
			(pinfunction "CH3")
			(pintype "passive")
			(solder_mask_margin 0.05)
		)
		(pad "5" smd rect
			(at 1 0.3875)
			(size 0.2 0.475)
			(layers "F.Cu" "F.Mask" "F.Paste")
			(net 3 "GND")
			(pinfunction "CH4")
			(pintype "passive")
			(solder_mask_margin 0.05)
		)
		(pad "6" smd rect
			(at 1 -0.3875)
			(size 0.2 0.475)
			(layers "F.Cu" "F.Mask" "F.Paste")
			(net 3 "GND")
			(pinfunction "CH4")
			(pintype "passive")
			(solder_mask_margin 0.05)
		)
		(pad "7" smd rect
			(at 0.5 -0.3875)
			(size 0.2 0.475)
			(layers "F.Cu" "F.Mask" "F.Paste")
			(net 9 "+3V3")
			(pinfunction "CH3")
			(pintype "passive")
			(solder_mask_margin 0.05)
		)
		(pad "8" smd rect
			(at 0 -0.3875)
			(size 0.2 0.475)
			(layers "F.Cu" "F.Mask" "F.Paste")
			(net 3 "GND")
			(pinfunction "GND")
			(pintype "passive")
			(solder_mask_margin 0.05)
		)
		(pad "9" smd rect
			(at -0.501 -0.3875)
			(size 0.2 0.475)
			(layers "F.Cu" "F.Mask" "F.Paste")
			(net 143 "/CSI/I_{2}C1.SDA")
			(pinfunction "CH2")
			(pintype "passive")
			(solder_mask_margin 0.05)
		)
		(pad "10" smd rect
			(at -1 -0.3875)
			(size 0.2 0.475)
			(layers "F.Cu" "F.Mask" "F.Paste")
			(net 142 "/CSI/I_{2}C1.SCL")
			(pinfunction "CH1")
			(pintype "passive")
			(solder_mask_margin 0.05)
		)
	)
	(footprint "antmicro-footprints:Conn_Socket_Hirose_DF40_2x50_DF40HC-3.0-100DS-0.4V"
		(layer "F.Cu")
		(at 114.020961 154.714 -90)
		(property "Reference" "J202"
			(at -8.7975 2.432999 90)
			(layer "F.SilkS")
			(effects
				(font
					(size 0.7 0.7)
					(thickness 0.15)
				)
				(justify left bottom)
			)
		)
		(property "Value" "Socket_Hirose_DF40_2x50_DF40HC-3.0-100DS-0.4V"
			(at 0 3.25 90)
			(layer "F.Fab")
			(effects
				(font
					(size 0.7 0.7)
					(thickness 0.15)
				)
				(justify left bottom)
			)
		)
		(property "Datasheet" "https://www.hirose.com/en/product/document?clcode=CL0684-4151-0-51&productname=DF40HC(3.0)-100DS-0.4V(51&series=DF40&documenttype=Catalog&lang=en&documentid=en_DF40_CAT"
			(at 0 0 270)
			(layer "F.Fab")
			(hide yes)
			(effects
				(font
					(size 1.27 1.27)
					(thickness 0.15)
				)
			)
		)
		(property "Manufacturer" "Hirose Electric"
			(at 0 0 270)
			(unlocked yes)
			(layer "F.Fab")
			(hide yes)
			(effects
				(font
					(size 1 1)
					(thickness 0.15)
				)
			)
		)
		(property "MPN" "DF40HC(3.0)-100DS-0.4V(51)"
			(at 0 0 270)
			(unlocked yes)
			(layer "F.Fab")
			(hide yes)
			(effects
				(font
					(size 1 1)
					(thickness 0.15)
				)
			)
		)
		(property "Author" "Antmicro"
			(at 0 0 270)
			(unlocked yes)
			(layer "F.Fab")
			(hide yes)
			(effects
				(font
					(size 1 1)
					(thickness 0.15)
				)
			)
		)
		(property "License" "Apache-2.0"
			(at 0 0 270)
			(unlocked yes)
			(layer "F.Fab")
			(hide yes)
			(effects
				(font
					(size 1 1)
					(thickness 0.15)
				)
			)
		)
		(property "Pitch" "0.4 mm"
			(at 0 0 270)
			(unlocked yes)
			(layer "F.Fab")
			(hide yes)
			(effects
				(font
					(size 1 1)
					(thickness 0.15)
				)
			)
		)
		(sheetname "/Compute module/")
		(sheetfile "compute-module.kicad_sch")
		(attr smd)
		(fp_line
			(start -11.298 1.446)
			(end -10.077 1.446)
			(stroke
				(width 0.15)
				(type solid)
			)
			(layer "F.SilkS")
		)
		(fp_line
			(start -11.298 1.446)
			(end -11.298 -1.433)
			(stroke
				(width 0.15)
				(type solid)
			)
			(layer "F.SilkS")
		)
		(fp_line
			(start 11.303 1.446)
			(end 10.082 1.446)
			(stroke
				(width 0.15)
				(type solid)
			)
			(layer "F.SilkS")
		)
		(fp_line
			(start -11.298 -1.433)
			(end -10.077 -1.433)
			(stroke
				(width 0.15)
				(type solid)
			)
			(layer "F.SilkS")
		)
		(fp_line
			(start 11.303 -1.433)
			(end 11.303 1.446)
			(stroke
				(width 0.15)
				(type solid)
			)
			(layer "F.SilkS")
		)
		(fp_line
			(start 11.303 -1.433)
			(end 10.082 -1.433)
			(stroke
				(width 0.15)
				(type solid)
			)
			(layer "F.SilkS")
		)
		(fp_circle
			(center -10.1 1.7)
			(end -10.05 1.7)
			(stroke
				(width 0.15)
				(type solid)
			)
			(fill yes)
			(layer "F.SilkS")
		)
		(fp_rect
			(start -11.55 -2.14)
			(end 11.54 2.13)
			(stroke
				(width 0.05)
				(type solid)
			)
			(fill no)
			(layer "F.CrtYd")
		)
		(fp_line
			(start -11.298 1.446)
			(end -11.298 -1.433)
			(stroke
				(width 0.15)
				(type solid)
			)
			(layer "F.Fab")
		)
		(fp_line
			(start -10.077 1.446)
			(end -11.298 1.446)
			(stroke
				(width 0.15)
				(type solid)
			)
			(layer "F.Fab")
		)
		(fp_line
			(start 10.082 1.446)
			(end -10.058 1.446)
			(stroke
				(width 0.15)
				(type solid)
			)
			(layer "F.Fab")
		)
		(fp_line
			(start 11.303 1.446)
			(end 10.082 1.446)
			(stroke
				(width 0.15)
				(type solid)
			)
			(layer "F.Fab")
		)
		(fp_line
			(start -11.298 -1.433)
			(end -10.077 -1.433)
			(stroke
				(width 0.15)
				(type solid)
			)
			(layer "F.Fab")
		)
		(fp_line
			(start -10.077 -1.433)
			(end 10.082 -1.433)
			(stroke
				(width 0.15)
				(type solid)
			)
			(layer "F.Fab")
		)
		(fp_line
			(start 10.082 -1.433)
			(end 11.303 -1.433)
			(stroke
				(width 0.15)
				(type solid)
			)
			(layer "F.Fab")
		)
		(fp_line
			(start 11.303 -1.433)
			(end 11.303 1.446)
			(stroke
				(width 0.15)
				(type solid)
			)
			(layer "F.Fab")
		)
		(fp_text user "${REFERENCE}"
			(at -12.65 7.406 270)
			(layer "F.Fab")
			(effects
				(font
					(size 0.7 0.7)
					(thickness 0.15)
				)
				(justify left bottom)
			)
		)
		(fp_text user "License: Apache-2.0"
			(at -12.65 5.006 270)
			(layer "F.Fab")
			(effects
				(font
					(size 0.7 0.7)
					(thickness 0.15)
				)
				(justify left bottom)
			)
		)
		(fp_text user "Author: Antmicro"
			(at -12.65 6.206 270)
			(layer "F.Fab")
			(effects
				(font
					(size 0.7 0.7)
					(thickness 0.15)
				)
				(justify left bottom)
			)
		)
		(pad "1" smd rect
			(at -9.798 1.547 270)
			(size 0.2 0.7)
			(layers "F.Cu" "F.Mask" "F.Paste")
			(net 279 "/Compute module/USB.OTGID")
			(pintype "passive")
		)
		(pad "2" smd rect
			(at -9.798 -1.534 270)
			(size 0.2 0.7)
			(layers "F.Cu" "F.Mask" "F.Paste")
			(net 144 "/Compute module/NVMe.~{CLK_REQ}")
			(pintype "passive")
		)
		(pad "3" smd rect
			(at -9.398 1.547 270)
			(size 0.2 0.7)
			(layers "F.Cu" "F.Mask" "F.Paste")
			(net 38 "/Compute module/USB.D_N")
			(pintype "passive")
		)
		(pad "4" smd rect
			(at -9.398 -1.534 270)
			(size 0.2 0.7)
			(layers "F.Cu" "F.Mask" "F.Paste")
			(net 174 "unconnected-(J202-Pad4)")
			(pintype "passive+no_connect")
		)
		(pad "5" smd rect
			(at -8.997 1.547 270)
			(size 0.2 0.7)
			(layers "F.Cu" "F.Mask" "F.Paste")
			(net 39 "/Compute module/USB.D_P")
			(pintype "passive")
		)
		(pad "6" smd rect
			(at -8.997 -1.534 270)
			(size 0.2 0.7)
			(layers "F.Cu" "F.Mask" "F.Paste")
			(net 157 "unconnected-(J202-Pad6)")
			(pintype "passive+no_connect")
		)
		(pad "7" smd rect
			(at -8.597 1.547 270)
			(size 0.2 0.7)
			(layers "F.Cu" "F.Mask" "F.Paste")
			(net 3 "GND")
			(pintype "passive")
		)
		(pad "8" smd rect
			(at -8.597 -1.534 270)
			(size 0.2 0.7)
			(layers "F.Cu" "F.Mask" "F.Paste")
			(net 3 "GND")
			(pintype "passive")
		)
		(pad "9" smd rect
			(at -8.196 1.547 270)
			(size 0.2 0.7)
			(layers "F.Cu" "F.Mask" "F.Paste")
			(net 145 "/Compute module/NVMe.~{RST}")
			(pintype "passive")
		)
		(pad "10" smd rect
			(at -8.196 -1.534 270)
			(size 0.2 0.7)
			(layers "F.Cu" "F.Mask" "F.Paste")
			(net 40 "/Compute module/NVMe.CLK_P")
			(pintype "passive")
		)
		(pad "11" smd rect
			(at -7.797 1.547 270)
			(size 0.2 0.7)
			(layers "F.Cu" "F.Mask" "F.Paste")
			(net 256 "/Compute module/VDAC_COMP")
			(pintype "passive")
		)
		(pad "12" smd rect
			(at -7.797 -1.534 270)
			(size 0.2 0.7)
			(layers "F.Cu" "F.Mask" "F.Paste")
			(net 41 "/Compute module/NVMe.CLK_N")
			(pintype "passive")
		)
		(pad "13" smd rect
			(at -7.397 1.547 270)
			(size 0.2 0.7)
			(layers "F.Cu" "F.Mask" "F.Paste")
			(net 3 "GND")
			(pintype "passive")
		)
		(pad "14" smd rect
			(at -7.397 -1.534 270)
			(size 0.2 0.7)
			(layers "F.Cu" "F.Mask" "F.Paste")
			(net 3 "GND")
			(pintype "passive")
		)
		(pad "15" smd rect
			(at -6.997 1.547 270)
			(size 0.2 0.7)
			(layers "F.Cu" "F.Mask" "F.Paste")
			(net 42 "/CSI/CSI1.D0_N")
			(pintype "passive")
		)
		(pad "16" smd rect
			(at -6.997 -1.534 270)
			(size 0.2 0.7)
			(layers "F.Cu" "F.Mask" "F.Paste")
			(net 171 "/Compute module/NVMe.RX0_P")
			(pintype "passive")
		)
		(pad "17" smd rect
			(at -6.596 1.547 270)
			(size 0.2 0.7)
			(layers "F.Cu" "F.Mask" "F.Paste")
			(net 44 "/CSI/CSI1.D0_P")
			(pintype "passive")
		)
		(pad "18" smd rect
			(at -6.596 -1.534 270)
			(size 0.2 0.7)
			(layers "F.Cu" "F.Mask" "F.Paste")
			(net 170 "/Compute module/NVMe.RX0_N")
			(pintype "passive")
		)
		(pad "19" smd rect
			(at -6.197 1.547 270)
			(size 0.2 0.7)
			(layers "F.Cu" "F.Mask" "F.Paste")
			(net 3 "GND")
			(pintype "passive")
		)
		(pad "20" smd rect
			(at -6.197 -1.534 270)
			(size 0.2 0.7)
			(layers "F.Cu" "F.Mask" "F.Paste")
			(net 3 "GND")
			(pintype "passive")
		)
		(pad "21" smd rect
			(at -5.797 1.547 270)
			(size 0.2 0.7)
			(layers "F.Cu" "F.Mask" "F.Paste")
			(net 46 "/CSI/CSI1.D1_N")
			(pintype "passive")
		)
		(pad "22" smd rect
			(at -5.797 -1.534 270)
			(size 0.2 0.7)
			(layers "F.Cu" "F.Mask" "F.Paste")
			(net 173 "/Compute module/NVMe.TX0_P")
			(pintype "passive")
		)
		(pad "23" smd rect
			(at -5.398 1.547 270)
			(size 0.2 0.7)
			(layers "F.Cu" "F.Mask" "F.Paste")
			(net 50 "/CSI/CSI1.D1_P")
			(pintype "passive")
		)
		(pad "24" smd rect
			(at -5.398 -1.534 270)
			(size 0.2 0.7)
			(layers "F.Cu" "F.Mask" "F.Paste")
			(net 172 "/Compute module/NVMe.TX0_N")
			(pintype "passive")
		)
		(pad "25" smd rect
			(at -4.997 1.547 270)
			(size 0.2 0.7)
			(layers "F.Cu" "F.Mask" "F.Paste")
			(net 3 "GND")
			(pintype "passive")
		)
		(pad "26" smd rect
			(at -4.997 -1.534 270)
			(size 0.2 0.7)
			(layers "F.Cu" "F.Mask" "F.Paste")
			(net 3 "GND")
			(pintype "passive")
		)
		(pad "27" smd rect
			(at -4.596 1.547 270)
			(size 0.2 0.7)
			(layers "F.Cu" "F.Mask" "F.Paste")
			(net 52 "/CSI/CSI1.CLK_N")
			(pintype "passive")
		)
		(pad "28" smd rect
			(at -4.596 -1.534 270)
			(size 0.2 0.7)
			(layers "F.Cu" "F.Mask" "F.Paste")
			(net 53 "/CSI/CSI0.D0_N")
			(pintype "passive")
		)
		(pad "29" smd rect
			(at -4.197 1.547 270)
			(size 0.2 0.7)
			(layers "F.Cu" "F.Mask" "F.Paste")
			(net 54 "/CSI/CSI1.CLK_P")
			(pintype "passive")
		)
		(pad "30" smd rect
			(at -4.197 -1.534 270)
			(size 0.2 0.7)
			(layers "F.Cu" "F.Mask" "F.Paste")
			(net 55 "/CSI/CSI0.D0_P")
			(pintype "passive")
		)
		(pad "31" smd rect
			(at -3.795 1.547 270)
			(size 0.2 0.7)
			(layers "F.Cu" "F.Mask" "F.Paste")
			(net 3 "GND")
			(pintype "passive")
		)
		(pad "32" smd rect
			(at -3.795 -1.534 270)
			(size 0.2 0.7)
			(layers "F.Cu" "F.Mask" "F.Paste")
			(net 3 "GND")
			(pintype "passive")
		)
		(pad "33" smd rect
			(at -3.396 1.547 270)
			(size 0.2 0.7)
			(layers "F.Cu" "F.Mask" "F.Paste")
			(net 56 "/CSI/CSI1.D2_N")
			(pintype "passive")
		)
		(pad "34" smd rect
			(at -3.396 -1.534 270)
			(size 0.2 0.7)
			(layers "F.Cu" "F.Mask" "F.Paste")
			(net 57 "/CSI/CSI0.D1_N")
			(pintype "passive")
		)
		(pad "35" smd rect
			(at -2.997 1.547 270)
			(size 0.2 0.7)
			(layers "F.Cu" "F.Mask" "F.Paste")
			(net 58 "/CSI/CSI1.D2_P")
			(pintype "passive")
		)
		(pad "36" smd rect
			(at -2.997 -1.534 270)
			(size 0.2 0.7)
			(layers "F.Cu" "F.Mask" "F.Paste")
			(net 67 "/CSI/CSI0.D1_P")
			(pintype "passive")
		)
		(pad "37" smd rect
			(at -2.598 1.547 270)
			(size 0.2 0.7)
			(layers "F.Cu" "F.Mask" "F.Paste")
			(net 3 "GND")
			(pintype "passive")
		)
		(pad "38" smd rect
			(at -2.598 -1.534 270)
			(size 0.2 0.7)
			(layers "F.Cu" "F.Mask" "F.Paste")
			(net 3 "GND")
			(pintype "passive")
		)
		(pad "39" smd rect
			(at -2.198 1.547 270)
			(size 0.2 0.7)
			(layers "F.Cu" "F.Mask" "F.Paste")
			(net 68 "/CSI/CSI1.D3_N")
			(pintype "passive")
		)
		(pad "40" smd rect
			(at -2.198 -1.534 270)
			(size 0.2 0.7)
			(layers "F.Cu" "F.Mask" "F.Paste")
			(net 69 "/CSI/CSI0.CLK_N")
			(pintype "passive")
		)
		(pad "41" smd rect
			(at -1.798 1.547 270)
			(size 0.2 0.7)
			(layers "F.Cu" "F.Mask" "F.Paste")
			(net 70 "/CSI/CSI1.D3_P")
			(pintype "passive")
		)
		(pad "42" smd rect
			(at -1.798 -1.534 270)
			(size 0.2 0.7)
			(layers "F.Cu" "F.Mask" "F.Paste")
			(net 71 "/CSI/CSI0.CLK_P")
			(pintype "passive")
		)
		(pad "43" smd rect
			(at -1.396 1.547 270)
			(size 0.2 0.7)
			(layers "F.Cu" "F.Mask" "F.Paste")
			(net 257 "/Compute module/Pf_5V.HPD")
			(pintype "passive")
		)
		(pad "44" smd rect
			(at -1.396 -1.534 270)
			(size 0.2 0.7)
			(layers "F.Cu" "F.Mask" "F.Paste")
			(net 3 "GND")
			(pintype "passive")
		)
		(pad "45" smd rect
			(at -0.997 1.547 270)
			(size 0.2 0.7)
			(layers "F.Cu" "F.Mask" "F.Paste")
			(net 258 "/Compute module/Pf_5V.SDA")
			(pintype "passive")
		)
		(pad "46" smd rect
			(at -0.997 -1.534 270)
			(size 0.2 0.7)
			(layers "F.Cu" "F.Mask" "F.Paste")
			(net 139 "/Compute module/T1_P")
			(pintype "passive")
		)
		(pad "47" smd rect
			(at -0.597 1.547 270)
			(size 0.2 0.7)
			(layers "F.Cu" "F.Mask" "F.Paste")
			(net 259 "/Compute module/Pf_5V.SCL")
			(pintype "passive")
		)
		(pad "48" smd rect
			(at -0.597 -1.534 270)
			(size 0.2 0.7)
			(layers "F.Cu" "F.Mask" "F.Paste")
			(net 146 "/Compute module/T1_N")
			(pintype "passive")
		)
		(pad "49" smd rect
			(at -0.198 1.547 270)
			(size 0.2 0.7)
			(layers "F.Cu" "F.Mask" "F.Paste")
			(net 260 "/Compute module/Pf_5V.CEC")
			(pintype "passive")
		)
		(pad "50" smd rect
			(at -0.198 -1.534 270)
			(size 0.2 0.7)
			(layers "F.Cu" "F.Mask" "F.Paste")
			(net 3 "GND")
			(pintype "passive")
		)
		(pad "51" smd rect
			(at 0.203 1.547 270)
			(size 0.2 0.7)
			(layers "F.Cu" "F.Mask" "F.Paste")
			(net 261 "/Compute module/HDMI.CEC")
			(pintype "passive")
		)
		(pad "52" smd rect
			(at 0.203 -1.534 270)
			(size 0.2 0.7)
			(layers "F.Cu" "F.Mask" "F.Paste")
			(net 147 "/Compute module/R1_P")
			(pintype "passive")
		)
		(pad "53" smd rect
			(at 0.602 1.547 270)
			(size 0.2 0.7)
			(layers "F.Cu" "F.Mask" "F.Paste")
			(net 262 "/Compute module/HDMI.HPD")
			(pintype "passive")
		)
		(pad "54" smd rect
			(at 0.602 -1.534 270)
			(size 0.2 0.7)
			(layers "F.Cu" "F.Mask" "F.Paste")
			(net 148 "/Compute module/R1_N")
			(pintype "passive")
		)
		(pad "55" smd rect
			(at 1.002 1.547 270)
			(size 0.2 0.7)
			(layers "F.Cu" "F.Mask" "F.Paste")
			(net 3 "GND")
			(pintype "passive")
		)
		(pad "56" smd rect
			(at 1.002 -1.534 270)
			(size 0.2 0.7)
			(layers "F.Cu" "F.Mask" "F.Paste")
			(net 3 "GND")
			(pintype "passive")
		)
		(pad "57" smd rect
			(at 1.401 1.547 270)
			(size 0.2 0.7)
			(layers "F.Cu" "F.Mask" "F.Paste")
			(net 149 "/Compute module/R2_N")
			(pintype "passive")
		)
		(pad "58" smd rect
			(at 1.401 -1.534 270)
			(size 0.2 0.7)
			(layers "F.Cu" "F.Mask" "F.Paste")
			(net 150 "/Compute module/T2_P")
			(pintype "passive")
		)
		(pad "59" smd rect
			(at 1.803 1.547 270)
			(size 0.2 0.7)
			(layers "F.Cu" "F.Mask" "F.Paste")
			(net 151 "/Compute module/R2_P")
			(pintype "passive")
		)
		(pad "60" smd rect
			(at 1.803 -1.534 270)
			(size 0.2 0.7)
			(layers "F.Cu" "F.Mask" "F.Paste")
			(net 152 "/Compute module/T2_N")
			(pintype "passive")
		)
		(pad "61" smd rect
			(at 2.203 1.547 270)
			(size 0.2 0.7)
			(layers "F.Cu" "F.Mask" "F.Paste")
			(net 3 "GND")
			(pintype "passive")
		)
		(pad "62" smd rect
			(at 2.203 -1.534 270)
			(size 0.2 0.7)
			(layers "F.Cu" "F.Mask" "F.Paste")
			(net 3 "GND")
			(pintype "passive")
		)
		(pad "63" smd rect
			(at 2.603 1.547 270)
			(size 0.2 0.7)
			(layers "F.Cu" "F.Mask" "F.Paste")
			(net 153 "/Compute module/T3_N")
			(pintype "passive")
		)
		(pad "64" smd rect
			(at 2.603 -1.534 270)
			(size 0.2 0.7)
			(layers "F.Cu" "F.Mask" "F.Paste")
			(net 154 "/Compute module/R3_P")
			(pintype "passive")
		)
		(pad "65" smd rect
			(at 3.002 1.547 270)
			(size 0.2 0.7)
			(layers "F.Cu" "F.Mask" "F.Paste")
			(net 155 "/Compute module/T3_P")
			(pintype "passive")
		)
		(pad "66" smd rect
			(at 3.002 -1.534 270)
			(size 0.2 0.7)
			(layers "F.Cu" "F.Mask" "F.Paste")
			(net 156 "/Compute module/R3_N")
			(pintype "passive")
		)
		(pad "67" smd rect
			(at 3.402 1.547 270)
			(size 0.2 0.7)
			(layers "F.Cu" "F.Mask" "F.Paste")
			(net 3 "GND")
			(pintype "passive")
		)
		(pad "68" smd rect
			(at 3.402 -1.534 270)
			(size 0.2 0.7)
			(layers "F.Cu" "F.Mask" "F.Paste")
			(net 3 "GND")
			(pintype "passive")
		)
		(pad "69" smd rect
			(at 3.802 1.547 270)
			(size 0.2 0.7)
			(layers "F.Cu" "F.Mask" "F.Paste")
			(net 264 "/Compute module/DSI0_C_N")
			(pintype "passive+no_connect")
		)
		(pad "70" smd rect
			(at 3.802 -1.534 270)
			(size 0.2 0.7)
			(layers "F.Cu" "F.Mask" "F.Paste")
			(net 16 "/Compute module/HDMI.D2_P")
			(pintype "passive")
		)
		(pad "71" smd rect
			(at 4.203 1.547 270)
			(size 0.2 0.7)
			(layers "F.Cu" "F.Mask" "F.Paste")
			(net 265 "/Compute module/DSI0_C_P")
			(pintype "passive+no_connect")
		)
		(pad "72" smd rect
			(at 4.203 -1.534 270)
			(size 0.2 0.7)
			(layers "F.Cu" "F.Mask" "F.Paste")
			(net 15 "/Compute module/HDMI.D2_N")
			(pintype "passive")
		)
		(pad "73" smd rect
			(at 4.602 1.547 270)
			(size 0.2 0.7)
			(layers "F.Cu" "F.Mask" "F.Paste")
			(net 3 "GND")
			(pintype "passive")
		)
		(pad "74" smd rect
			(at 4.602 -1.534 270)
			(size 0.2 0.7)
			(layers "F.Cu" "F.Mask" "F.Paste")
			(net 3 "GND")
			(pintype "passive")
		)
		(pad "75" smd rect
			(at 5.002 1.547 270)
			(size 0.2 0.7)
			(layers "F.Cu" "F.Mask" "F.Paste")
			(net 72 "/Compute module/DSI.D0_N")
			(pintype "passive")
		)
		(pad "76" smd rect
			(at 5.002 -1.534 270)
			(size 0.2 0.7)
			(layers "F.Cu" "F.Mask" "F.Paste")
			(net 14 "/Compute module/HDMI.D1_P")
			(pintype "passive")
		)
		(pad "77" smd rect
			(at 5.403 1.547 270)
			(size 0.2 0.7)
			(layers "F.Cu" "F.Mask" "F.Paste")
			(net 73 "/Compute module/DSI.D0_P")
			(pintype "passive")
		)
		(pad "78" smd rect
			(at 5.403 -1.534 270)
			(size 0.2 0.7)
			(layers "F.Cu" "F.Mask" "F.Paste")
			(net 13 "/Compute module/HDMI.D1_N")
			(pintype "passive")
		)
		(pad "79" smd rect
			(at 5.802 1.547 270)
			(size 0.2 0.7)
			(layers "F.Cu" "F.Mask" "F.Paste")
			(net 3 "GND")
			(pintype "passive")
		)
		(pad "80" smd rect
			(at 5.802 -1.534 270)
			(size 0.2 0.7)
			(layers "F.Cu" "F.Mask" "F.Paste")
			(net 3 "GND")
			(pintype "passive")
		)
		(pad "81" smd rect
			(at 6.203 1.547 270)
			(size 0.2 0.7)
			(layers "F.Cu" "F.Mask" "F.Paste")
			(net 74 "/Compute module/DSI.D1_N")
			(pintype "passive")
		)
		(pad "82" smd rect
			(at 6.203 -1.534 270)
			(size 0.2 0.7)
			(layers "F.Cu" "F.Mask" "F.Paste")
			(net 35 "/Compute module/HDMI.D0_P")
			(pintype "passive")
		)
		(pad "83" smd rect
			(at 6.602 1.547 270)
			(size 0.2 0.7)
			(layers "F.Cu" "F.Mask" "F.Paste")
			(net 75 "/Compute module/DSI.D1_P")
			(pintype "passive")
		)
		(pad "84" smd rect
			(at 6.602 -1.534 270)
			(size 0.2 0.7)
			(layers "F.Cu" "F.Mask" "F.Paste")
			(net 34 "/Compute module/HDMI.D0_N")
			(pintype "passive")
		)
		(pad "85" smd rect
			(at 7.001 1.547 270)
			(size 0.2 0.7)
			(layers "F.Cu" "F.Mask" "F.Paste")
			(net 3 "GND")
			(pintype "passive")
		)
		(pad "86" smd rect
			(at 7.001 -1.534 270)
			(size 0.2 0.7)
			(layers "F.Cu" "F.Mask" "F.Paste")
			(net 3 "GND")
			(pintype "passive")
		)
		(pad "87" smd rect
			(at 7.403 1.547 270)
			(size 0.2 0.7)
			(layers "F.Cu" "F.Mask" "F.Paste")
			(net 76 "/Compute module/DSI.CLK_N")
			(pintype "passive")
		)
		(pad "88" smd rect
			(at 7.403 -1.534 270)
			(size 0.2 0.7)
			(layers "F.Cu" "F.Mask" "F.Paste")
			(net 25 "/Compute module/HDMI.CLK_P")
			(pintype "passive")
		)
		(pad "89" smd rect
			(at 7.802 1.547 270)
			(size 0.2 0.7)
			(layers "F.Cu" "F.Mask" "F.Paste")
			(net 86 "/Compute module/DSI.CLK_P")
			(pintype "passive")
		)
		(pad "90" smd rect
			(at 7.802 -1.534 270)
			(size 0.2 0.7)
			(layers "F.Cu" "F.Mask" "F.Paste")
			(net 23 "/Compute module/HDMI.CLK_N")
			(pintype "passive")
		)
		(pad "91" smd rect
			(at 8.202 1.547 270)
			(size 0.2 0.7)
			(layers "F.Cu" "F.Mask" "F.Paste")
			(net 3 "GND")
			(pintype "passive")
		)
		(pad "92" smd rect
			(at 8.202 -1.534 270)
			(size 0.2 0.7)
			(layers "F.Cu" "F.Mask" "F.Paste")
			(net 3 "GND")
			(pintype "passive")
		)
		(pad "93" smd rect
			(at 8.602 1.547 270)
			(size 0.2 0.7)
			(layers "F.Cu" "F.Mask" "F.Paste")
			(net 87 "/Compute module/DSI.D2_N")
			(pintype "passive")
		)
		(pad "94" smd rect
			(at 8.602 -1.534 270)
			(size 0.2 0.7)
			(layers "F.Cu" "F.Mask" "F.Paste")
			(net 96 "/Compute module/DSI.D3_N")
			(pintype "passive")
		)
		(pad "95" smd rect
			(at 9.002 1.547 270)
			(size 0.2 0.7)
			(layers "F.Cu" "F.Mask" "F.Paste")
			(net 97 "/Compute module/DSI.D2_P")
			(pintype "passive")
		)
		(pad "96" smd rect
			(at 9.002 -1.534 270)
			(size 0.2 0.7)
			(layers "F.Cu" "F.Mask" "F.Paste")
			(net 98 "/Compute module/DSI.D3_P")
			(pintype "passive")
		)
		(pad "97" smd rect
			(at 9.403 1.547 270)
			(size 0.2 0.7)
			(layers "F.Cu" "F.Mask" "F.Paste")
			(net 3 "GND")
			(pintype "passive")
		)
		(pad "98" smd rect
			(at 9.403 -1.534 270)
			(size 0.2 0.7)
			(layers "F.Cu" "F.Mask" "F.Paste")
			(net 3 "GND")
			(pintype "passive")
		)
		(pad "99" smd rect
			(at 9.803 1.547 270)
			(size 0.2 0.7)
			(layers "F.Cu" "F.Mask" "F.Paste")
			(net 266 "/Compute module/HDMI.SDA")
			(pintype "passive")
		)
		(pad "100" smd rect
			(at 9.803 -1.534 270)
			(size 0.2 0.7)
			(layers "F.Cu" "F.Mask" "F.Paste")
			(net 267 "/Compute module/HDMI.SCL")
			(pintype "passive")
		)
	)
	(footprint "antmicro-footprints:R_0402_1005Metric"
		(layer "F.Cu")
		(at 75.067962 167.6665 180)
		(descr "Resistor SMD 0402")
		(tags "resistor SMD 0402")
		(property "Reference" "R804"
			(at -1.4 1.35 0)
			(layer "F.SilkS")
			(effects
				(font
					(size 0.7 0.7)
					(thickness 0.15)
				)
				(justify right bottom)
			)
		)
		(property "Value" "R_10k_0402"
			(at -1.011843 1.772047 0)
			(layer "F.Fab")
			(effects
				(font
					(size 0.7 0.7)
					(thickness 0.15)
				)
				(justify right bottom)
			)
		)
		(property "Datasheet" "https://www.bourns.com/docs/product-datasheets/cr.pdf"
			(at 0 0 180)
			(layer "F.Fab")
			(hide yes)
			(effects
				(font
					(size 1.27 1.27)
					(thickness 0.15)
				)
			)
		)
		(property "MPN" "CR0402-FX-1002GLF"
			(at 0 0 180)
			(unlocked yes)
			(layer "F.Fab")
			(hide yes)
			(effects
				(font
					(size 1 1)
					(thickness 0.15)
				)
			)
		)
		(property "Manufacturer" "Bourns"
			(at 0 0 180)
			(unlocked yes)
			(layer "F.Fab")
			(hide yes)
			(effects
				(font
					(size 1 1)
					(thickness 0.15)
				)
			)
		)
		(property "License" "Apache-2.0"
			(at 0 0 180)
			(unlocked yes)
			(layer "F.Fab")
			(hide yes)
			(effects
				(font
					(size 1 1)
					(thickness 0.15)
				)
			)
		)
		(property "Author" "Antmicro"
			(at 0 0 180)
			(unlocked yes)
			(layer "F.Fab")
			(hide yes)
			(effects
				(font
					(size 1 1)
					(thickness 0.15)
				)
			)
		)
		(property "Val" "10k"
			(at 0 0 180)
			(unlocked yes)
			(layer "F.Fab")
			(hide yes)
			(effects
				(font
					(size 1 1)
					(thickness 0.15)
				)
			)
		)
		(property "Tolerance" "1%"
			(at 0 0 180)
			(unlocked yes)
			(layer "F.Fab")
			(hide yes)
			(effects
				(font
					(size 1 1)
					(thickness 0.15)
				)
			)
		)
		(sheetname "/Peripherals/")
		(sheetfile "peripherals.kicad_sch")
		(attr smd)
		(fp_rect
			(start -0.925 -0.47)
			(end 0.925 0.47)
			(stroke
				(width 0.05)
				(type default)
			)
			(fill no)
			(layer "F.CrtYd")
		)
		(fp_rect
			(start -0.5 -0.25)
			(end 0.5 0.25)
			(stroke
				(width 0.15)
				(type solid)
			)
			(fill no)
			(layer "F.Fab")
		)
		(fp_text user "${REFERENCE}"
			(at -0.95 3.168 180)
			(layer "F.Fab")
			(effects
				(font
					(size 0.7 0.7)
					(thickness 0.15)
				)
				(justify left bottom)
			)
		)
		(fp_text user "License: Apache-2.0"
			(at -0.95 5.169 180)
			(layer "F.Fab")
			(effects
				(font
					(size 0.7 0.7)
					(thickness 0.15)
				)
				(justify left bottom)
			)
		)
		(fp_text user "Author: Antmicro"
			(at -0.95 4.169 180)
			(layer "F.Fab")
			(effects
				(font
					(size 0.7 0.7)
					(thickness 0.15)
				)
				(justify left bottom)
			)
		)
		(pad "1" smd roundrect
			(at -0.48 0 180)
			(size 0.59 0.64)
			(layers "F.Cu" "F.Mask" "F.Paste")
			(roundrect_rratio 0.25)
			(net 3 "GND")
			(pintype "passive")
		)
		(pad "2" smd roundrect
			(at 0.48 0 180)
			(size 0.59 0.64)
			(layers "F.Cu" "F.Mask" "F.Paste")
			(roundrect_rratio 0.25)
			(net 374 "Net-(U801-I2C_ADR0)")
			(pintype "passive")
		)
	)
	(footprint "antmicro-footprints:Texas_X2QFN-12_1.6x1.6mm_P0.4mm"
		(layer "F.Cu")
		(at 99.567962 121.449 180)
		(descr "Texas  X2QFN, 12 Pin (http://www.ti.com/lit/ml/mpqf391c/mpqf391c.pdf), generated with kicad-footprint-generator ipc_noLead_generator.py")
		(tags "Texas X2QFN NoLead")
		(property "Reference" "U906"
			(at -28.64 -24.0475 90)
			(layer "F.SilkS")
			(effects
				(font
					(size 0.7 0.7)
					(thickness 0.15)
				)
				(justify right bottom)
			)
		)
		(property "Value" "TUSB321RWBR"
			(at -1.41 2.85 0)
			(layer "F.Fab")
			(effects
				(font
					(size 0.7 0.7)
					(thickness 0.15)
				)
				(justify right bottom)
			)
		)
		(property "Datasheet" "https://www.ti.com/lit/ds/symlink/tusb321.pdf?ts=1709901243739"
			(at 0 0 180)
			(layer "F.Fab")
			(hide yes)
			(effects
				(font
					(size 1.27 1.27)
					(thickness 0.15)
				)
			)
		)
		(property "MPN" "TUSB321RWBR"
			(at 0 0 180)
			(unlocked yes)
			(layer "F.Fab")
			(hide yes)
			(effects
				(font
					(size 1 1)
					(thickness 0.15)
				)
			)
		)
		(property "Manufacturer" "Texas Instruments"
			(at 0 0 180)
			(unlocked yes)
			(layer "F.Fab")
			(hide yes)
			(effects
				(font
					(size 1 1)
					(thickness 0.15)
				)
			)
		)
		(property "Author" "Antmicro"
			(at 0 0 180)
			(unlocked yes)
			(layer "F.Fab")
			(hide yes)
			(effects
				(font
					(size 1 1)
					(thickness 0.15)
				)
			)
		)
		(property "License" "Apache-2.0"
			(at 0 0 180)
			(unlocked yes)
			(layer "F.Fab")
			(hide yes)
			(effects
				(font
					(size 1 1)
					(thickness 0.15)
				)
			)
		)
		(sheetname "/USB/")
		(sheetfile "usb.kicad_sch")
		(attr smd)
		(fp_line
			(start 0.91 0.91)
			(end 0.91 0.56)
			(stroke
				(width 0.15)
				(type solid)
			)
			(layer "F.SilkS")
		)
		(fp_line
			(start 0.91 -0.912)
			(end 0.91 -0.562)
			(stroke
				(width 0.15)
				(type solid)
			)
			(layer "F.SilkS")
		)
		(fp_line
			(start -0.912 0.91)
			(end -0.912 0.56)
			(stroke
				(width 0.15)
				(type solid)
			)
			(layer "F.SilkS")
		)
		(fp_circle
			(center -1.3 -0.2)
			(end -1.25 -0.2)
			(stroke
				(width 0.15)
				(type solid)
			)
			(fill yes)
			(layer "F.SilkS")
		)
		(fp_line
			(start 1.39 1.39)
			(end 1.39 -1.41)
			(stroke
				(width 0.05)
				(type solid)
			)
			(layer "F.CrtYd")
		)
		(fp_line
			(start 1.39 -1.41)
			(end -1.41 -1.41)
			(stroke
				(width 0.05)
				(type solid)
			)
			(layer "F.CrtYd")
		)
		(fp_line
			(start -1.41 1.39)
			(end 1.39 1.39)
			(stroke
				(width 0.05)
				(type solid)
			)
			(layer "F.CrtYd")
		)
		(fp_line
			(start -1.41 -1.41)
			(end -1.41 1.39)
			(stroke
				(width 0.05)
				(type solid)
			)
			(layer "F.CrtYd")
		)
		(fp_line
			(start 0.8 0.8)
			(end -0.802 0.8)
			(stroke
				(width 0.15)
				(type solid)
			)
			(layer "F.Fab")
		)
		(fp_line
			(start 0.8 -0.802)
			(end 0.8 0.8)
			(stroke
				(width 0.15)
				(type solid)
			)
			(layer "F.Fab")
		)
		(fp_line
			(start -0.402 -0.802)
			(end 0.8 -0.802)
			(stroke
				(width 0.15)
				(type solid)
			)
			(layer "F.Fab")
		)
		(fp_line
			(start -0.802 0.8)
			(end -0.802 -0.402)
			(stroke
				(width 0.15)
				(type solid)
			)
			(layer "F.Fab")
		)
		(fp_line
			(start -0.802 -0.402)
			(end -0.402 -0.802)
			(stroke
				(width 0.15)
				(type solid)
			)
			(layer "F.Fab")
		)
		(fp_text user "Author: Antmicro"
			(at -1.76 7.25 180)
			(layer "F.Fab")
			(effects
				(font
					(size 0.7 0.7)
					(thickness 0.15)
				)
				(justify left bottom)
			)
		)
		(fp_text user "License: Apache-2.0"
			(at -1.76 4.85 180)
			(layer "F.Fab")
			(effects
				(font
					(size 0.7 0.7)
					(thickness 0.15)
				)
				(justify left bottom)
			)
		)
		(fp_text user "${REFERENCE}"
			(at -1.76 6.05 180)
			(layer "F.Fab")
			(effects
				(font
					(size 0.7 0.7)
					(thickness 0.15)
				)
				(justify left bottom)
			)
		)
		(pad "1" smd roundrect
			(at -0.725 -0.2 180)
			(size 0.85 0.2)
			(layers "F.Cu" "F.Mask" "F.Paste")
			(roundrect_rratio 0.25)
			(net 203 "/USB/USBA_CC1")
			(pinfunction "CC1")
			(pintype "bidirectional")
		)
		(pad "2" smd roundrect
			(at -0.725 0.2 180)
			(size 0.85 0.2)
			(layers "F.Cu" "F.Mask" "F.Paste")
			(roundrect_rratio 0.25)
			(net 204 "/USB/USBA_CC2")
			(pinfunction "CC2")
			(pintype "bidirectional")
		)
		(pad "3" smd roundrect
			(at -0.6 0.825 180)
			(size 0.2 0.65)
			(layers "F.Cu" "F.Mask" "F.Paste")
			(roundrect_rratio 0.25)
			(net 432 "Net-(U906-CURRENT_MODE)")
			(pinfunction "CURRENT_MODE")
			(pintype "input")
		)
		(pad "4" smd roundrect
			(at -0.2 0.825 180)
			(size 0.2 0.65)
			(layers "F.Cu" "F.Mask" "F.Paste")
			(roundrect_rratio 0.25)
			(net 434 "Net-(U906-PORT)")
			(pinfunction "PORT")
			(pintype "input")
		)
		(pad "5" smd roundrect
			(at 0.2 0.825 180)
			(size 0.2 0.65)
			(layers "F.Cu" "F.Mask" "F.Paste")
			(roundrect_rratio 0.25)
			(net 340 "Net-(U906-VBUS_DET)")
			(pinfunction "VBUS_DET")
			(pintype "input")
		)
		(pad "6" smd roundrect
			(at 0.6 0.825 180)
			(size 0.2 0.65)
			(layers "F.Cu" "F.Mask" "F.Paste")
			(roundrect_rratio 0.25)
			(net 435 "Net-(U906-~{VCONN_FAULT})")
			(pinfunction "~{VCONN_FAULT}")
			(pintype "open_collector")
		)
		(pad "7" smd roundrect
			(at 0.725 0.2 180)
			(size 0.85 0.2)
			(layers "F.Cu" "F.Mask" "F.Paste")
			(roundrect_rratio 0.25)
			(net 436 "Net-(U906-OUT1)")
			(pinfunction "OUT1")
			(pintype "open_collector")
		)
		(pad "8" smd roundrect
			(at 0.725 -0.2 180)
			(size 0.85 0.2)
			(layers "F.Cu" "F.Mask" "F.Paste")
			(roundrect_rratio 0.25)
			(net 437 "Net-(U906-OUT2)")
			(pinfunction "OUT2")
			(pintype "open_collector")
		)
		(pad "9" smd roundrect
			(at 0.6 -0.825 180)
			(size 0.2 0.65)
			(layers "F.Cu" "F.Mask" "F.Paste")
			(roundrect_rratio 0.25)
			(net 279 "/Compute module/USB.OTGID")
			(pinfunction "ID")
			(pintype "open_collector")
		)
		(pad "10" smd roundrect
			(at 0.2 -0.825 180)
			(size 0.2 0.65)
			(layers "F.Cu" "F.Mask" "F.Paste")
			(roundrect_rratio 0.25)
			(net 3 "GND")
			(pinfunction "GND")
			(pintype "power_in")
		)
		(pad "11" smd roundrect
			(at -0.2 -0.825 180)
			(size 0.2 0.65)
			(layers "F.Cu" "F.Mask" "F.Paste")
			(roundrect_rratio 0.25)
			(net 433 "Net-(U906-DIR)")
			(pinfunction "DIR")
			(pintype "open_collector")
		)
		(pad "12" smd roundrect
			(at -0.6 -0.825 180)
			(size 0.2 0.65)
			(layers "F.Cu" "F.Mask" "F.Paste")
			(roundrect_rratio 0.25)
			(net 28 "/USB/+5V_{CAP}")
			(pinfunction "VDD")
			(pintype "power_in")
		)
	)
	(footprint "antmicro-footprints:R_0402_1005Metric"
		(layer "F.Cu")
		(at 135.137962 157.6465 90)
		(descr "Resistor SMD 0402")
		(tags "resistor SMD 0402")
		(property "Reference" "R602"
			(at -7.23 1.65 90)
			(layer "F.SilkS")
			(effects
				(font
					(size 0.7 0.7)
					(thickness 0.15)
				)
				(justify left bottom)
			)
		)
		(property "Value" "R_10k_0402"
			(at -1.011843 1.772047 90)
			(layer "F.Fab")
			(effects
				(font
					(size 0.7 0.7)
					(thickness 0.15)
				)
				(justify left bottom)
			)
		)
		(property "Datasheet" "https://www.bourns.com/docs/product-datasheets/cr.pdf"
			(at 0 0 90)
			(layer "F.Fab")
			(hide yes)
			(effects
				(font
					(size 1.27 1.27)
					(thickness 0.15)
				)
			)
		)
		(property "Manufacturer" "Bourns"
			(at 0 0 90)
			(unlocked yes)
			(layer "F.Fab")
			(hide yes)
			(effects
				(font
					(size 1 1)
					(thickness 0.15)
				)
			)
		)
		(property "MPN" "CR0402-FX-1002GLF"
			(at 0 0 90)
			(unlocked yes)
			(layer "F.Fab")
			(hide yes)
			(effects
				(font
					(size 1 1)
					(thickness 0.15)
				)
			)
		)
		(property "Val" "10k"
			(at 0 0 90)
			(unlocked yes)
			(layer "F.Fab")
			(hide yes)
			(effects
				(font
					(size 1 1)
					(thickness 0.15)
				)
			)
		)
		(property "License" "Apache-2.0"
			(at 0 0 90)
			(unlocked yes)
			(layer "F.Fab")
			(hide yes)
			(effects
				(font
					(size 1 1)
					(thickness 0.15)
				)
			)
		)
		(property "Author" "Antmicro"
			(at 0 0 90)
			(unlocked yes)
			(layer "F.Fab")
			(hide yes)
			(effects
				(font
					(size 1 1)
					(thickness 0.15)
				)
			)
		)
		(property "Tolerance" "1%"
			(at 0 0 90)
			(unlocked yes)
			(layer "F.Fab")
			(hide yes)
			(effects
				(font
					(size 1 1)
					(thickness 0.15)
				)
			)
		)
		(sheetname "/CSI/")
		(sheetfile "csi.kicad_sch")
		(attr smd)
		(fp_rect
			(start -0.925 -0.47)
			(end 0.925 0.47)
			(stroke
				(width 0.05)
				(type default)
			)
			(fill no)
			(layer "F.CrtYd")
		)
		(fp_rect
			(start -0.5 -0.25)
			(end 0.5 0.25)
			(stroke
				(width 0.15)
				(type solid)
			)
			(fill no)
			(layer "F.Fab")
		)
		(fp_text user "${REFERENCE}"
			(at -0.95 3.168 90)
			(layer "F.Fab")
			(effects
				(font
					(size 0.7 0.7)
					(thickness 0.15)
				)
				(justify left bottom)
			)
		)
		(fp_text user "License: Apache-2.0"
			(at -0.95 5.169 90)
			(layer "F.Fab")
			(effects
				(font
					(size 0.7 0.7)
					(thickness 0.15)
				)
				(justify left bottom)
			)
		)
		(fp_text user "Author: Antmicro"
			(at -0.95 4.169 90)
			(layer "F.Fab")
			(effects
				(font
					(size 0.7 0.7)
					(thickness 0.15)
				)
				(justify left bottom)
			)
		)
		(pad "1" smd roundrect
			(at -0.48 0 90)
			(size 0.59 0.64)
			(layers "F.Cu" "F.Mask" "F.Paste")
			(roundrect_rratio 0.25)
			(net 10 "+5V")
			(pintype "passive")
		)
		(pad "2" smd roundrect
			(at 0.48 0 90)
			(size 0.59 0.64)
			(layers "F.Cu" "F.Mask" "F.Paste")
			(roundrect_rratio 0.25)
			(net 370 "Net-(U601-FLG)")
			(pintype "passive")
		)
	)
	(footprint "antmicro-footprints:TP_SMD_0.75mm"
		(layer "F.Cu")
		(at 81.4 120.4165)
		(property "Reference" "TP920"
			(at -3.61 0.1735 0)
			(layer "F.SilkS")
			(effects
				(font
					(size 0.7 0.7)
					(thickness 0.15)
				)
				(justify left bottom)
			)
		)
		(property "Value" "TP_0.75mm_SMD"
			(at 0 1.2 0)
			(layer "F.Fab")
			(effects
				(font
					(size 0.7 0.7)
					(thickness 0.15)
				)
				(justify left bottom)
			)
		)
		(property "MPN" ""
			(at 0 0 0)
			(unlocked yes)
			(layer "F.Fab")
			(hide yes)
			(effects
				(font
					(size 1 1)
					(thickness 0.15)
				)
			)
		)
		(property "Manufacturer" ""
			(at 0 0 0)
			(unlocked yes)
			(layer "F.Fab")
			(hide yes)
			(effects
				(font
					(size 1 1)
					(thickness 0.15)
				)
			)
		)
		(property "Author" "Antmicro"
			(at 0 0 0)
			(unlocked yes)
			(layer "F.Fab")
			(hide yes)
			(effects
				(font
					(size 1 1)
					(thickness 0.15)
				)
			)
		)
		(property "License" "Apache-2.0"
			(at 0 0 0)
			(unlocked yes)
			(layer "F.Fab")
			(hide yes)
			(effects
				(font
					(size 1 1)
					(thickness 0.15)
				)
			)
		)
		(sheetname "/USB/")
		(sheetfile "usb.kicad_sch")
		(attr exclude_from_pos_files exclude_from_bom)
		(fp_circle
			(center 0 0)
			(end 0.475 0)
			(stroke
				(width 0.05)
				(type default)
			)
			(fill no)
			(layer "F.CrtYd")
		)
		(fp_text user "Author: Antmicro"
			(at -0.4 3.901 0)
			(layer "F.Fab")
			(effects
				(font
					(size 0.7 0.7)
					(thickness 0.15)
				)
				(justify left bottom)
			)
		)
		(fp_text user "${REFERENCE}"
			(at -0.4 2.7 0)
			(layer "F.Fab")
			(effects
				(font
					(size 0.7 0.7)
					(thickness 0.15)
				)
				(justify left bottom)
			)
		)
		(fp_text user "License: Apache-2.0"
			(at -0.4 5.101 0)
			(layer "F.Fab")
			(effects
				(font
					(size 0.7 0.7)
					(thickness 0.15)
				)
				(justify left bottom)
			)
		)
		(pad "1" smd circle
			(at 0 0)
			(size 0.75 0.75)
			(layers "F.Cu" "F.Mask")
			(net 26 "/USB/USBD_VBUS")
			(pinfunction "1")
			(pintype "passive")
		)
	)
	(footprint "antmicro-footprints:C_0402_1005Metric"
		(layer "F.Cu")
		(at 83.567962 140.307236)
		(descr "Capacitor SMD 0402")
		(tags "capacitor SMD 0402")
		(property "Reference" "C924"
			(at -3.86 0.499264 0)
			(layer "F.SilkS")
			(effects
				(font
					(size 0.7 0.7)
					(thickness 0.15)
				)
				(justify left bottom)
			)
		)
		(property "Value" "C_4u7_0402"
			(at -1.022927 2.155213 0)
			(layer "F.Fab")
			(effects
				(font
					(size 0.7 0.7)
					(thickness 0.15)
				)
				(justify left bottom)
			)
		)
		(property "Datasheet" "https://www.murata.com/products/productdetail?partno=GRM155R61A475MEAA%23"
			(at 0 0 0)
			(layer "F.Fab")
			(hide yes)
			(effects
				(font
					(size 1.27 1.27)
					(thickness 0.15)
				)
			)
		)
		(property "Manufacturer" "Murata"
			(at 0 0 0)
			(unlocked yes)
			(layer "F.Fab")
			(hide yes)
			(effects
				(font
					(size 1 1)
					(thickness 0.15)
				)
			)
		)
		(property "MPN" "GRM155R61A475MEAAD"
			(at 0 0 0)
			(unlocked yes)
			(layer "F.Fab")
			(hide yes)
			(effects
				(font
					(size 1 1)
					(thickness 0.15)
				)
			)
		)
		(property "Val" "4u7"
			(at 0 0 0)
			(unlocked yes)
			(layer "F.Fab")
			(hide yes)
			(effects
				(font
					(size 1 1)
					(thickness 0.15)
				)
			)
		)
		(property "License" "Apache-2.0"
			(at 0 0 0)
			(unlocked yes)
			(layer "F.Fab")
			(hide yes)
			(effects
				(font
					(size 1 1)
					(thickness 0.15)
				)
			)
		)
		(property "Author" "Antmicro"
			(at 0 0 0)
			(unlocked yes)
			(layer "F.Fab")
			(hide yes)
			(effects
				(font
					(size 1 1)
					(thickness 0.15)
				)
			)
		)
		(property "Voltage" ""
			(at 0 0 0)
			(unlocked yes)
			(layer "F.Fab")
			(hide yes)
			(effects
				(font
					(size 1 1)
					(thickness 0.15)
				)
			)
		)
		(property "Dielectric" ""
			(at 0 0 0)
			(unlocked yes)
			(layer "F.Fab")
			(hide yes)
			(effects
				(font
					(size 1 1)
					(thickness 0.15)
				)
			)
		)
		(sheetname "/USB/")
		(sheetfile "usb.kicad_sch")
		(attr smd)
		(fp_rect
			(start -0.925 -0.47)
			(end 0.925 0.47)
			(stroke
				(width 0.05)
				(type default)
			)
			(fill no)
			(layer "F.CrtYd")
		)
		(fp_line
			(start -0.494 -0.25)
			(end 0.504 -0.25)
			(stroke
				(width 0.15)
				(type solid)
			)
			(layer "F.Fab")
		)
		(fp_line
			(start -0.494 0.248)
			(end -0.494 -0.25)
			(stroke
				(width 0.15)
				(type solid)
			)
			(layer "F.Fab")
		)
		(fp_line
			(start 0.504 -0.25)
			(end 0.504 0.248)
			(stroke
				(width 0.15)
				(type solid)
			)
			(layer "F.Fab")
		)
		(fp_line
			(start 0.504 0.248)
			(end -0.494 0.248)
			(stroke
				(width 0.15)
				(type solid)
			)
			(layer "F.Fab")
		)
		(fp_text user "${REFERENCE}"
			(at -0.939 4.599 0)
			(layer "F.Fab")
			(effects
				(font
					(size 0.7 0.7)
					(thickness 0.15)
				)
				(justify left bottom)
			)
		)
		(fp_text user "License: Apache-2.0"
			(at -0.939 5.799 0)
			(layer "F.Fab")
			(effects
				(font
					(size 0.7 0.7)
					(thickness 0.15)
				)
				(justify left bottom)
			)
		)
		(fp_text user "Author: Antmicro"
			(at -0.939 3.399 0)
			(layer "F.Fab")
			(effects
				(font
					(size 0.7 0.7)
					(thickness 0.15)
				)
				(justify left bottom)
			)
		)
		(pad "1" smd roundrect
			(at -0.48 0)
			(size 0.59 0.64)
			(layers "F.Cu" "F.Mask" "F.Paste")
			(roundrect_rratio 0.25)
			(net 3 "GND")
			(pintype "passive")
		)
		(pad "2" smd roundrect
			(at 0.48 0)
			(size 0.59 0.64)
			(layers "F.Cu" "F.Mask" "F.Paste")
			(roundrect_rratio 0.25)
			(net 27 "/USB/USB_3V3")
			(pintype "passive")
		)
	)
	(footprint "antmicro-footprints:R_0402_1005Metric"
		(layer "F.Cu")
		(at 130.717962 157.7915 90)
		(descr "Resistor SMD 0402")
		(tags "resistor SMD 0402")
		(property "Reference" "R603"
			(at -0.9785 -0.817962 90)
			(layer "F.SilkS")
			(effects
				(font
					(size 0.7 0.7)
					(thickness 0.15)
				)
				(justify left bottom)
			)
		)
		(property "Value" "R_10k_0402"
			(at -1.011843 1.772047 90)
			(layer "F.Fab")
			(effects
				(font
					(size 0.7 0.7)
					(thickness 0.15)
				)
				(justify left bottom)
			)
		)
		(property "Datasheet" "https://www.bourns.com/docs/product-datasheets/cr.pdf"
			(at 0 0 90)
			(layer "F.Fab")
			(hide yes)
			(effects
				(font
					(size 1.27 1.27)
					(thickness 0.15)
				)
			)
		)
		(property "Manufacturer" "Bourns"
			(at 0 0 90)
			(unlocked yes)
			(layer "F.Fab")
			(hide yes)
			(effects
				(font
					(size 1 1)
					(thickness 0.15)
				)
			)
		)
		(property "MPN" "CR0402-FX-1002GLF"
			(at 0 0 90)
			(unlocked yes)
			(layer "F.Fab")
			(hide yes)
			(effects
				(font
					(size 1 1)
					(thickness 0.15)
				)
			)
		)
		(property "Val" "10k"
			(at 0 0 90)
			(unlocked yes)
			(layer "F.Fab")
			(hide yes)
			(effects
				(font
					(size 1 1)
					(thickness 0.15)
				)
			)
		)
		(property "License" "Apache-2.0"
			(at 0 0 90)
			(unlocked yes)
			(layer "F.Fab")
			(hide yes)
			(effects
				(font
					(size 1 1)
					(thickness 0.15)
				)
			)
		)
		(property "Author" "Antmicro"
			(at 0 0 90)
			(unlocked yes)
			(layer "F.Fab")
			(hide yes)
			(effects
				(font
					(size 1 1)
					(thickness 0.15)
				)
			)
		)
		(property "Tolerance" "1%"
			(at 0 0 90)
			(unlocked yes)
			(layer "F.Fab")
			(hide yes)
			(effects
				(font
					(size 1 1)
					(thickness 0.15)
				)
			)
		)
		(sheetname "/CSI/")
		(sheetfile "csi.kicad_sch")
		(attr smd)
		(fp_rect
			(start -0.925 -0.47)
			(end 0.925 0.47)
			(stroke
				(width 0.05)
				(type default)
			)
			(fill no)
			(layer "F.CrtYd")
		)
		(fp_rect
			(start -0.5 -0.25)
			(end 0.5 0.25)
			(stroke
				(width 0.15)
				(type solid)
			)
			(fill no)
			(layer "F.Fab")
		)
		(fp_text user "License: Apache-2.0"
			(at -0.95 5.169 90)
			(layer "F.Fab")
			(effects
				(font
					(size 0.7 0.7)
					(thickness 0.15)
				)
				(justify left bottom)
			)
		)
		(fp_text user "Author: Antmicro"
			(at -0.95 4.169 90)
			(layer "F.Fab")
			(effects
				(font
					(size 0.7 0.7)
					(thickness 0.15)
				)
				(justify left bottom)
			)
		)
		(fp_text user "${REFERENCE}"
			(at -0.95 3.168 90)
			(layer "F.Fab")
			(effects
				(font
					(size 0.7 0.7)
					(thickness 0.15)
				)
				(justify left bottom)
			)
		)
		(pad "1" smd roundrect
			(at -0.48 0 90)
			(size 0.59 0.64)
			(layers "F.Cu" "F.Mask" "F.Paste")
			(roundrect_rratio 0.25)
			(net 9 "+3V3")
			(pintype "passive")
		)
		(pad "2" smd roundrect
			(at 0.48 0 90)
			(size 0.59 0.64)
			(layers "F.Cu" "F.Mask" "F.Paste")
			(roundrect_rratio 0.25)
			(net 371 "Net-(U602-FLG)")
			(pintype "passive")
		)
	)
	(footprint "antmicro-footprints:Conv_Murata_ULS-60W"
		(layer "F.Cu")
		(at 59.937962 139.8265 -90)
		(property "Reference" "U403"
			(at -1.7265 -4.262038 270)
			(layer "F.SilkS")
			(effects
				(font
					(size 0.7 0.7)
					(thickness 0.15)
				)
				(justify left bottom)
			)
		)
		(property "Value" "ULS-12_5-D48N-C"
			(at -2.8 20.1 270)
			(layer "F.Fab")
			(effects
				(font
					(size 0.7 0.7)
					(thickness 0.15)
				)
				(justify left bottom)
			)
		)
		(property "Datasheet" "https://www.murata.com/products/productdata/8807040286750/uls.pdf?1649388617000"
			(at 0 0 270)
			(layer "F.Fab")
			(hide yes)
			(effects
				(font
					(size 1.27 1.27)
					(thickness 0.15)
				)
			)
		)
		(property "Description" "Isolated Through Hole DC/DC Converter, ITE, 2:1, 60 W, 1 Output, 12 V, 5 A"
			(at 0 0 270)
			(layer "F.Fab")
			(hide yes)
			(effects
				(font
					(size 1.27 1.27)
					(thickness 0.15)
				)
			)
		)
		(property "Manufacturer" "Murata"
			(at 0 0 270)
			(unlocked yes)
			(layer "F.Fab")
			(hide yes)
			(effects
				(font
					(size 1 1)
					(thickness 0.15)
				)
			)
		)
		(property "MPN" "ULS-12/5-D48N-C"
			(at 0 0 270)
			(unlocked yes)
			(layer "F.Fab")
			(hide yes)
			(effects
				(font
					(size 1 1)
					(thickness 0.15)
				)
			)
		)
		(property "Author" "Antmicro"
			(at 0 0 270)
			(unlocked yes)
			(layer "F.Fab")
			(hide yes)
			(effects
				(font
					(size 1 1)
					(thickness 0.15)
				)
			)
		)
		(property "License" "Apache-2.0"
			(at 0 0 270)
			(unlocked yes)
			(layer "F.Fab")
			(hide yes)
			(effects
				(font
					(size 1 1)
					(thickness 0.15)
				)
			)
		)
		(property "Alternatives 50W" " VCB4812SBO-50WR3, V36SE12004NRFA, PKU5513ESI, KHHD004A2B41Z"
			(at 0 0 270)
			(unlocked yes)
			(layer "F.Fab")
			(hide yes)
			(effects
				(font
					(size 1 1)
					(thickness 0.15)
				)
			)
		)
		(property "Alternatives 75W" " VCB4812SBO-75WR3"
			(at 0 0 270)
			(unlocked yes)
			(layer "F.Fab")
			(hide yes)
			(effects
				(font
					(size 1 1)
					(thickness 0.15)
				)
			)
		)
		(property "Alternatives 100W" "PKU4913DPIHS, VCB4812SBO-100WFR3"
			(at 0 0 270)
			(unlocked yes)
			(layer "F.Fab")
			(hide yes)
			(effects
				(font
					(size 1 1)
					(thickness 0.15)
				)
			)
		)
		(property "Alternatives 120W" "PQC50-48-S12-O"
			(at 0 0 270)
			(unlocked yes)
			(layer "F.Fab")
			(hide yes)
			(effects
				(font
					(size 1 1)
					(thickness 0.15)
				)
			)
		)
		(sheetname "/Ethernet/")
		(sheetfile "ethernet.kicad_sch")
		(attr through_hole)
		(fp_line
			(start -2.535 19.053)
			(end -2.535 -2.537)
			(stroke
				(width 0.15)
				(type solid)
			)
			(layer "F.SilkS")
		)
		(fp_line
			(start 30.485 19.053)
			(end -2.535 19.053)
			(stroke
				(width 0.15)
				(type solid)
			)
			(layer "F.SilkS")
		)
		(fp_line
			(start 30.485 19.053)
			(end 30.485 -3.807)
			(stroke
				(width 0.15)
				(type solid)
			)
			(layer "F.SilkS")
		)
		(fp_line
			(start -2.535 -2.537)
			(end -1.265 -3.807)
			(stroke
				(width 0.15)
				(type solid)
			)
			(layer "F.SilkS")
		)
		(fp_line
			(start 30.485 -3.807)
			(end -1.265 -3.807)
			(stroke
				(width 0.15)
				(type solid)
			)
			(layer "F.SilkS")
		)
		(fp_circle
			(center -1.9 0)
			(end -1.85 0)
			(stroke
				(width 0.15)
				(type solid)
			)
			(fill yes)
			(layer "F.SilkS")
		)
		(fp_rect
			(start -3.54 -4.81)
			(end 31.48 20.05)
			(stroke
				(width 0.05)
				(type solid)
			)
			(fill no)
			(layer "F.CrtYd")
		)
		(fp_line
			(start -2.535 19.053)
			(end -2.535 -2.537)
			(stroke
				(width 0.15)
				(type solid)
			)
			(layer "F.Fab")
		)
		(fp_line
			(start 30.485 19.053)
			(end -2.535 19.053)
			(stroke
				(width 0.15)
				(type solid)
			)
			(layer "F.Fab")
		)
		(fp_line
			(start 30.485 19.053)
			(end 30.485 -3.807)
			(stroke
				(width 0.15)
				(type solid)
			)
			(layer "F.Fab")
		)
		(fp_line
			(start -2.535 -2.537)
			(end -1.265 -3.807)
			(stroke
				(width 0.15)
				(type solid)
			)
			(layer "F.Fab")
		)
		(fp_line
			(start 30.485 -3.807)
			(end -1.265 -3.807)
			(stroke
				(width 0.15)
				(type solid)
			)
			(layer "F.Fab")
		)
		(fp_text user "License: Apache-2.0"
			(at -3.54 24.45 270)
			(layer "F.Fab")
			(effects
				(font
					(size 0.7 0.7)
					(thickness 0.15)
				)
				(justify left bottom)
			)
		)
		(fp_text user "${REFERENCE}"
			(at -3.54 23.25 270)
			(layer "F.Fab")
			(effects
				(font
					(size 0.7 0.7)
					(thickness 0.15)
				)
				(justify left bottom)
			)
		)
		(fp_text user "Author: Antmicro"
			(at -3.54 22.05 270)
			(layer "F.Fab")
			(effects
				(font
					(size 0.7 0.7)
					(thickness 0.15)
				)
				(justify left bottom)
			)
		)
		(pad "1" thru_hole rect
			(at 0 0 270)
			(size 2.54 2.54)
			(drill 1.4)
			(layers "*.Cu" "*.Mask")
			(remove_unused_layers no)
			(net 33 "/Ethernet/VDD")
			(pinfunction "VIN+")
			(pintype "power_in")
		)
		(pad "2" thru_hole circle
			(at 0 7.62 270)
			(size 2.54 2.54)
			(drill 1.4)
			(layers "*.Cu" "*.Mask")
			(remove_unused_layers no)
			(net 126 "/Ethernet/ULS-12_CTRL")
			(pinfunction "CTRL")
			(pintype "input")
		)
		(pad "3" thru_hole circle
			(at 0 15.24 270)
			(size 2.54 2.54)
			(drill 1.4)
			(layers "*.Cu" "*.Mask")
			(remove_unused_layers no)
			(net 1 "GNDD")
			(pinfunction "VIN-")
			(pintype "power_in")
		)
		(pad "4" thru_hole circle
			(at 27.94 15.24 270)
			(size 2.54 2.54)
			(drill 1.956)
			(layers "*.Cu" "*.Mask")
			(remove_unused_layers no)
			(net 3 "GND")
			(pinfunction "VOUT-")
			(pintype "power_out")
		)
		(pad "5" thru_hole circle
			(at 27.94 11.43 270)
			(size 2.54 2.54)
			(drill 1.4)
			(layers "*.Cu" "*.Mask")
			(remove_unused_layers no)
			(net 3 "GND")
			(pinfunction "SENSE-")
			(pintype "passive")
		)
		(pad "6" thru_hole circle
			(at 27.94 7.62 270)
			(size 2.54 2.54)
			(drill 1.4)
			(layers "*.Cu" "*.Mask")
			(remove_unused_layers no)
			(net 368 "Net-(U403-TRIM)")
			(pinfunction "TRIM")
			(pintype "input")
		)
		(pad "7" thru_hole circle
			(at 27.94 3.81 270)
			(size 2.54 2.54)
			(drill 1.4)
			(layers "*.Cu" "*.Mask")
			(remove_unused_layers no)
			(net 47 "/Ethernet/POE_12V")
			(pinfunction "SENSE+")
			(pintype "passive")
		)
		(pad "8" thru_hole circle
			(at 27.94 0 270)
			(size 2.54 2.54)
			(drill 1.956)
			(layers "*.Cu" "*.Mask")
			(remove_unused_layers no)
			(net 47 "/Ethernet/POE_12V")
			(pinfunction "VOUT+")
			(pintype "power_out")
		)
	)
	(footprint "antmicro-footprints:TP_SMD_0.75mm"
		(layer "F.Cu")
		(at 93.8 130.85)
		(property "Reference" "TP904"
			(at 3.03 2.64 0)
			(layer "F.SilkS")
			(effects
				(font
					(size 0.7 0.7)
					(thickness 0.15)
				)
				(justify left bottom)
			)
		)
		(property "Value" "TP_0.75mm_SMD"
			(at 0 1.2 0)
			(layer "F.Fab")
			(effects
				(font
					(size 0.7 0.7)
					(thickness 0.15)
				)
				(justify left bottom)
			)
		)
		(property "MPN" ""
			(at 0 0 0)
			(unlocked yes)
			(layer "F.Fab")
			(hide yes)
			(effects
				(font
					(size 1 1)
					(thickness 0.15)
				)
			)
		)
		(property "Manufacturer" ""
			(at 0 0 0)
			(unlocked yes)
			(layer "F.Fab")
			(hide yes)
			(effects
				(font
					(size 1 1)
					(thickness 0.15)
				)
			)
		)
		(property "Author" "Antmicro"
			(at 0 0 0)
			(unlocked yes)
			(layer "F.Fab")
			(hide yes)
			(effects
				(font
					(size 1 1)
					(thickness 0.15)
				)
			)
		)
		(property "License" "Apache-2.0"
			(at 0 0 0)
			(unlocked yes)
			(layer "F.Fab")
			(hide yes)
			(effects
				(font
					(size 1 1)
					(thickness 0.15)
				)
			)
		)
		(sheetname "/USB/")
		(sheetfile "usb.kicad_sch")
		(attr exclude_from_pos_files exclude_from_bom)
		(fp_circle
			(center 0 0)
			(end 0.475 0)
			(stroke
				(width 0.05)
				(type default)
			)
			(fill no)
			(layer "F.CrtYd")
		)
		(fp_text user "Author: Antmicro"
			(at -0.4 3.901 0)
			(layer "F.Fab")
			(effects
				(font
					(size 0.7 0.7)
					(thickness 0.15)
				)
				(justify left bottom)
			)
		)
		(fp_text user "${REFERENCE}"
			(at -0.4 2.7 0)
			(layer "F.Fab")
			(effects
				(font
					(size 0.7 0.7)
					(thickness 0.15)
				)
				(justify left bottom)
			)
		)
		(fp_text user "License: Apache-2.0"
			(at -0.4 5.101 0)
			(layer "F.Fab")
			(effects
				(font
					(size 0.7 0.7)
					(thickness 0.15)
				)
				(justify left bottom)
			)
		)
		(pad "1" smd circle
			(at 0 0)
			(size 0.75 0.75)
			(layers "F.Cu" "F.Mask")
			(net 448 "Net-(U905-GPIO0)")
			(pinfunction "1")
			(pintype "passive")
		)
	)
	(footprint "antmicro-footprints:R_0402_1005Metric"
		(layer "F.Cu")
		(at 76.7 170.0665 -90)
		(descr "Resistor SMD 0402")
		(tags "resistor SMD 0402")
		(property "Reference" "R240"
			(at -3.98 -11.56 90)
			(layer "F.SilkS")
			(effects
				(font
					(size 0.7 0.7)
					(thickness 0.15)
				)
				(justify right bottom)
			)
		)
		(property "Value" "R_0R_0402"
			(at -1.011843 1.772047 90)
			(layer "F.Fab")
			(effects
				(font
					(size 0.7 0.7)
					(thickness 0.15)
				)
				(justify right bottom)
			)
		)
		(property "Datasheet" "https://industrial.panasonic.com/cdbs/www-data/pdf/RDA0000/AOA0000C301.pdf"
			(at 0 0 90)
			(layer "F.Fab")
			(hide yes)
			(effects
				(font
					(size 1.27 1.27)
					(thickness 0.15)
				)
			)
		)
		(property "Manufacturer" "Panasonic"
			(at 0 0 270)
			(unlocked yes)
			(layer "F.Fab")
			(hide yes)
			(effects
				(font
					(size 1 1)
					(thickness 0.15)
				)
			)
		)
		(property "MPN" "ERJ2GE0R00X"
			(at 0 0 270)
			(unlocked yes)
			(layer "F.Fab")
			(hide yes)
			(effects
				(font
					(size 1 1)
					(thickness 0.15)
				)
			)
		)
		(property "Val" "0R"
			(at 0 0 270)
			(unlocked yes)
			(layer "F.Fab")
			(hide yes)
			(effects
				(font
					(size 1 1)
					(thickness 0.15)
				)
			)
		)
		(property "License" "Apache-2.0"
			(at 0 0 270)
			(unlocked yes)
			(layer "F.Fab")
			(hide yes)
			(effects
				(font
					(size 1 1)
					(thickness 0.15)
				)
			)
		)
		(property "Author" "Antmicro"
			(at 0 0 270)
			(unlocked yes)
			(layer "F.Fab")
			(hide yes)
			(effects
				(font
					(size 1 1)
					(thickness 0.15)
				)
			)
		)
		(property "Tolerance" "~"
			(at 0 0 270)
			(unlocked yes)
			(layer "F.Fab")
			(hide yes)
			(effects
				(font
					(size 1 1)
					(thickness 0.15)
				)
			)
		)
		(property "Current" "1A"
			(at 0 0 270)
			(unlocked yes)
			(layer "F.Fab")
			(hide yes)
			(effects
				(font
					(size 1 1)
					(thickness 0.15)
				)
			)
		)
		(sheetname "/Compute module/")
		(sheetfile "compute-module.kicad_sch")
		(attr smd)
		(fp_rect
			(start -0.925 -0.47)
			(end 0.925 0.47)
			(stroke
				(width 0.05)
				(type default)
			)
			(fill no)
			(layer "F.CrtYd")
		)
		(fp_rect
			(start -0.5 -0.25)
			(end 0.5 0.25)
			(stroke
				(width 0.15)
				(type solid)
			)
			(fill no)
			(layer "F.Fab")
		)
		(fp_text user "Author: Antmicro"
			(at -0.95 4.169 90)
			(layer "F.Fab")
			(effects
				(font
					(size 0.7 0.7)
					(thickness 0.15)
				)
				(justify right top)
			)
		)
		(fp_text user "License: Apache-2.0"
			(at -0.95 5.169 90)
			(layer "F.Fab")
			(effects
				(font
					(size 0.7 0.7)
					(thickness 0.15)
				)
				(justify right top)
			)
		)
		(fp_text user "${REFERENCE}"
			(at -0.95 3.168 90)
			(layer "F.Fab")
			(effects
				(font
					(size 0.7 0.7)
					(thickness 0.15)
				)
				(justify right top)
			)
		)
		(pad "1" smd roundrect
			(at -0.48 0 270)
			(size 0.59 0.64)
			(layers "F.Cu" "F.Mask" "F.Paste")
			(roundrect_rratio 0.25)
			(net 276 "Net-(U204-GPA3)")
			(pintype "passive")
		)
		(pad "2" smd roundrect
			(at 0.48 0 270)
			(size 0.59 0.64)
			(layers "F.Cu" "F.Mask" "F.Paste")
			(roundrect_rratio 0.25)
			(net 328 "/Compute module/NFC.WKUP_REQ")
			(pintype "passive")
		)
	)
	(footprint "antmicro-footprints:R_0402_1005Metric"
		(layer "F.Cu")
		(at 102.542962 154.2915 90)
		(descr "Resistor SMD 0402")
		(tags "resistor SMD 0402")
		(property "Reference" "R203"
			(at -1.122484 -0.772697 90)
			(layer "F.SilkS")
			(effects
				(font
					(size 0.7 0.7)
					(thickness 0.15)
				)
				(justify left bottom)
			)
		)
		(property "Value" "R_100k_0402"
			(at -1.011843 1.772047 90)
			(layer "F.Fab")
			(effects
				(font
					(size 0.7 0.7)
					(thickness 0.15)
				)
				(justify left bottom)
			)
		)
		(property "Datasheet" "https://www.bourns.com/docs/product-datasheets/cr.pdf"
			(at 0 0 90)
			(layer "F.Fab")
			(hide yes)
			(effects
				(font
					(size 1.27 1.27)
					(thickness 0.15)
				)
			)
		)
		(property "MPN" "CR0402-FX-1003GLF"
			(at 0 0 90)
			(unlocked yes)
			(layer "F.Fab")
			(hide yes)
			(effects
				(font
					(size 1 1)
					(thickness 0.15)
				)
			)
		)
		(property "Manufacturer" "Bourns"
			(at 0 0 90)
			(unlocked yes)
			(layer "F.Fab")
			(hide yes)
			(effects
				(font
					(size 1 1)
					(thickness 0.15)
				)
			)
		)
		(property "License" "Apache-2.0"
			(at 0 0 90)
			(unlocked yes)
			(layer "F.Fab")
			(hide yes)
			(effects
				(font
					(size 1 1)
					(thickness 0.15)
				)
			)
		)
		(property "Author" "Antmicro"
			(at 0 0 90)
			(unlocked yes)
			(layer "F.Fab")
			(hide yes)
			(effects
				(font
					(size 1 1)
					(thickness 0.15)
				)
			)
		)
		(property "Val" "100k"
			(at 0 0 90)
			(unlocked yes)
			(layer "F.Fab")
			(hide yes)
			(effects
				(font
					(size 1 1)
					(thickness 0.15)
				)
			)
		)
		(property "Tolerance" "1%"
			(at 0 0 90)
			(unlocked yes)
			(layer "F.Fab")
			(hide yes)
			(effects
				(font
					(size 1 1)
					(thickness 0.15)
				)
			)
		)
		(sheetname "/Compute module/")
		(sheetfile "compute-module.kicad_sch")
		(attr smd)
		(fp_rect
			(start -0.925 -0.47)
			(end 0.925 0.47)
			(stroke
				(width 0.05)
				(type default)
			)
			(fill no)
			(layer "F.CrtYd")
		)
		(fp_rect
			(start -0.5 -0.25)
			(end 0.5 0.25)
			(stroke
				(width 0.15)
				(type solid)
			)
			(fill no)
			(layer "F.Fab")
		)
		(fp_text user "${REFERENCE}"
			(at -0.95 3.168 90)
			(layer "F.Fab")
			(effects
				(font
					(size 0.7 0.7)
					(thickness 0.15)
				)
				(justify left bottom)
			)
		)
		(fp_text user "License: Apache-2.0"
			(at -0.95 5.169 90)
			(layer "F.Fab")
			(effects
				(font
					(size 0.7 0.7)
					(thickness 0.15)
				)
				(justify left bottom)
			)
		)
		(fp_text user "Author: Antmicro"
			(at -0.95 4.169 90)
			(layer "F.Fab")
			(effects
				(font
					(size 0.7 0.7)
					(thickness 0.15)
				)
				(justify left bottom)
			)
		)
		(pad "1" smd roundrect
			(at -0.48 0 90)
			(size 0.59 0.64)
			(layers "F.Cu" "F.Mask" "F.Paste")
			(roundrect_rratio 0.25)
			(net 10 "+5V")
			(pintype "passive")
		)
		(pad "2" smd roundrect
			(at 0.48 0 90)
			(size 0.59 0.64)
			(layers "F.Cu" "F.Mask" "F.Paste")
			(roundrect_rratio 0.25)
			(net 327 "Net-(Q201-D)")
			(pintype "passive")
		)
	)
	(footprint "antmicro-footprints:R_0402_1005Metric"
		(layer "F.Cu")
		(at 123.792962 167.8665)
		(descr "Resistor SMD 0402")
		(tags "resistor SMD 0402")
		(property "Reference" "R511"
			(at -3.837514 0.45 0)
			(layer "F.SilkS")
			(effects
				(font
					(size 0.7 0.7)
					(thickness 0.15)
				)
				(justify left bottom)
			)
		)
		(property "Value" "R_10k_0402"
			(at -1.011843 1.772047 0)
			(layer "F.Fab")
			(effects
				(font
					(size 0.7 0.7)
					(thickness 0.15)
				)
				(justify left bottom)
			)
		)
		(property "Datasheet" "https://www.bourns.com/docs/product-datasheets/cr.pdf"
			(at 0 0 0)
			(layer "F.Fab")
			(hide yes)
			(effects
				(font
					(size 1.27 1.27)
					(thickness 0.15)
				)
			)
		)
		(property "Manufacturer" "Bourns"
			(at 0 0 0)
			(unlocked yes)
			(layer "F.Fab")
			(hide yes)
			(effects
				(font
					(size 1 1)
					(thickness 0.15)
				)
			)
		)
		(property "MPN" "CR0402-FX-1002GLF"
			(at 0 0 0)
			(unlocked yes)
			(layer "F.Fab")
			(hide yes)
			(effects
				(font
					(size 1 1)
					(thickness 0.15)
				)
			)
		)
		(property "Val" "10k"
			(at 0 0 0)
			(unlocked yes)
			(layer "F.Fab")
			(hide yes)
			(effects
				(font
					(size 1 1)
					(thickness 0.15)
				)
			)
		)
		(property "License" "Apache-2.0"
			(at 0 0 0)
			(unlocked yes)
			(layer "F.Fab")
			(hide yes)
			(effects
				(font
					(size 1 1)
					(thickness 0.15)
				)
			)
		)
		(property "Author" "Antmicro"
			(at 0 0 0)
			(unlocked yes)
			(layer "F.Fab")
			(hide yes)
			(effects
				(font
					(size 1 1)
					(thickness 0.15)
				)
			)
		)
		(property "Tolerance" "1%"
			(at 0 0 0)
			(unlocked yes)
			(layer "F.Fab")
			(hide yes)
			(effects
				(font
					(size 1 1)
					(thickness 0.15)
				)
			)
		)
		(sheetname "/NVMe & microSD/")
		(sheetfile "nvme-micro-sd.kicad_sch")
		(attr smd)
		(fp_rect
			(start -0.925 -0.47)
			(end 0.925 0.47)
			(stroke
				(width 0.05)
				(type default)
			)
			(fill no)
			(layer "F.CrtYd")
		)
		(fp_rect
			(start -0.5 -0.25)
			(end 0.5 0.25)
			(stroke
				(width 0.15)
				(type solid)
			)
			(fill no)
			(layer "F.Fab")
		)
		(fp_text user "${REFERENCE}"
			(at -0.95 3.168 0)
			(layer "F.Fab")
			(effects
				(font
					(size 0.7 0.7)
					(thickness 0.15)
				)
				(justify left bottom)
			)
		)
		(fp_text user "Author: Antmicro"
			(at -0.95 4.169 0)
			(layer "F.Fab")
			(effects
				(font
					(size 0.7 0.7)
					(thickness 0.15)
				)
				(justify left bottom)
			)
		)
		(fp_text user "License: Apache-2.0"
			(at -0.95 5.169 0)
			(layer "F.Fab")
			(effects
				(font
					(size 0.7 0.7)
					(thickness 0.15)
				)
				(justify left bottom)
			)
		)
		(pad "1" smd roundrect
			(at -0.48 0)
			(size 0.59 0.64)
			(layers "F.Cu" "F.Mask" "F.Paste")
			(roundrect_rratio 0.25)
			(net 9 "+3V3")
			(pintype "passive")
		)
		(pad "2" smd roundrect
			(at 0.48 0)
			(size 0.59 0.64)
			(layers "F.Cu" "F.Mask" "F.Paste")
			(roundrect_rratio 0.25)
			(net 12 "/Compute module/SDIO.D2")
			(pintype "passive")
		)
	)
	(footprint "antmicro-footprints:LED_0603_1608Metric_G"
		(layer "F.Cu")
		(at 117.627962 139.5915 90)
		(descr "LED SMD 0603 Green")
		(tags "LED SMD 0603 Green")
		(property "Reference" "D305"
			(at -3.325 1.54 90)
			(layer "F.SilkS")
			(effects
				(font
					(size 0.7 0.7)
					(thickness 0.15)
				)
				(justify left bottom)
			)
		)
		(property "Value" "LED_G_0603_KP-1608CGCK"
			(at -0.001 1.599 90)
			(layer "F.Fab")
			(effects
				(font
					(size 0.7 0.7)
					(thickness 0.15)
				)
				(justify left bottom)
			)
		)
		(property "Datasheet" "http://www.kingbright.com/attachments/file/psearch//000/00/00/KP-1608CGCK(Ver.23B).pdf"
			(at 0 0 90)
			(layer "F.Fab")
			(hide yes)
			(effects
				(font
					(size 1.27 1.27)
					(thickness 0.15)
				)
			)
		)
		(property "MPN" "KP-1608CGCK"
			(at 0 0 90)
			(unlocked yes)
			(layer "F.Fab")
			(hide yes)
			(effects
				(font
					(size 1 1)
					(thickness 0.15)
				)
			)
		)
		(property "Manufacturer" "Kingbright"
			(at 0 0 90)
			(unlocked yes)
			(layer "F.Fab")
			(hide yes)
			(effects
				(font
					(size 1 1)
					(thickness 0.15)
				)
			)
		)
		(property "Color" "Green"
			(at 0 0 90)
			(unlocked yes)
			(layer "F.Fab")
			(hide yes)
			(effects
				(font
					(size 1 1)
					(thickness 0.15)
				)
			)
		)
		(property "Author" "Antmicro"
			(at 0 0 90)
			(unlocked yes)
			(layer "F.Fab")
			(hide yes)
			(effects
				(font
					(size 1 1)
					(thickness 0.15)
				)
			)
		)
		(property "License" "Apache-2.0"
			(at 0 0 90)
			(unlocked yes)
			(layer "F.Fab")
			(hide yes)
			(effects
				(font
					(size 1 1)
					(thickness 0.15)
				)
			)
		)
		(sheetname "/Supply/")
		(sheetfile "supply.kicad_sch")
		(attr smd)
		(fp_line
			(start 0.22 -0.35)
			(end -0.22 -0.35)
			(stroke
				(width 0.15)
				(type solid)
			)
			(layer "F.SilkS")
		)
		(fp_line
			(start -1.18 -0.319)
			(end -1.18 0.321)
			(stroke
				(width 0.15)
				(type solid)
			)
			(layer "F.SilkS")
		)
		(fp_line
			(start 0.105328 0.001008)
			(end 0.24 0.001)
			(stroke
				(width 0.1)
				(type solid)
			)
			(layer "F.SilkS")
		)
		(fp_line
			(start -0.094672 0.001008)
			(end 0.105328 -0.198992)
			(stroke
				(width 0.1)
				(type solid)
			)
			(layer "F.SilkS")
		)
		(fp_line
			(start -0.094672 0.001008)
			(end -0.24 0.001008)
			(stroke
				(width 0.1)
				(type solid)
			)
			(layer "F.SilkS")
		)
		(fp_line
			(start 0.105328 0.201008)
			(end 0.105328 -0.198992)
			(stroke
				(width 0.1)
				(type solid)
			)
			(layer "F.SilkS")
		)
		(fp_line
			(start 0.105328 0.201008)
			(end -0.094672 0.001008)
			(stroke
				(width 0.1)
				(type solid)
			)
			(layer "F.SilkS")
		)
		(fp_line
			(start -0.094672 0.201008)
			(end -0.094672 -0.198992)
			(stroke
				(width 0.1)
				(type solid)
			)
			(layer "F.SilkS")
		)
		(fp_line
			(start 0.22 0.35)
			(end -0.22 0.35)
			(stroke
				(width 0.15)
				(type solid)
			)
			(layer "F.SilkS")
		)
		(fp_rect
			(start 1.25 0.65)
			(end -1.25 -0.65)
			(stroke
				(width 0.05)
				(type solid)
			)
			(fill no)
			(layer "F.CrtYd")
		)
		(fp_line
			(start 0.201 -0.202)
			(end -0.101 0)
			(stroke
				(width 0.15)
				(type solid)
			)
			(layer "F.Fab")
		)
		(fp_line
			(start -0.199 -0.202)
			(end -0.199 0.1)
			(stroke
				(width 0.15)
				(type solid)
			)
			(layer "F.Fab")
		)
		(fp_line
			(start 0.599 0)
			(end 0.201 0)
			(stroke
				(width 0.15)
				(type solid)
			)
			(layer "F.Fab")
		)
		(fp_line
			(start 0.201 0)
			(end 0.201 -0.202)
			(stroke
				(width 0.15)
				(type solid)
			)
			(layer "F.Fab")
		)
		(fp_line
			(start -0.101 0)
			(end 0.201 0.2)
			(stroke
				(width 0.15)
				(type solid)
			)
			(layer "F.Fab")
		)
		(fp_line
			(start -0.199 0)
			(end -0.597 0)
			(stroke
				(width 0.15)
				(type solid)
			)
			(layer "F.Fab")
		)
		(fp_line
			(start 0.201 0.2)
			(end 0.201 0)
			(stroke
				(width 0.15)
				(type solid)
			)
			(layer "F.Fab")
		)
		(fp_line
			(start -0.199 0.2)
			(end -0.199 0.1)
			(stroke
				(width 0.15)
				(type solid)
			)
			(layer "F.Fab")
		)
		(fp_rect
			(start 0.848 0.4)
			(end -0.85 -0.402)
			(stroke
				(width 0.15)
				(type solid)
			)
			(fill no)
			(layer "F.Fab")
		)
		(fp_text user "${REFERENCE}"
			(at -1.4224 5.999 90)
			(layer "F.Fab")
			(effects
				(font
					(size 0.7 0.7)
					(thickness 0.15)
				)
				(justify left bottom)
			)
		)
		(fp_text user "License: Apache-2.0"
			(at -1.4224 3.599 90)
			(layer "F.Fab")
			(effects
				(font
					(size 0.7 0.7)
					(thickness 0.15)
				)
				(justify left bottom)
			)
		)
		(fp_text user "Author: Antmicro"
			(at -1.4224 4.799 90)
			(layer "F.Fab")
			(effects
				(font
					(size 0.7 0.7)
					(thickness 0.15)
				)
				(justify left bottom)
			)
		)
		(pad "1" smd roundrect
			(at -0.7 0 270)
			(size 0.8 1)
			(layers "F.Cu" "F.Mask" "F.Paste")
			(roundrect_rratio 0.2)
			(net 3 "GND")
			(pinfunction "C")
			(pintype "passive")
		)
		(pad "2" smd roundrect
			(at 0.7 0 270)
			(size 0.8 1)
			(layers "F.Cu" "F.Mask" "F.Paste")
			(roundrect_rratio 0.2)
			(net 475 "Net-(D305-A)")
			(pinfunction "A")
			(pintype "passive")
		)
	)
	(footprint "antmicro-footprints:R_0402_1005Metric"
		(layer "F.Cu")
		(at 99.717962 147.5665 180)
		(descr "Resistor SMD 0402")
		(tags "resistor SMD 0402")
		(property "Reference" "R931"
			(at -3.6 -0.7 0)
			(layer "F.SilkS")
			(effects
				(font
					(size 0.7 0.7)
					(thickness 0.15)
				)
				(justify right bottom)
			)
		)
		(property "Value" "R_0R_0402"
			(at -1.011843 1.772047 0)
			(layer "F.Fab")
			(effects
				(font
					(size 0.7 0.7)
					(thickness 0.15)
				)
				(justify right bottom)
			)
		)
		(property "Datasheet" "https://industrial.panasonic.com/cdbs/www-data/pdf/RDA0000/AOA0000C301.pdf"
			(at 0 0 180)
			(layer "F.Fab")
			(hide yes)
			(effects
				(font
					(size 1.27 1.27)
					(thickness 0.15)
				)
			)
		)
		(property "Manufacturer" "Panasonic"
			(at 0 0 180)
			(unlocked yes)
			(layer "F.Fab")
			(hide yes)
			(effects
				(font
					(size 1 1)
					(thickness 0.15)
				)
			)
		)
		(property "MPN" "ERJ2GE0R00X"
			(at 0 0 180)
			(unlocked yes)
			(layer "F.Fab")
			(hide yes)
			(effects
				(font
					(size 1 1)
					(thickness 0.15)
				)
			)
		)
		(property "Val" "0R"
			(at 0 0 180)
			(unlocked yes)
			(layer "F.Fab")
			(hide yes)
			(effects
				(font
					(size 1 1)
					(thickness 0.15)
				)
			)
		)
		(property "License" "Apache-2.0"
			(at 0 0 180)
			(unlocked yes)
			(layer "F.Fab")
			(hide yes)
			(effects
				(font
					(size 1 1)
					(thickness 0.15)
				)
			)
		)
		(property "Author" "Antmicro"
			(at 0 0 180)
			(unlocked yes)
			(layer "F.Fab")
			(hide yes)
			(effects
				(font
					(size 1 1)
					(thickness 0.15)
				)
			)
		)
		(property "Tolerance" "~"
			(at 0 0 180)
			(unlocked yes)
			(layer "F.Fab")
			(hide yes)
			(effects
				(font
					(size 1 1)
					(thickness 0.15)
				)
			)
		)
		(property "Current" "1A"
			(at 0 0 180)
			(unlocked yes)
			(layer "F.Fab")
			(hide yes)
			(effects
				(font
					(size 1 1)
					(thickness 0.15)
				)
			)
		)
		(sheetname "/USB/")
		(sheetfile "usb.kicad_sch")
		(attr smd)
		(fp_rect
			(start -0.925 -0.47)
			(end 0.925 0.47)
			(stroke
				(width 0.05)
				(type default)
			)
			(fill no)
			(layer "F.CrtYd")
		)
		(fp_rect
			(start -0.5 -0.25)
			(end 0.5 0.25)
			(stroke
				(width 0.15)
				(type solid)
			)
			(fill no)
			(layer "F.Fab")
		)
		(fp_text user "${REFERENCE}"
			(at -0.95 3.168 180)
			(layer "F.Fab")
			(effects
				(font
					(size 0.7 0.7)
					(thickness 0.15)
				)
				(justify left bottom)
			)
		)
		(fp_text user "License: Apache-2.0"
			(at -0.95 5.169 180)
			(layer "F.Fab")
			(effects
				(font
					(size 0.7 0.7)
					(thickness 0.15)
				)
				(justify left bottom)
			)
		)
		(fp_text user "Author: Antmicro"
			(at -0.95 4.169 180)
			(layer "F.Fab")
			(effects
				(font
					(size 0.7 0.7)
					(thickness 0.15)
				)
				(justify left bottom)
			)
		)
		(pad "1" smd roundrect
			(at -0.48 0 180)
			(size 0.59 0.64)
			(layers "F.Cu" "F.Mask" "F.Paste")
			(roundrect_rratio 0.25)
			(net 490 "Net-(Q905-G)")
			(pintype "passive")
		)
		(pad "2" smd roundrect
			(at 0.48 0 180)
			(size 0.59 0.64)
			(layers "F.Cu" "F.Mask" "F.Paste")
			(roundrect_rratio 0.25)
			(net 463 "/USB/I2C_EN")
			(pintype "passive")
		)
	)
	(footprint "antmicro-footprints:R_0402_1005Metric"
		(layer "F.Cu")
		(at 77.65 170.0665 -90)
		(descr "Resistor SMD 0402")
		(tags "resistor SMD 0402")
		(property "Reference" "R242"
			(at -3.98 -11.56 90)
			(layer "F.SilkS")
			(effects
				(font
					(size 0.7 0.7)
					(thickness 0.15)
				)
				(justify right bottom)
			)
		)
		(property "Value" "R_200R_0402"
			(at -1.011843 1.772047 90)
			(layer "F.Fab")
			(effects
				(font
					(size 0.7 0.7)
					(thickness 0.15)
				)
				(justify right bottom)
			)
		)
		(property "Datasheet" "https://www.bourns.com/docs/product-datasheets/cr.pdf"
			(at 0 0 270)
			(layer "F.Fab")
			(hide yes)
			(effects
				(font
					(size 1.27 1.27)
					(thickness 0.15)
				)
			)
		)
		(property "Manufacturer" "Bourns"
			(at 0 0 270)
			(unlocked yes)
			(layer "F.Fab")
			(hide yes)
			(effects
				(font
					(size 1 1)
					(thickness 0.15)
				)
			)
		)
		(property "MPN" "CR0402-FX-2000GLF"
			(at 0 0 270)
			(unlocked yes)
			(layer "F.Fab")
			(hide yes)
			(effects
				(font
					(size 1 1)
					(thickness 0.15)
				)
			)
		)
		(property "Val" "200R"
			(at 0 0 270)
			(unlocked yes)
			(layer "F.Fab")
			(hide yes)
			(effects
				(font
					(size 1 1)
					(thickness 0.15)
				)
			)
		)
		(property "License" "Apache-2.0"
			(at 0 0 270)
			(unlocked yes)
			(layer "F.Fab")
			(hide yes)
			(effects
				(font
					(size 1 1)
					(thickness 0.15)
				)
			)
		)
		(property "Author" "Antmicro"
			(at 0 0 270)
			(unlocked yes)
			(layer "F.Fab")
			(hide yes)
			(effects
				(font
					(size 1 1)
					(thickness 0.15)
				)
			)
		)
		(property "Tolerance" "1%"
			(at 0 0 270)
			(unlocked yes)
			(layer "F.Fab")
			(hide yes)
			(effects
				(font
					(size 1 1)
					(thickness 0.15)
				)
			)
		)
		(sheetname "/Compute module/")
		(sheetfile "compute-module.kicad_sch")
		(attr smd exclude_from_pos_files exclude_from_bom dnp)
		(fp_rect
			(start -0.925 -0.47)
			(end 0.925 0.47)
			(stroke
				(width 0.05)
				(type default)
			)
			(fill no)
			(layer "F.CrtYd")
		)
		(fp_rect
			(start -0.5 -0.25)
			(end 0.5 0.25)
			(stroke
				(width 0.15)
				(type solid)
			)
			(fill no)
			(layer "F.Fab")
		)
		(fp_text user "${REFERENCE}"
			(at -0.95 3.168 270)
			(layer "F.Fab")
			(effects
				(font
					(size 0.7 0.7)
					(thickness 0.15)
				)
				(justify left bottom)
			)
		)
		(fp_text user "License: Apache-2.0"
			(at -0.95 5.169 270)
			(layer "F.Fab")
			(effects
				(font
					(size 0.7 0.7)
					(thickness 0.15)
				)
				(justify left bottom)
			)
		)
		(fp_text user "Author: Antmicro"
			(at -0.95 4.169 270)
			(layer "F.Fab")
			(effects
				(font
					(size 0.7 0.7)
					(thickness 0.15)
				)
				(justify left bottom)
			)
		)
		(pad "1" smd roundrect
			(at -0.48 0 270)
			(size 0.59 0.64)
			(layers "F.Cu" "F.Mask" "F.Paste")
			(roundrect_rratio 0.25)
			(net 276 "Net-(U204-GPA3)")
			(pintype "passive")
		)
		(pad "2" smd roundrect
			(at 0.48 0 270)
			(size 0.59 0.64)
			(layers "F.Cu" "F.Mask" "F.Paste")
			(roundrect_rratio 0.25)
			(net 469 "Net-(D207-C)")
			(pintype "passive")
		)
	)
	(footprint "antmicro-footprints:TP_SMD_0.75mm"
		(layer "F.Cu")
		(at 76 162.9565 180)
		(property "Reference" "TP206"
			(at 8.55 -0.1935 0)
			(layer "F.SilkS")
			(effects
				(font
					(size 0.7 0.7)
					(thickness 0.15)
				)
				(justify right bottom)
			)
		)
		(property "Value" "TP_0.75mm_SMD"
			(at 0 1.2 0)
			(layer "F.Fab")
			(effects
				(font
					(size 0.7 0.7)
					(thickness 0.15)
				)
				(justify right bottom)
			)
		)
		(property "Author" "Antmicro"
			(at 0 0 180)
			(unlocked yes)
			(layer "F.Fab")
			(hide yes)
			(effects
				(font
					(size 1 1)
					(thickness 0.15)
				)
			)
		)
		(property "License" "Apache-2.0"
			(at 0 0 180)
			(unlocked yes)
			(layer "F.Fab")
			(hide yes)
			(effects
				(font
					(size 1 1)
					(thickness 0.15)
				)
			)
		)
		(property "MPN" ""
			(at 0 0 180)
			(unlocked yes)
			(layer "F.Fab")
			(hide yes)
			(effects
				(font
					(size 1 1)
					(thickness 0.15)
				)
			)
		)
		(property "Manufacturer" ""
			(at 0 0 180)
			(unlocked yes)
			(layer "F.Fab")
			(hide yes)
			(effects
				(font
					(size 1 1)
					(thickness 0.15)
				)
			)
		)
		(sheetname "/Compute module/")
		(sheetfile "compute-module.kicad_sch")
		(attr exclude_from_pos_files exclude_from_bom)
		(fp_circle
			(center 0 0)
			(end 0.475 0)
			(stroke
				(width 0.05)
				(type default)
			)
			(fill no)
			(layer "F.CrtYd")
		)
		(fp_text user "${REFERENCE}"
			(at -0.4 2.7 180)
			(layer "F.Fab")
			(effects
				(font
					(size 0.7 0.7)
					(thickness 0.15)
				)
				(justify left bottom)
			)
		)
		(fp_text user "Author: Antmicro"
			(at -0.4 3.901 180)
			(layer "F.Fab")
			(effects
				(font
					(size 0.7 0.7)
					(thickness 0.15)
				)
				(justify left bottom)
			)
		)
		(fp_text user "License: Apache-2.0"
			(at -0.4 5.101 180)
			(layer "F.Fab")
			(effects
				(font
					(size 0.7 0.7)
					(thickness 0.15)
				)
				(justify left bottom)
			)
		)
		(pad "1" smd circle
			(at 0 0 180)
			(size 0.75 0.75)
			(layers "F.Cu" "F.Mask")
			(net 248 "/Compute module/BT_nDis")
			(pinfunction "1")
			(pintype "passive")
		)
	)
	(footprint "antmicro-footprints:C_0402_1005Metric"
		(layer "F.Cu")
		(at 63.61 174.2415)
		(descr "Capacitor SMD 0402")
		(tags "capacitor SMD 0402")
		(property "Reference" "C823"
			(at -13.36 -2.9915 0)
			(layer "F.SilkS")
			(effects
				(font
					(size 0.7 0.7)
					(thickness 0.15)
				)
				(justify right top)
			)
		)
		(property "Value" "C_template_name_0402"
			(at -1.022927 2.155213 0)
			(layer "F.Fab")
			(effects
				(font
					(size 0.7 0.7)
					(thickness 0.15)
				)
				(justify left bottom)
			)
		)
		(property "Datasheet" "template_datasheet"
			(at 0 0 0)
			(layer "F.Fab")
			(hide yes)
			(effects
				(font
					(size 1.27 1.27)
					(thickness 0.15)
				)
			)
		)
		(property "MPN" "template_MPN"
			(at 0 0 0)
			(unlocked yes)
			(layer "F.Fab")
			(hide yes)
			(effects
				(font
					(size 1 1)
					(thickness 0.15)
				)
			)
		)
		(property "Manufacturer" "template_manufacturer"
			(at 0 0 0)
			(unlocked yes)
			(layer "F.Fab")
			(hide yes)
			(effects
				(font
					(size 1 1)
					(thickness 0.15)
				)
			)
		)
		(property "License" "Apache-2.0"
			(at 0 0 0)
			(unlocked yes)
			(layer "F.Fab")
			(hide yes)
			(effects
				(font
					(size 1 1)
					(thickness 0.15)
				)
			)
		)
		(property "Author" "Antmicro"
			(at 0 0 0)
			(unlocked yes)
			(layer "F.Fab")
			(hide yes)
			(effects
				(font
					(size 1 1)
					(thickness 0.15)
				)
			)
		)
		(property "Val" "template_value"
			(at 0 0 0)
			(unlocked yes)
			(layer "F.Fab")
			(hide yes)
			(effects
				(font
					(size 1 1)
					(thickness 0.15)
				)
			)
		)
		(property "Voltage" "template_voltage"
			(at 0 0 0)
			(unlocked yes)
			(layer "F.Fab")
			(hide yes)
			(effects
				(font
					(size 1 1)
					(thickness 0.15)
				)
			)
		)
		(property "Dielectric" "template_dielectric"
			(at 0 0 0)
			(unlocked yes)
			(layer "F.Fab")
			(hide yes)
			(effects
				(font
					(size 1 1)
					(thickness 0.15)
				)
			)
		)
		(sheetname "/Peripherals/")
		(sheetfile "peripherals.kicad_sch")
		(attr smd exclude_from_pos_files exclude_from_bom dnp)
		(fp_rect
			(start -0.925 -0.47)
			(end 0.925 0.47)
			(stroke
				(width 0.05)
				(type default)
			)
			(fill no)
			(layer "F.CrtYd")
		)
		(fp_line
			(start -0.494 -0.25)
			(end 0.504 -0.25)
			(stroke
				(width 0.15)
				(type solid)
			)
			(layer "F.Fab")
		)
		(fp_line
			(start -0.494 0.248)
			(end -0.494 -0.25)
			(stroke
				(width 0.15)
				(type solid)
			)
			(layer "F.Fab")
		)
		(fp_line
			(start 0.504 -0.25)
			(end 0.504 0.248)
			(stroke
				(width 0.15)
				(type solid)
			)
			(layer "F.Fab")
		)
		(fp_line
			(start 0.504 0.248)
			(end -0.494 0.248)
			(stroke
				(width 0.15)
				(type solid)
			)
			(layer "F.Fab")
		)
		(fp_text user "License: Apache-2.0"
			(at -0.939 5.799 0)
			(layer "F.Fab")
			(effects
				(font
					(size 0.7 0.7)
					(thickness 0.15)
				)
				(justify left bottom)
			)
		)
		(fp_text user "Author: Antmicro"
			(at -0.939 3.399 0)
			(layer "F.Fab")
			(effects
				(font
					(size 0.7 0.7)
					(thickness 0.15)
				)
				(justify left bottom)
			)
		)
		(fp_text user "${REFERENCE}"
			(at -0.939 4.599 0)
			(layer "F.Fab")
			(effects
				(font
					(size 0.7 0.7)
					(thickness 0.15)
				)
				(justify left bottom)
			)
		)
		(pad "1" smd roundrect
			(at -0.48 0)
			(size 0.59 0.64)
			(layers "F.Cu" "F.Mask" "F.Paste")
			(roundrect_rratio 0.25)
			(net 106 "Net-(C814-Pad2)")
			(pintype "passive")
		)
		(pad "2" smd roundrect
			(at 0.48 0)
			(size 0.59 0.64)
			(layers "F.Cu" "F.Mask" "F.Paste")
			(roundrect_rratio 0.25)
			(net 110 "Net-(C817-Pad1)")
			(pintype "passive")
		)
	)
	(footprint "antmicro-footprints:Nexperia_DFN-10_2.5x1mm_P0.5mm"
		(layer "F.Cu")
		(at 142.292962 141.4165 90)
		(property "Reference" "D804"
			(at 2.61 0.155 90)
			(layer "F.SilkS")
			(effects
				(font
					(size 0.7 0.7)
					(thickness 0.15)
				)
				(justify left bottom)
			)
		)
		(property "Value" "PUSB3F96X_PASS"
			(at -0.016 1.705 90)
			(layer "F.Fab")
			(effects
				(font
					(size 0.7 0.7)
					(thickness 0.15)
				)
				(justify left bottom)
			)
		)
		(property "Datasheet" "https://mouser.com/datasheet/2/916/PUSB3F96-1600324.pdf"
			(at 0 0 90)
			(layer "F.Fab")
			(hide yes)
			(effects
				(font
					(size 1.27 1.27)
					(thickness 0.15)
				)
			)
		)
		(property "Manufacturer" "Nexperia"
			(at 0 0 90)
			(unlocked yes)
			(layer "F.Fab")
			(hide yes)
			(effects
				(font
					(size 1 1)
					(thickness 0.15)
				)
			)
		)
		(property "MPN" "PUSB3F96X"
			(at 0 0 90)
			(unlocked yes)
			(layer "F.Fab")
			(hide yes)
			(effects
				(font
					(size 1 1)
					(thickness 0.15)
				)
			)
		)
		(property "Author" "Antmicro"
			(at 0 0 90)
			(unlocked yes)
			(layer "F.Fab")
			(hide yes)
			(effects
				(font
					(size 1 1)
					(thickness 0.15)
				)
			)
		)
		(property "License" "Apache-2.0"
			(at 0 0 90)
			(unlocked yes)
			(layer "F.Fab")
			(hide yes)
			(effects
				(font
					(size 1 1)
					(thickness 0.15)
				)
			)
		)
		(sheetname "/Peripherals/")
		(sheetfile "peripherals.kicad_sch")
		(attr smd)
		(fp_line
			(start -1.375 -0.4)
			(end -1.375 0.4)
			(stroke
				(width 0.15)
				(type solid)
			)
			(layer "F.SilkS")
		)
		(fp_line
			(start 1.375 0.4)
			(end 1.375 -0.4)
			(stroke
				(width 0.15)
				(type solid)
			)
			(layer "F.SilkS")
		)
		(fp_circle
			(center -1.4 0.7)
			(end -1.349 0.7)
			(stroke
				(width 0.15)
				(type solid)
			)
			(fill yes)
			(layer "F.SilkS")
		)
		(fp_rect
			(start -1.4 -0.725)
			(end 1.4 0.725)
			(stroke
				(width 0.05)
				(type solid)
			)
			(fill no)
			(layer "F.CrtYd")
		)
		(fp_line
			(start 1.25 -0.5)
			(end -1.25 -0.5)
			(stroke
				(width 0.15)
				(type solid)
			)
			(layer "F.Fab")
		)
		(fp_line
			(start -1.25 -0.5)
			(end -1.25 0.15)
			(stroke
				(width 0.15)
				(type solid)
			)
			(layer "F.Fab")
		)
		(fp_line
			(start -1.25 0.15)
			(end -0.9 0.5)
			(stroke
				(width 0.15)
				(type solid)
			)
			(layer "F.Fab")
		)
		(fp_line
			(start 1.25 0.5)
			(end 1.25 -0.5)
			(stroke
				(width 0.15)
				(type solid)
			)
			(layer "F.Fab")
		)
		(fp_line
			(start -0.9 0.5)
			(end 1.25 0.5)
			(stroke
				(width 0.15)
				(type solid)
			)
			(layer "F.Fab")
		)
		(fp_text user "Author: Antmicro"
			(at -1.367 4.905 90)
			(layer "F.Fab")
			(effects
				(font
					(size 0.7 0.7)
					(thickness 0.15)
				)
				(justify left bottom)
			)
		)
		(fp_text user "License: Apache-2.0"
			(at -1.367 6.105 90)
			(layer "F.Fab")
			(effects
				(font
					(size 0.7 0.7)
					(thickness 0.15)
				)
				(justify left bottom)
			)
		)
		(fp_text user "${REFERENCE}"
			(at -1.367 3.704 90)
			(layer "F.Fab")
			(effects
				(font
					(size 0.7 0.7)
					(thickness 0.15)
				)
				(justify left bottom)
			)
		)
		(pad "1" smd rect
			(at -1 0.3875 90)
			(size 0.2 0.475)
			(layers "F.Cu" "F.Mask" "F.Paste")
			(net 223 "/Compute module/GPIO.6")
			(pinfunction "CH1")
			(pintype "passive")
			(solder_mask_margin 0.05)
		)
		(pad "2" smd rect
			(at -0.5 0.3875 90)
			(size 0.2 0.475)
			(layers "F.Cu" "F.Mask" "F.Paste")
			(net 221 "/Compute module/GPIO.13{slash}TXD5")
			(pinfunction "CH2")
			(pintype "passive")
			(solder_mask_margin 0.05)
		)
		(pad "3" smd rect
			(at 0 0.3875 90)
			(size 0.2 0.475)
			(layers "F.Cu" "F.Mask" "F.Paste")
			(net 3 "GND")
			(pinfunction "GND")
			(pintype "passive")
			(solder_mask_margin 0.05)
		)
		(pad "4" smd rect
			(at 0.5 0.3875 90)
			(size 0.2 0.475)
			(layers "F.Cu" "F.Mask" "F.Paste")
			(net 219 "/Compute module/GPIO.19")
			(pinfunction "CH3")
			(pintype "passive")
			(solder_mask_margin 0.05)
		)
		(pad "5" smd rect
			(at 1 0.3875 90)
			(size 0.2 0.475)
			(layers "F.Cu" "F.Mask" "F.Paste")
			(net 217 "/Compute module/GPIO.26")
			(pinfunction "CH4")
			(pintype "passive")
			(solder_mask_margin 0.05)
		)
		(pad "6" smd rect
			(at 1 -0.3875 90)
			(size 0.2 0.475)
			(layers "F.Cu" "F.Mask" "F.Paste")
			(net 217 "/Compute module/GPIO.26")
			(pinfunction "CH4")
			(pintype "passive")
			(solder_mask_margin 0.05)
		)
		(pad "7" smd rect
			(at 0.5 -0.3875 90)
			(size 0.2 0.475)
			(layers "F.Cu" "F.Mask" "F.Paste")
			(net 219 "/Compute module/GPIO.19")
			(pinfunction "CH3")
			(pintype "passive")
			(solder_mask_margin 0.05)
		)
		(pad "8" smd rect
			(at 0 -0.3875 90)
			(size 0.2 0.475)
			(layers "F.Cu" "F.Mask" "F.Paste")
			(net 3 "GND")
			(pinfunction "GND")
			(pintype "passive")
			(solder_mask_margin 0.05)
		)
		(pad "9" smd rect
			(at -0.501 -0.3875 90)
			(size 0.2 0.475)
			(layers "F.Cu" "F.Mask" "F.Paste")
			(net 221 "/Compute module/GPIO.13{slash}TXD5")
			(pinfunction "CH2")
			(pintype "passive")
			(solder_mask_margin 0.05)
		)
		(pad "10" smd rect
			(at -1 -0.3875 90)
			(size 0.2 0.475)
			(layers "F.Cu" "F.Mask" "F.Paste")
			(net 223 "/Compute module/GPIO.6")
			(pinfunction "CH1")
			(pintype "passive")
			(solder_mask_margin 0.05)
		)
	)
	(footprint "antmicro-footprints:LED_0603_1608Metric_G"
		(layer "F.Cu")
		(at 73.767962 158.4865 180)
		(descr "LED SMD 0603 Green")
		(tags "LED SMD 0603 Green")
		(property "Reference" "D304"
			(at 6.15 0.42 0)
			(layer "F.SilkS")
			(effects
				(font
					(size 0.7 0.7)
					(thickness 0.15)
				)
				(justify right bottom)
			)
		)
		(property "Value" "LED_G_0603_KP-1608CGCK"
			(at -0.001 1.599 0)
			(layer "F.Fab")
			(effects
				(font
					(size 0.7 0.7)
					(thickness 0.15)
				)
				(justify right bottom)
			)
		)
		(property "Datasheet" "http://www.kingbright.com/attachments/file/psearch//000/00/00/KP-1608CGCK(Ver.23B).pdf"
			(at 0 0 180)
			(layer "F.Fab")
			(hide yes)
			(effects
				(font
					(size 1.27 1.27)
					(thickness 0.15)
				)
			)
		)
		(property "MPN" "KP-1608CGCK"
			(at 0 0 180)
			(unlocked yes)
			(layer "F.Fab")
			(hide yes)
			(effects
				(font
					(size 1 1)
					(thickness 0.15)
				)
			)
		)
		(property "Manufacturer" "Kingbright"
			(at 0 0 180)
			(unlocked yes)
			(layer "F.Fab")
			(hide yes)
			(effects
				(font
					(size 1 1)
					(thickness 0.15)
				)
			)
		)
		(property "Color" "Green"
			(at 0 0 180)
			(unlocked yes)
			(layer "F.Fab")
			(hide yes)
			(effects
				(font
					(size 1 1)
					(thickness 0.15)
				)
			)
		)
		(property "Author" "Antmicro"
			(at 0 0 180)
			(unlocked yes)
			(layer "F.Fab")
			(hide yes)
			(effects
				(font
					(size 1 1)
					(thickness 0.15)
				)
			)
		)
		(property "License" "Apache-2.0"
			(at 0 0 180)
			(unlocked yes)
			(layer "F.Fab")
			(hide yes)
			(effects
				(font
					(size 1 1)
					(thickness 0.15)
				)
			)
		)
		(sheetname "/Supply/")
		(sheetfile "supply.kicad_sch")
		(attr smd)
		(fp_line
			(start 0.22 0.35)
			(end -0.22 0.35)
			(stroke
				(width 0.15)
				(type solid)
			)
			(layer "F.SilkS")
		)
		(fp_line
			(start 0.22 -0.35)
			(end -0.22 -0.35)
			(stroke
				(width 0.15)
				(type solid)
			)
			(layer "F.SilkS")
		)
		(fp_line
			(start 0.105328 0.201008)
			(end 0.105328 -0.198992)
			(stroke
				(width 0.1)
				(type solid)
			)
			(layer "F.SilkS")
		)
		(fp_line
			(start 0.105328 0.201008)
			(end -0.094672 0.001008)
			(stroke
				(width 0.1)
				(type solid)
			)
			(layer "F.SilkS")
		)
		(fp_line
			(start 0.105328 0.001008)
			(end 0.24 0.001)
			(stroke
				(width 0.1)
				(type solid)
			)
			(layer "F.SilkS")
		)
		(fp_line
			(start -0.094672 0.201008)
			(end -0.094672 -0.198992)
			(stroke
				(width 0.1)
				(type solid)
			)
			(layer "F.SilkS")
		)
		(fp_line
			(start -0.094672 0.001008)
			(end 0.105328 -0.198992)
			(stroke
				(width 0.1)
				(type solid)
			)
			(layer "F.SilkS")
		)
		(fp_line
			(start -0.094672 0.001008)
			(end -0.24 0.001008)
			(stroke
				(width 0.1)
				(type solid)
			)
			(layer "F.SilkS")
		)
		(fp_line
			(start -1.18 -0.319)
			(end -1.18 0.321)
			(stroke
				(width 0.15)
				(type solid)
			)
			(layer "F.SilkS")
		)
		(fp_rect
			(start 1.25 0.65)
			(end -1.25 -0.65)
			(stroke
				(width 0.05)
				(type solid)
			)
			(fill no)
			(layer "F.CrtYd")
		)
		(fp_line
			(start 0.599 0)
			(end 0.201 0)
			(stroke
				(width 0.15)
				(type solid)
			)
			(layer "F.Fab")
		)
		(fp_line
			(start 0.201 0.2)
			(end 0.201 0)
			(stroke
				(width 0.15)
				(type solid)
			)
			(layer "F.Fab")
		)
		(fp_line
			(start 0.201 0)
			(end 0.201 -0.202)
			(stroke
				(width 0.15)
				(type solid)
			)
			(layer "F.Fab")
		)
		(fp_line
			(start 0.201 -0.202)
			(end -0.101 0)
			(stroke
				(width 0.15)
				(type solid)
			)
			(layer "F.Fab")
		)
		(fp_line
			(start -0.101 0)
			(end 0.201 0.2)
			(stroke
				(width 0.15)
				(type solid)
			)
			(layer "F.Fab")
		)
		(fp_line
			(start -0.199 0.2)
			(end -0.199 0.1)
			(stroke
				(width 0.15)
				(type solid)
			)
			(layer "F.Fab")
		)
		(fp_line
			(start -0.199 0)
			(end -0.597 0)
			(stroke
				(width 0.15)
				(type solid)
			)
			(layer "F.Fab")
		)
		(fp_line
			(start -0.199 -0.202)
			(end -0.199 0.1)
			(stroke
				(width 0.15)
				(type solid)
			)
			(layer "F.Fab")
		)
		(fp_rect
			(start 0.848 0.4)
			(end -0.85 -0.402)
			(stroke
				(width 0.15)
				(type solid)
			)
			(fill no)
			(layer "F.Fab")
		)
		(fp_text user "License: Apache-2.0"
			(at -1.4224 3.599 180)
			(layer "F.Fab")
			(effects
				(font
					(size 0.7 0.7)
					(thickness 0.15)
				)
				(justify left bottom)
			)
		)
		(fp_text user "Author: Antmicro"
			(at -1.4224 4.799 180)
			(layer "F.Fab")
			(effects
				(font
					(size 0.7 0.7)
					(thickness 0.15)
				)
				(justify left bottom)
			)
		)
		(fp_text user "${REFERENCE}"
			(at -1.4224 5.999 180)
			(layer "F.Fab")
			(effects
				(font
					(size 0.7 0.7)
					(thickness 0.15)
				)
				(justify left bottom)
			)
		)
		(pad "1" smd roundrect
			(at -0.7 0)
			(size 0.8 1)
			(layers "F.Cu" "F.Mask" "F.Paste")
			(roundrect_rratio 0.2)
			(net 3 "GND")
			(pinfunction "C")
			(pintype "passive")
		)
		(pad "2" smd roundrect
			(at 0.7 0)
			(size 0.8 1)
			(layers "F.Cu" "F.Mask" "F.Paste")
			(roundrect_rratio 0.2)
			(net 474 "Net-(D304-A)")
			(pinfunction "A")
			(pintype "passive")
		)
	)
	(footprint "antmicro-footprints:C_0402_1005Metric"
		(layer "F.Cu")
		(at 92.142962 144.3165 -90)
		(descr "Capacitor SMD 0402")
		(tags "capacitor SMD 0402")
		(property "Reference" "C914"
			(at 0.425 -2.225 90)
			(layer "F.SilkS")
			(effects
				(font
					(size 0.7 0.7)
					(thickness 0.15)
				)
				(justify right bottom)
			)
		)
		(property "Value" "C_100n_0402"
			(at -1.022927 2.155213 90)
			(layer "F.Fab")
			(effects
				(font
					(size 0.7 0.7)
					(thickness 0.15)
				)
				(justify right bottom)
			)
		)
		(property "Datasheet" "https://www.murata.com/products/productdetail?partno=GRM155R61H104KE14%23"
			(at 0 0 270)
			(layer "F.Fab")
			(hide yes)
			(effects
				(font
					(size 1.27 1.27)
					(thickness 0.15)
				)
			)
		)
		(property "Manufacturer" "Murata"
			(at 0 0 270)
			(unlocked yes)
			(layer "F.Fab")
			(hide yes)
			(effects
				(font
					(size 1 1)
					(thickness 0.15)
				)
			)
		)
		(property "MPN" "GRM155R61H104KE14D"
			(at 0 0 270)
			(unlocked yes)
			(layer "F.Fab")
			(hide yes)
			(effects
				(font
					(size 1 1)
					(thickness 0.15)
				)
			)
		)
		(property "Val" "100n"
			(at 0 0 270)
			(unlocked yes)
			(layer "F.Fab")
			(hide yes)
			(effects
				(font
					(size 1 1)
					(thickness 0.15)
				)
			)
		)
		(property "License" "Apache-2.0"
			(at 0 0 270)
			(unlocked yes)
			(layer "F.Fab")
			(hide yes)
			(effects
				(font
					(size 1 1)
					(thickness 0.15)
				)
			)
		)
		(property "Author" "Antmicro"
			(at 0 0 270)
			(unlocked yes)
			(layer "F.Fab")
			(hide yes)
			(effects
				(font
					(size 1 1)
					(thickness 0.15)
				)
			)
		)
		(property "Voltage" "50V"
			(at 0 0 270)
			(unlocked yes)
			(layer "F.Fab")
			(hide yes)
			(effects
				(font
					(size 1 1)
					(thickness 0.15)
				)
			)
		)
		(property "Dielectric" "X5R"
			(at 0 0 270)
			(unlocked yes)
			(layer "F.Fab")
			(hide yes)
			(effects
				(font
					(size 1 1)
					(thickness 0.15)
				)
			)
		)
		(sheetname "/USB/")
		(sheetfile "usb.kicad_sch")
		(attr smd)
		(fp_rect
			(start -0.925 -0.47)
			(end 0.925 0.47)
			(stroke
				(width 0.05)
				(type default)
			)
			(fill no)
			(layer "F.CrtYd")
		)
		(fp_line
			(start -0.494 0.248)
			(end -0.494 -0.25)
			(stroke
				(width 0.15)
				(type solid)
			)
			(layer "F.Fab")
		)
		(fp_line
			(start 0.504 0.248)
			(end -0.494 0.248)
			(stroke
				(width 0.15)
				(type solid)
			)
			(layer "F.Fab")
		)
		(fp_line
			(start -0.494 -0.25)
			(end 0.504 -0.25)
			(stroke
				(width 0.15)
				(type solid)
			)
			(layer "F.Fab")
		)
		(fp_line
			(start 0.504 -0.25)
			(end 0.504 0.248)
			(stroke
				(width 0.15)
				(type solid)
			)
			(layer "F.Fab")
		)
		(fp_text user "License: Apache-2.0"
			(at -0.939 5.799 270)
			(layer "F.Fab")
			(effects
				(font
					(size 0.7 0.7)
					(thickness 0.15)
				)
				(justify left bottom)
			)
		)
		(fp_text user "${REFERENCE}"
			(at -0.939 4.599 270)
			(layer "F.Fab")
			(effects
				(font
					(size 0.7 0.7)
					(thickness 0.15)
				)
				(justify left bottom)
			)
		)
		(fp_text user "Author: Antmicro"
			(at -0.939 3.399 270)
			(layer "F.Fab")
			(effects
				(font
					(size 0.7 0.7)
					(thickness 0.15)
				)
				(justify left bottom)
			)
		)
		(pad "1" smd roundrect
			(at -0.48 0 270)
			(size 0.59 0.64)
			(layers "F.Cu" "F.Mask" "F.Paste")
			(roundrect_rratio 0.25)
			(net 30 "/USB/USB_1V2")
			(pintype "passive")
		)
		(pad "2" smd roundrect
			(at 0.48 0 270)
			(size 0.59 0.64)
			(layers "F.Cu" "F.Mask" "F.Paste")
			(roundrect_rratio 0.25)
			(net 3 "GND")
			(pintype "passive")
		)
	)
	(footprint "antmicro-footprints:R_0402_1005Metric"
		(layer "F.Cu")
		(at 106.467962 139.1665 180)
		(descr "Resistor SMD 0402")
		(tags "resistor SMD 0402")
		(property "Reference" "R924"
			(at -1.38 0.83 0)
			(layer "F.SilkS")
			(effects
				(font
					(size 0.7 0.7)
					(thickness 0.15)
				)
				(justify right bottom)
			)
		)
		(property "Value" "R_10k_0402"
			(at -1.011843 1.772047 0)
			(layer "F.Fab")
			(effects
				(font
					(size 0.7 0.7)
					(thickness 0.15)
				)
				(justify right bottom)
			)
		)
		(property "Datasheet" "https://www.bourns.com/docs/product-datasheets/cr.pdf"
			(at 0 0 180)
			(layer "F.Fab")
			(hide yes)
			(effects
				(font
					(size 1.27 1.27)
					(thickness 0.15)
				)
			)
		)
		(property "Manufacturer" "Bourns"
			(at 0 0 180)
			(unlocked yes)
			(layer "F.Fab")
			(hide yes)
			(effects
				(font
					(size 1 1)
					(thickness 0.15)
				)
			)
		)
		(property "MPN" "CR0402-FX-1002GLF"
			(at 0 0 180)
			(unlocked yes)
			(layer "F.Fab")
			(hide yes)
			(effects
				(font
					(size 1 1)
					(thickness 0.15)
				)
			)
		)
		(property "Val" "10k"
			(at 0 0 180)
			(unlocked yes)
			(layer "F.Fab")
			(hide yes)
			(effects
				(font
					(size 1 1)
					(thickness 0.15)
				)
			)
		)
		(property "License" "Apache-2.0"
			(at 0 0 180)
			(unlocked yes)
			(layer "F.Fab")
			(hide yes)
			(effects
				(font
					(size 1 1)
					(thickness 0.15)
				)
			)
		)
		(property "Author" "Antmicro"
			(at 0 0 180)
			(unlocked yes)
			(layer "F.Fab")
			(hide yes)
			(effects
				(font
					(size 1 1)
					(thickness 0.15)
				)
			)
		)
		(property "Tolerance" "1%"
			(at 0 0 180)
			(unlocked yes)
			(layer "F.Fab")
			(hide yes)
			(effects
				(font
					(size 1 1)
					(thickness 0.15)
				)
			)
		)
		(sheetname "/USB/")
		(sheetfile "usb.kicad_sch")
		(attr smd)
		(fp_rect
			(start -0.925 -0.47)
			(end 0.925 0.47)
			(stroke
				(width 0.05)
				(type default)
			)
			(fill no)
			(layer "F.CrtYd")
		)
		(fp_rect
			(start -0.5 -0.25)
			(end 0.5 0.25)
			(stroke
				(width 0.15)
				(type solid)
			)
			(fill no)
			(layer "F.Fab")
		)
		(fp_text user "${REFERENCE}"
			(at -0.95 3.168 180)
			(layer "F.Fab")
			(effects
				(font
					(size 0.7 0.7)
					(thickness 0.15)
				)
				(justify left bottom)
			)
		)
		(fp_text user "Author: Antmicro"
			(at -0.95 4.169 180)
			(layer "F.Fab")
			(effects
				(font
					(size 0.7 0.7)
					(thickness 0.15)
				)
				(justify left bottom)
			)
		)
		(fp_text user "License: Apache-2.0"
			(at -0.95 5.169 180)
			(layer "F.Fab")
			(effects
				(font
					(size 0.7 0.7)
					(thickness 0.15)
				)
				(justify left bottom)
			)
		)
		(pad "1" smd roundrect
			(at -0.48 0 180)
			(size 0.59 0.64)
			(layers "F.Cu" "F.Mask" "F.Paste")
			(roundrect_rratio 0.25)
			(net 9 "+3V3")
			(pintype "passive")
		)
		(pad "2" smd roundrect
			(at 0.48 0 180)
			(size 0.59 0.64)
			(layers "F.Cu" "F.Mask" "F.Paste")
			(roundrect_rratio 0.25)
			(net 279 "/Compute module/USB.OTGID")
			(pintype "passive")
		)
	)
	(footprint "antmicro-footprints:R_0402_1005Metric"
		(layer "F.Cu")
		(at 129.267962 119.6165)
		(descr "Resistor SMD 0402")
		(tags "resistor SMD 0402")
		(property "Reference" "R213"
			(at -3.7 0.12 0)
			(layer "F.SilkS")
			(effects
				(font
					(size 0.7 0.7)
					(thickness 0.15)
				)
				(justify left bottom)
			)
		)
		(property "Value" "R_100k_0402"
			(at -1.011843 1.772047 0)
			(layer "F.Fab")
			(effects
				(font
					(size 0.7 0.7)
					(thickness 0.15)
				)
				(justify left bottom)
			)
		)
		(property "Datasheet" "https://www.bourns.com/docs/product-datasheets/cr.pdf"
			(at 0 0 0)
			(layer "F.Fab")
			(hide yes)
			(effects
				(font
					(size 1.27 1.27)
					(thickness 0.15)
				)
			)
		)
		(property "Manufacturer" "Bourns"
			(at 0 0 0)
			(unlocked yes)
			(layer "F.Fab")
			(hide yes)
			(effects
				(font
					(size 1 1)
					(thickness 0.15)
				)
			)
		)
		(property "MPN" "CR0402-FX-1003GLF"
			(at 0 0 0)
			(unlocked yes)
			(layer "F.Fab")
			(hide yes)
			(effects
				(font
					(size 1 1)
					(thickness 0.15)
				)
			)
		)
		(property "Val" "100k"
			(at 0 0 0)
			(unlocked yes)
			(layer "F.Fab")
			(hide yes)
			(effects
				(font
					(size 1 1)
					(thickness 0.15)
				)
			)
		)
		(property "License" "Apache-2.0"
			(at 0 0 0)
			(unlocked yes)
			(layer "F.Fab")
			(hide yes)
			(effects
				(font
					(size 1 1)
					(thickness 0.15)
				)
			)
		)
		(property "Author" "Antmicro"
			(at 0 0 0)
			(unlocked yes)
			(layer "F.Fab")
			(hide yes)
			(effects
				(font
					(size 1 1)
					(thickness 0.15)
				)
			)
		)
		(property "Tolerance" "1%"
			(at 0 0 0)
			(unlocked yes)
			(layer "F.Fab")
			(hide yes)
			(effects
				(font
					(size 1 1)
					(thickness 0.15)
				)
			)
		)
		(sheetname "/Compute module/")
		(sheetfile "compute-module.kicad_sch")
		(attr smd)
		(fp_rect
			(start -0.925 -0.47)
			(end 0.925 0.47)
			(stroke
				(width 0.05)
				(type default)
			)
			(fill no)
			(layer "F.CrtYd")
		)
		(fp_rect
			(start -0.5 -0.25)
			(end 0.5 0.25)
			(stroke
				(width 0.15)
				(type solid)
			)
			(fill no)
			(layer "F.Fab")
		)
		(fp_text user "${REFERENCE}"
			(at -0.95 3.168 0)
			(layer "F.Fab")
			(effects
				(font
					(size 0.7 0.7)
					(thickness 0.15)
				)
				(justify left bottom)
			)
		)
		(fp_text user "License: Apache-2.0"
			(at -0.95 5.169 0)
			(layer "F.Fab")
			(effects
				(font
					(size 0.7 0.7)
					(thickness 0.15)
				)
				(justify left bottom)
			)
		)
		(fp_text user "Author: Antmicro"
			(at -0.95 4.169 0)
			(layer "F.Fab")
			(effects
				(font
					(size 0.7 0.7)
					(thickness 0.15)
				)
				(justify left bottom)
			)
		)
		(pad "1" smd roundrect
			(at -0.48 0)
			(size 0.59 0.64)
			(layers "F.Cu" "F.Mask" "F.Paste")
			(roundrect_rratio 0.25)
			(net 3 "GND")
			(pintype "passive")
		)
		(pad "2" smd roundrect
			(at 0.48 0)
			(size 0.59 0.64)
			(layers "F.Cu" "F.Mask" "F.Paste")
			(roundrect_rratio 0.25)
			(net 4 "Net-(D204-A)")
			(pintype "passive")
		)
	)
	(footprint "antmicro-footprints:Nexperia_DFN-10_2.5x1mm_P0.5mm"
		(layer "F.Cu")
		(at 134.079962 144.1785 90)
		(property "Reference" "D809"
			(at -1.298 -1.562 90)
			(layer "F.SilkS")
			(effects
				(font
					(size 0.7 0.7)
					(thickness 0.15)
				)
				(justify left bottom)
			)
		)
		(property "Value" "PUSB3F96X_PASS"
			(at -0.016 1.705 90)
			(layer "F.Fab")
			(effects
				(font
					(size 0.7 0.7)
					(thickness 0.15)
				)
				(justify left bottom)
			)
		)
		(property "Datasheet" "https://mouser.com/datasheet/2/916/PUSB3F96-1600324.pdf"
			(at 0 0 90)
			(layer "F.Fab")
			(hide yes)
			(effects
				(font
					(size 1.27 1.27)
					(thickness 0.15)
				)
			)
		)
		(property "Manufacturer" "Nexperia"
			(at 0 0 90)
			(unlocked yes)
			(layer "F.Fab")
			(hide yes)
			(effects
				(font
					(size 1 1)
					(thickness 0.15)
				)
			)
		)
		(property "MPN" "PUSB3F96X"
			(at 0 0 90)
			(unlocked yes)
			(layer "F.Fab")
			(hide yes)
			(effects
				(font
					(size 1 1)
					(thickness 0.15)
				)
			)
		)
		(property "Author" "Antmicro"
			(at 0 0 90)
			(unlocked yes)
			(layer "F.Fab")
			(hide yes)
			(effects
				(font
					(size 1 1)
					(thickness 0.15)
				)
			)
		)
		(property "License" "Apache-2.0"
			(at 0 0 90)
			(unlocked yes)
			(layer "F.Fab")
			(hide yes)
			(effects
				(font
					(size 1 1)
					(thickness 0.15)
				)
			)
		)
		(sheetname "/Peripherals/")
		(sheetfile "peripherals.kicad_sch")
		(attr smd)
		(fp_line
			(start -1.375 -0.4)
			(end -1.375 0.4)
			(stroke
				(width 0.15)
				(type solid)
			)
			(layer "F.SilkS")
		)
		(fp_line
			(start 1.375 0.4)
			(end 1.375 -0.4)
			(stroke
				(width 0.15)
				(type solid)
			)
			(layer "F.SilkS")
		)
		(fp_circle
			(center -1.4 0.7)
			(end -1.349 0.7)
			(stroke
				(width 0.15)
				(type solid)
			)
			(fill yes)
			(layer "F.SilkS")
		)
		(fp_rect
			(start -1.4 -0.725)
			(end 1.4 0.725)
			(stroke
				(width 0.05)
				(type solid)
			)
			(fill no)
			(layer "F.CrtYd")
		)
		(fp_line
			(start 1.25 -0.5)
			(end -1.25 -0.5)
			(stroke
				(width 0.15)
				(type solid)
			)
			(layer "F.Fab")
		)
		(fp_line
			(start -1.25 -0.5)
			(end -1.25 0.15)
			(stroke
				(width 0.15)
				(type solid)
			)
			(layer "F.Fab")
		)
		(fp_line
			(start -1.25 0.15)
			(end -0.9 0.5)
			(stroke
				(width 0.15)
				(type solid)
			)
			(layer "F.Fab")
		)
		(fp_line
			(start 1.25 0.5)
			(end 1.25 -0.5)
			(stroke
				(width 0.15)
				(type solid)
			)
			(layer "F.Fab")
		)
		(fp_line
			(start -0.9 0.5)
			(end 1.25 0.5)
			(stroke
				(width 0.15)
				(type solid)
			)
			(layer "F.Fab")
		)
		(fp_text user "Author: Antmicro"
			(at -1.367 4.905 90)
			(layer "F.Fab")
			(effects
				(font
					(size 0.7 0.7)
					(thickness 0.15)
				)
				(justify left bottom)
			)
		)
		(fp_text user "${REFERENCE}"
			(at -1.367 3.704 90)
			(layer "F.Fab")
			(effects
				(font
					(size 0.7 0.7)
					(thickness 0.15)
				)
				(justify left bottom)
			)
		)
		(fp_text user "License: Apache-2.0"
			(at -1.367 6.105 90)
			(layer "F.Fab")
			(effects
				(font
					(size 0.7 0.7)
					(thickness 0.15)
				)
				(justify left bottom)
			)
		)
		(pad "1" smd rect
			(at -1 0.3875 90)
			(size 0.2 0.475)
			(layers "F.Cu" "F.Mask" "F.Paste")
			(net 228 "/Compute module/GPIO.8{slash}TXD4")
			(pinfunction "CH1")
			(pintype "passive")
			(solder_mask_margin 0.05)
		)
		(pad "2" smd rect
			(at -0.5 0.3875 90)
			(size 0.2 0.475)
			(layers "F.Cu" "F.Mask" "F.Paste")
			(net 226 "/Compute module/GPIO.7")
			(pinfunction "CH2")
			(pintype "passive")
			(solder_mask_margin 0.05)
		)
		(pad "3" smd rect
			(at 0 0.3875 90)
			(size 0.2 0.475)
			(layers "F.Cu" "F.Mask" "F.Paste")
			(net 3 "GND")
			(pinfunction "GND")
			(pintype "passive")
			(solder_mask_margin 0.05)
		)
		(pad "4" smd rect
			(at 0.5 0.3875 90)
			(size 0.2 0.475)
			(layers "F.Cu" "F.Mask" "F.Paste")
			(net 446 "/Compute module/GPIO.1{slash}SCL0")
			(pinfunction "CH3")
			(pintype "passive")
			(solder_mask_margin 0.05)
		)
		(pad "5" smd rect
			(at 1 0.3875 90)
			(size 0.2 0.475)
			(layers "F.Cu" "F.Mask" "F.Paste")
			(net 253 "/Compute module/GPIO.AIN0")
			(pinfunction "CH4")
			(pintype "passive")
			(solder_mask_margin 0.05)
		)
		(pad "6" smd rect
			(at 1 -0.3875 90)
			(size 0.2 0.475)
			(layers "F.Cu" "F.Mask" "F.Paste")
			(net 253 "/Compute module/GPIO.AIN0")
			(pinfunction "CH4")
			(pintype "passive")
			(solder_mask_margin 0.05)
		)
		(pad "7" smd rect
			(at 0.5 -0.3875 90)
			(size 0.2 0.475)
			(layers "F.Cu" "F.Mask" "F.Paste")
			(net 446 "/Compute module/GPIO.1{slash}SCL0")
			(pinfunction "CH3")
			(pintype "passive")
			(solder_mask_margin 0.05)
		)
		(pad "8" smd rect
			(at 0 -0.3875 90)
			(size 0.2 0.475)
			(layers "F.Cu" "F.Mask" "F.Paste")
			(net 3 "GND")
			(pinfunction "GND")
			(pintype "passive")
			(solder_mask_margin 0.05)
		)
		(pad "9" smd rect
			(at -0.501 -0.3875 90)
			(size 0.2 0.475)
			(layers "F.Cu" "F.Mask" "F.Paste")
			(net 226 "/Compute module/GPIO.7")
			(pinfunction "CH2")
			(pintype "passive")
			(solder_mask_margin 0.05)
		)
		(pad "10" smd rect
			(at -1 -0.3875 90)
			(size 0.2 0.475)
			(layers "F.Cu" "F.Mask" "F.Paste")
			(net 228 "/Compute module/GPIO.8{slash}TXD4")
			(pinfunction "CH1")
			(pintype "passive")
			(solder_mask_margin 0.05)
		)
	)
	(footprint "antmicro-footprints:C_0402_1005Metric"
		(layer "F.Cu")
		(at 94.092962 148.7915)
		(descr "Capacitor SMD 0402")
		(tags "capacitor SMD 0402")
		(property "Reference" "C210"
			(at 2.025 0.425 0)
			(layer "F.SilkS")
			(effects
				(font
					(size 0.7 0.7)
					(thickness 0.15)
				)
				(justify left bottom)
			)
		)
		(property "Value" "C_100n_0402"
			(at -1.022927 2.155213 0)
			(layer "F.Fab")
			(effects
				(font
					(size 0.7 0.7)
					(thickness 0.15)
				)
				(justify left bottom)
			)
		)
		(property "Datasheet" "https://www.murata.com/products/productdetail?partno=GRM155R61H104KE14%23"
			(at 0 0 0)
			(layer "F.Fab")
			(hide yes)
			(effects
				(font
					(size 1.27 1.27)
					(thickness 0.15)
				)
			)
		)
		(property "Manufacturer" "Murata"
			(at 0 0 0)
			(unlocked yes)
			(layer "F.Fab")
			(hide yes)
			(effects
				(font
					(size 1 1)
					(thickness 0.15)
				)
			)
		)
		(property "MPN" "GRM155R61H104KE14D"
			(at 0 0 0)
			(unlocked yes)
			(layer "F.Fab")
			(hide yes)
			(effects
				(font
					(size 1 1)
					(thickness 0.15)
				)
			)
		)
		(property "Val" "100n"
			(at 0 0 0)
			(unlocked yes)
			(layer "F.Fab")
			(hide yes)
			(effects
				(font
					(size 1 1)
					(thickness 0.15)
				)
			)
		)
		(property "License" "Apache-2.0"
			(at 0 0 0)
			(unlocked yes)
			(layer "F.Fab")
			(hide yes)
			(effects
				(font
					(size 1 1)
					(thickness 0.15)
				)
			)
		)
		(property "Author" "Antmicro"
			(at 0 0 0)
			(unlocked yes)
			(layer "F.Fab")
			(hide yes)
			(effects
				(font
					(size 1 1)
					(thickness 0.15)
				)
			)
		)
		(property "Voltage" "50V"
			(at 0 0 0)
			(unlocked yes)
			(layer "F.Fab")
			(hide yes)
			(effects
				(font
					(size 1 1)
					(thickness 0.15)
				)
			)
		)
		(property "Dielectric" "X5R"
			(at 0 0 0)
			(unlocked yes)
			(layer "F.Fab")
			(hide yes)
			(effects
				(font
					(size 1 1)
					(thickness 0.15)
				)
			)
		)
		(sheetname "/Compute module/")
		(sheetfile "compute-module.kicad_sch")
		(attr smd)
		(fp_rect
			(start -0.925 -0.47)
			(end 0.925 0.47)
			(stroke
				(width 0.05)
				(type default)
			)
			(fill no)
			(layer "F.CrtYd")
		)
		(fp_line
			(start -0.494 -0.25)
			(end 0.504 -0.25)
			(stroke
				(width 0.15)
				(type solid)
			)
			(layer "F.Fab")
		)
		(fp_line
			(start -0.494 0.248)
			(end -0.494 -0.25)
			(stroke
				(width 0.15)
				(type solid)
			)
			(layer "F.Fab")
		)
		(fp_line
			(start 0.504 -0.25)
			(end 0.504 0.248)
			(stroke
				(width 0.15)
				(type solid)
			)
			(layer "F.Fab")
		)
		(fp_line
			(start 0.504 0.248)
			(end -0.494 0.248)
			(stroke
				(width 0.15)
				(type solid)
			)
			(layer "F.Fab")
		)
		(fp_text user "License: Apache-2.0"
			(at -0.939 5.799 0)
			(layer "F.Fab")
			(effects
				(font
					(size 0.7 0.7)
					(thickness 0.15)
				)
				(justify left bottom)
			)
		)
		(fp_text user "${REFERENCE}"
			(at -0.939 4.599 0)
			(layer "F.Fab")
			(effects
				(font
					(size 0.7 0.7)
					(thickness 0.15)
				)
				(justify left bottom)
			)
		)
		(fp_text user "Author: Antmicro"
			(at -0.939 3.399 0)
			(layer "F.Fab")
			(effects
				(font
					(size 0.7 0.7)
					(thickness 0.15)
				)
				(justify left bottom)
			)
		)
		(pad "1" smd roundrect
			(at -0.48 0)
			(size 0.59 0.64)
			(layers "F.Cu" "F.Mask" "F.Paste")
			(roundrect_rratio 0.25)
			(net 3 "GND")
			(pintype "passive")
		)
		(pad "2" smd roundrect
			(at 0.48 0)
			(size 0.59 0.64)
			(layers "F.Cu" "F.Mask" "F.Paste")
			(roundrect_rratio 0.25)
			(net 9 "+3V3")
			(pintype "passive")
		)
	)
	(footprint "antmicro-footprints:TP_SMD_0.75mm"
		(layer "F.Cu")
		(at 109.467962 153.5665)
		(property "Reference" "TP214"
			(at -0.617962 -0.5165 180)
			(layer "F.SilkS")
			(effects
				(font
					(size 0.7 0.7)
					(thickness 0.15)
				)
				(justify left bottom)
			)
		)
		(property "Value" "TP_0.75mm_SMD"
			(at 0 1.2 0)
			(layer "F.Fab")
			(effects
				(font
					(size 0.7 0.7)
					(thickness 0.15)
				)
				(justify left bottom)
			)
		)
		(property "MPN" ""
			(at 0 0 0)
			(unlocked yes)
			(layer "F.Fab")
			(hide yes)
			(effects
				(font
					(size 1 1)
					(thickness 0.15)
				)
			)
		)
		(property "Manufacturer" ""
			(at 0 0 0)
			(unlocked yes)
			(layer "F.Fab")
			(hide yes)
			(effects
				(font
					(size 1 1)
					(thickness 0.15)
				)
			)
		)
		(property "Author" "Antmicro"
			(at 0 0 0)
			(unlocked yes)
			(layer "F.Fab")
			(hide yes)
			(effects
				(font
					(size 1 1)
					(thickness 0.15)
				)
			)
		)
		(property "License" "Apache-2.0"
			(at 0 0 0)
			(unlocked yes)
			(layer "F.Fab")
			(hide yes)
			(effects
				(font
					(size 1 1)
					(thickness 0.15)
				)
			)
		)
		(sheetname "/Compute module/")
		(sheetfile "compute-module.kicad_sch")
		(attr exclude_from_pos_files exclude_from_bom)
		(fp_circle
			(center 0 0)
			(end 0.475 0)
			(stroke
				(width 0.05)
				(type default)
			)
			(fill no)
			(layer "F.CrtYd")
		)
		(fp_text user "License: Apache-2.0"
			(at -0.4 5.101 0)
			(layer "F.Fab")
			(effects
				(font
					(size 0.7 0.7)
					(thickness 0.15)
				)
				(justify left bottom)
			)
		)
		(fp_text user "${REFERENCE}"
			(at -0.4 2.7 0)
			(layer "F.Fab")
			(effects
				(font
					(size 0.7 0.7)
					(thickness 0.15)
				)
				(justify left bottom)
			)
		)
		(fp_text user "Author: Antmicro"
			(at -0.4 3.901 0)
			(layer "F.Fab")
			(effects
				(font
					(size 0.7 0.7)
					(thickness 0.15)
				)
				(justify left bottom)
			)
		)
		(pad "1" smd circle
			(at 0 0)
			(size 0.75 0.75)
			(layers "F.Cu" "F.Mask")
			(net 257 "/Compute module/Pf_5V.HPD")
			(pinfunction "1")
			(pintype "passive")
		)
	)
	(footprint "antmicro-footprints:R_0402_1005Metric"
		(layer "F.Cu")
		(at 98.8 118.65 -90)
		(descr "Resistor SMD 0402")
		(tags "resistor SMD 0402")
		(property "Reference" "R903"
			(at 24.0125 -27.805 90)
			(layer "F.SilkS")
			(effects
				(font
					(size 0.7 0.7)
					(thickness 0.15)
				)
				(justify right bottom)
			)
		)
		(property "Value" "R_910k_0402"
			(at -1.011843 1.772047 90)
			(layer "F.Fab")
			(effects
				(font
					(size 0.7 0.7)
					(thickness 0.15)
				)
				(justify right bottom)
			)
		)
		(property "Datasheet" "https://www.bourns.com/docs/product-datasheets/cr.pdf"
			(at 0 0 270)
			(layer "F.Fab")
			(hide yes)
			(effects
				(font
					(size 1.27 1.27)
					(thickness 0.15)
				)
			)
		)
		(property "MPN" "CR0402-FX-9103GLF"
			(at 0 0 270)
			(unlocked yes)
			(layer "F.Fab")
			(hide yes)
			(effects
				(font
					(size 1 1)
					(thickness 0.15)
				)
			)
		)
		(property "Manufacturer" "Bourns"
			(at 0 0 270)
			(unlocked yes)
			(layer "F.Fab")
			(hide yes)
			(effects
				(font
					(size 1 1)
					(thickness 0.15)
				)
			)
		)
		(property "License" "Apache-2.0"
			(at 0 0 270)
			(unlocked yes)
			(layer "F.Fab")
			(hide yes)
			(effects
				(font
					(size 1 1)
					(thickness 0.15)
				)
			)
		)
		(property "Author" "Antmicro"
			(at 0 0 270)
			(unlocked yes)
			(layer "F.Fab")
			(hide yes)
			(effects
				(font
					(size 1 1)
					(thickness 0.15)
				)
			)
		)
		(property "Val" "910k"
			(at 0 0 270)
			(unlocked yes)
			(layer "F.Fab")
			(hide yes)
			(effects
				(font
					(size 1 1)
					(thickness 0.15)
				)
			)
		)
		(property "Tolerance" "1%"
			(at 0 0 270)
			(unlocked yes)
			(layer "F.Fab")
			(hide yes)
			(effects
				(font
					(size 1 1)
					(thickness 0.15)
				)
			)
		)
		(sheetname "/USB/")
		(sheetfile "usb.kicad_sch")
		(attr smd)
		(fp_rect
			(start -0.925 -0.47)
			(end 0.925 0.47)
			(stroke
				(width 0.05)
				(type default)
			)
			(fill no)
			(layer "F.CrtYd")
		)
		(fp_rect
			(start -0.5 -0.25)
			(end 0.5 0.25)
			(stroke
				(width 0.15)
				(type solid)
			)
			(fill no)
			(layer "F.Fab")
		)
		(fp_text user "Author: Antmicro"
			(at -0.95 4.169 270)
			(layer "F.Fab")
			(effects
				(font
					(size 0.7 0.7)
					(thickness 0.15)
				)
				(justify left bottom)
			)
		)
		(fp_text user "${REFERENCE}"
			(at -0.95 3.168 270)
			(layer "F.Fab")
			(effects
				(font
					(size 0.7 0.7)
					(thickness 0.15)
				)
				(justify left bottom)
			)
		)
		(fp_text user "License: Apache-2.0"
			(at -0.95 5.169 270)
			(layer "F.Fab")
			(effects
				(font
					(size 0.7 0.7)
					(thickness 0.15)
				)
				(justify left bottom)
			)
		)
		(pad "1" smd roundrect
			(at -0.48 0 270)
			(size 0.59 0.64)
			(layers "F.Cu" "F.Mask" "F.Paste")
			(roundrect_rratio 0.25)
			(net 24 "/Compute module/USBA_VBUS")
			(pintype "passive")
		)
		(pad "2" smd roundrect
			(at 0.48 0 270)
			(size 0.59 0.64)
			(layers "F.Cu" "F.Mask" "F.Paste")
			(roundrect_rratio 0.25)
			(net 340 "Net-(U906-VBUS_DET)")
			(pintype "passive")
		)
	)
	(footprint "antmicro-footprints:C_0402_1005Metric"
		(layer "F.Cu")
		(at 85.242962 132.5915)
		(descr "Capacitor SMD 0402")
		(tags "capacitor SMD 0402")
		(property "Reference" "C903"
			(at -2.835 -0.845 0)
			(layer "F.SilkS")
			(effects
				(font
					(size 0.7 0.7)
					(thickness 0.15)
				)
				(justify left bottom)
			)
		)
		(property "Value" "C_100n_0402"
			(at -1.022927 2.155213 0)
			(layer "F.Fab")
			(effects
				(font
					(size 0.7 0.7)
					(thickness 0.15)
				)
				(justify left bottom)
			)
		)
		(property "Datasheet" "https://www.murata.com/products/productdetail?partno=GRM155R61H104KE14%23"
			(at 0 0 0)
			(layer "F.Fab")
			(hide yes)
			(effects
				(font
					(size 1.27 1.27)
					(thickness 0.15)
				)
			)
		)
		(property "Manufacturer" "Murata"
			(at 0 0 0)
			(unlocked yes)
			(layer "F.Fab")
			(hide yes)
			(effects
				(font
					(size 1 1)
					(thickness 0.15)
				)
			)
		)
		(property "MPN" "GRM155R61H104KE14D"
			(at 0 0 0)
			(unlocked yes)
			(layer "F.Fab")
			(hide yes)
			(effects
				(font
					(size 1 1)
					(thickness 0.15)
				)
			)
		)
		(property "Val" "100n"
			(at 0 0 0)
			(unlocked yes)
			(layer "F.Fab")
			(hide yes)
			(effects
				(font
					(size 1 1)
					(thickness 0.15)
				)
			)
		)
		(property "License" "Apache-2.0"
			(at 0 0 0)
			(unlocked yes)
			(layer "F.Fab")
			(hide yes)
			(effects
				(font
					(size 1 1)
					(thickness 0.15)
				)
			)
		)
		(property "Author" "Antmicro"
			(at 0 0 0)
			(unlocked yes)
			(layer "F.Fab")
			(hide yes)
			(effects
				(font
					(size 1 1)
					(thickness 0.15)
				)
			)
		)
		(property "Voltage" "50V"
			(at 0 0 0)
			(unlocked yes)
			(layer "F.Fab")
			(hide yes)
			(effects
				(font
					(size 1 1)
					(thickness 0.15)
				)
			)
		)
		(property "Dielectric" "X5R"
			(at 0 0 0)
			(unlocked yes)
			(layer "F.Fab")
			(hide yes)
			(effects
				(font
					(size 1 1)
					(thickness 0.15)
				)
			)
		)
		(sheetname "/USB/")
		(sheetfile "usb.kicad_sch")
		(attr smd)
		(fp_rect
			(start -0.925 -0.47)
			(end 0.925 0.47)
			(stroke
				(width 0.05)
				(type default)
			)
			(fill no)
			(layer "F.CrtYd")
		)
		(fp_line
			(start -0.494 -0.25)
			(end 0.504 -0.25)
			(stroke
				(width 0.15)
				(type solid)
			)
			(layer "F.Fab")
		)
		(fp_line
			(start -0.494 0.248)
			(end -0.494 -0.25)
			(stroke
				(width 0.15)
				(type solid)
			)
			(layer "F.Fab")
		)
		(fp_line
			(start 0.504 -0.25)
			(end 0.504 0.248)
			(stroke
				(width 0.15)
				(type solid)
			)
			(layer "F.Fab")
		)
		(fp_line
			(start 0.504 0.248)
			(end -0.494 0.248)
			(stroke
				(width 0.15)
				(type solid)
			)
			(layer "F.Fab")
		)
		(fp_text user "${REFERENCE}"
			(at -0.939 4.599 0)
			(layer "F.Fab")
			(effects
				(font
					(size 0.7 0.7)
					(thickness 0.15)
				)
				(justify left bottom)
			)
		)
		(fp_text user "Author: Antmicro"
			(at -0.939 3.399 0)
			(layer "F.Fab")
			(effects
				(font
					(size 0.7 0.7)
					(thickness 0.15)
				)
				(justify left bottom)
			)
		)
		(fp_text user "License: Apache-2.0"
			(at -0.939 5.799 0)
			(layer "F.Fab")
			(effects
				(font
					(size 0.7 0.7)
					(thickness 0.15)
				)
				(justify left bottom)
			)
		)
		(pad "1" smd roundrect
			(at -0.48 0)
			(size 0.59 0.64)
			(layers "F.Cu" "F.Mask" "F.Paste")
			(roundrect_rratio 0.25)
			(net 27 "/USB/USB_3V3")
			(pintype "passive")
		)
		(pad "2" smd roundrect
			(at 0.48 0)
			(size 0.59 0.64)
			(layers "F.Cu" "F.Mask" "F.Paste")
			(roundrect_rratio 0.25)
			(net 3 "GND")
			(pintype "passive")
		)
	)
	(footprint "antmicro-footprints:SOT-23-3"
		(layer "F.Cu")
		(at 104.892962 154.792)
		(property "Reference" "Q205"
			(at -2.045 -1.6155 0)
			(layer "F.SilkS")
			(effects
				(font
					(size 0.7 0.7)
					(thickness 0.15)
				)
				(justify left bottom)
			)
		)
		(property "Value" "SSM3J332R"
			(at -1.9 2.7 0)
			(layer "F.Fab")
			(effects
				(font
					(size 0.7 0.7)
					(thickness 0.15)
				)
				(justify left bottom)
			)
		)
		(property "Datasheet" "https://www.mouser.com/datasheet/2/408/SSM3J332R_datasheet_en_20181015-1150575.pdf"
			(at 0 0 0)
			(layer "F.Fab")
			(hide yes)
			(effects
				(font
					(size 1.27 1.27)
					(thickness 0.15)
				)
			)
		)
		(property "MPN" "SSM3J332R,LF"
			(at 0 0 0)
			(unlocked yes)
			(layer "F.Fab")
			(hide yes)
			(effects
				(font
					(size 1 1)
					(thickness 0.15)
				)
			)
		)
		(property "Manufacturer" "Toshiba"
			(at 0 0 0)
			(unlocked yes)
			(layer "F.Fab")
			(hide yes)
			(effects
				(font
					(size 1 1)
					(thickness 0.15)
				)
			)
		)
		(property "Author" "Antmicro"
			(at 0 0 0)
			(unlocked yes)
			(layer "F.Fab")
			(hide yes)
			(effects
				(font
					(size 1 1)
					(thickness 0.15)
				)
			)
		)
		(property "License" "Apache-2.0"
			(at 0 0 0)
			(unlocked yes)
			(layer "F.Fab")
			(hide yes)
			(effects
				(font
					(size 1 1)
					(thickness 0.15)
				)
			)
		)
		(sheetname "/Compute module/")
		(sheetfile "compute-module.kicad_sch")
		(attr smd)
		(fp_line
			(start -1.45 -1.35)
			(end -0.85 -1.35)
			(stroke
				(width 0.15)
				(type solid)
			)
			(layer "F.SilkS")
		)
		(fp_line
			(start -0.85 -1.35)
			(end -0.7 -1.5)
			(stroke
				(width 0.15)
				(type solid)
			)
			(layer "F.SilkS")
		)
		(fp_line
			(start -0.7 1.5)
			(end -0.7 1.35)
			(stroke
				(width 0.15)
				(type solid)
			)
			(layer "F.SilkS")
		)
		(fp_line
			(start 0.7 -1.5)
			(end -0.7 -1.5)
			(stroke
				(width 0.15)
				(type solid)
			)
			(layer "F.SilkS")
		)
		(fp_line
			(start 0.7 -0.4)
			(end 0.7 -1.5)
			(stroke
				(width 0.15)
				(type solid)
			)
			(layer "F.SilkS")
		)
		(fp_line
			(start 0.7 0.4)
			(end 0.7 1.5)
			(stroke
				(width 0.15)
				(type solid)
			)
			(layer "F.SilkS")
		)
		(fp_line
			(start 0.7 1.5)
			(end -0.7 1.5)
			(stroke
				(width 0.15)
				(type solid)
			)
			(layer "F.SilkS")
		)
		(fp_line
			(start -1.75 -0.5)
			(end -1.75 -1.4)
			(stroke
				(width 0.05)
				(type solid)
			)
			(layer "F.CrtYd")
		)
		(fp_line
			(start -1.75 0.5)
			(end -0.85 0.5)
			(stroke
				(width 0.05)
				(type solid)
			)
			(layer "F.CrtYd")
		)
		(fp_line
			(start -1.75 1.4)
			(end -1.75 0.5)
			(stroke
				(width 0.05)
				(type solid)
			)
			(layer "F.CrtYd")
		)
		(fp_line
			(start -0.9 -1.6)
			(end -0.9 -1.4)
			(stroke
				(width 0.05)
				(type solid)
			)
			(layer "F.CrtYd")
		)
		(fp_line
			(start -0.9 -1.6)
			(end 0.825 -1.6)
			(stroke
				(width 0.05)
				(type solid)
			)
			(layer "F.CrtYd")
		)
		(fp_line
			(start -0.9 -1.4)
			(end -1.75 -1.4)
			(stroke
				(width 0.05)
				(type solid)
			)
			(layer "F.CrtYd")
		)
		(fp_line
			(start -0.85 -0.5)
			(end -1.75 -0.5)
			(stroke
				(width 0.05)
				(type solid)
			)
			(layer "F.CrtYd")
		)
		(fp_line
			(start -0.85 0.5)
			(end -0.85 -0.5)
			(stroke
				(width 0.05)
				(type solid)
			)
			(layer "F.CrtYd")
		)
		(fp_line
			(start -0.85 1.4)
			(end -1.75 1.4)
			(stroke
				(width 0.05)
				(type solid)
			)
			(layer "F.CrtYd")
		)
		(fp_line
			(start -0.85 1.65)
			(end -0.85 1.4)
			(stroke
				(width 0.05)
				(type solid)
			)
			(layer "F.CrtYd")
		)
		(fp_line
			(start 0.825 -1.6)
			(end 0.825 -0.45)
			(stroke
				(width 0.05)
				(type solid)
			)
			(layer "F.CrtYd")
		)
		(fp_line
			(start 0.825 -0.45)
			(end 1.75 -0.45)
			(stroke
				(width 0.05)
				(type solid)
			)
			(layer "F.CrtYd")
		)
		(fp_line
			(start 0.85 0.45)
			(end 0.85 1.65)
			(stroke
				(width 0.05)
				(type solid)
			)
			(layer "F.CrtYd")
		)
		(fp_line
			(start 0.85 1.65)
			(end -0.85 1.65)
			(stroke
				(width 0.05)
				(type solid)
			)
			(layer "F.CrtYd")
		)
		(fp_line
			(start 1.75 -0.45)
			(end 1.75 0.45)
			(stroke
				(width 0.05)
				(type solid)
			)
			(layer "F.CrtYd")
		)
		(fp_line
			(start 1.75 0.45)
			(end 0.85 0.45)
			(stroke
				(width 0.05)
				(type solid)
			)
			(layer "F.CrtYd")
		)
		(fp_line
			(start -0.712 -1.325)
			(end -0.712 1.523)
			(stroke
				(width 0.15)
				(type solid)
			)
			(layer "F.Fab")
		)
		(fp_line
			(start -0.712 1.519)
			(end 0.688 1.519)
			(stroke
				(width 0.15)
				(type solid)
			)
			(layer "F.Fab")
		)
		(fp_line
			(start -0.437 -1.526)
			(end -0.712 -1.325)
			(stroke
				(width 0.15)
				(type solid)
			)
			(layer "F.Fab")
		)
		(fp_line
			(start -0.437 -1.526)
			(end 0.688 -1.526)
			(stroke
				(width 0.15)
				(type solid)
			)
			(layer "F.Fab")
		)
		(fp_line
			(start 0.688 1.519)
			(end 0.688 -1.52)
			(stroke
				(width 0.15)
				(type solid)
			)
			(layer "F.Fab")
		)
		(fp_text user "${REFERENCE}"
			(at -1.837 4 0)
			(layer "F.Fab")
			(effects
				(font
					(size 0.7 0.7)
					(thickness 0.15)
				)
				(justify left bottom)
			)
		)
		(fp_text user "License: Apache-2.0"
			(at -1.8 6.8 0)
			(layer "F.Fab")
			(effects
				(font
					(size 0.7 0.7)
					(thickness 0.15)
				)
				(justify left bottom)
			)
		)
		(fp_text user "Author: Antmicro"
			(at -1.837 5.3 0)
			(layer "F.Fab")
			(effects
				(font
					(size 0.7 0.7)
					(thickness 0.15)
				)
				(justify left bottom)
			)
		)
		(pad "1" smd roundrect
			(at -1.1 -0.951)
			(size 1 0.6)
			(layers "F.Cu" "F.Mask" "F.Paste")
			(roundrect_rratio 0.15)
			(net 327 "Net-(Q201-D)")
			(pinfunction "G")
			(pintype "input")
		)
		(pad "2" smd roundrect
			(at -1.1 0.949)
			(size 1 0.6)
			(layers "F.Cu" "F.Mask" "F.Paste")
			(roundrect_rratio 0.15)
			(net 10 "+5V")
			(pinfunction "S")
			(pintype "passive")
		)
		(pad "3" smd roundrect
			(at 1.1 -0.0005)
			(size 1 0.6)
			(layers "F.Cu" "F.Mask" "F.Paste")
			(roundrect_rratio 0.15)
			(net 260 "/Compute module/Pf_5V.CEC")
			(pinfunction "D")
			(pintype "passive")
		)
	)
	(footprint "antmicro-footprints:Nexperia_DFN-10_2.5x1mm_P0.5mm"
		(layer "F.Cu")
		(at 134.067962 147.1665 90)
		(property "Reference" "D808"
			(at -1.298 -1.562 90)
			(layer "F.SilkS")
			(effects
				(font
					(size 0.7 0.7)
					(thickness 0.15)
				)
				(justify left bottom)
			)
		)
		(property "Value" "PUSB3F96X_PASS"
			(at -0.016 1.705 90)
			(layer "F.Fab")
			(effects
				(font
					(size 0.7 0.7)
					(thickness 0.15)
				)
				(justify left bottom)
			)
		)
		(property "Datasheet" "https://mouser.com/datasheet/2/916/PUSB3F96-1600324.pdf"
			(at 0 0 90)
			(layer "F.Fab")
			(hide yes)
			(effects
				(font
					(size 1.27 1.27)
					(thickness 0.15)
				)
			)
		)
		(property "Manufacturer" "Nexperia"
			(at 0 0 90)
			(unlocked yes)
			(layer "F.Fab")
			(hide yes)
			(effects
				(font
					(size 1 1)
					(thickness 0.15)
				)
			)
		)
		(property "MPN" "PUSB3F96X"
			(at 0 0 90)
			(unlocked yes)
			(layer "F.Fab")
			(hide yes)
			(effects
				(font
					(size 1 1)
					(thickness 0.15)
				)
			)
		)
		(property "Author" "Antmicro"
			(at 0 0 90)
			(unlocked yes)
			(layer "F.Fab")
			(hide yes)
			(effects
				(font
					(size 1 1)
					(thickness 0.15)
				)
			)
		)
		(property "License" "Apache-2.0"
			(at 0 0 90)
			(unlocked yes)
			(layer "F.Fab")
			(hide yes)
			(effects
				(font
					(size 1 1)
					(thickness 0.15)
				)
			)
		)
		(sheetname "/Peripherals/")
		(sheetfile "peripherals.kicad_sch")
		(attr smd)
		(fp_line
			(start -1.375 -0.4)
			(end -1.375 0.4)
			(stroke
				(width 0.15)
				(type solid)
			)
			(layer "F.SilkS")
		)
		(fp_line
			(start 1.375 0.4)
			(end 1.375 -0.4)
			(stroke
				(width 0.15)
				(type solid)
			)
			(layer "F.SilkS")
		)
		(fp_circle
			(center -1.4 0.7)
			(end -1.349 0.7)
			(stroke
				(width 0.15)
				(type solid)
			)
			(fill yes)
			(layer "F.SilkS")
		)
		(fp_rect
			(start -1.4 -0.725)
			(end 1.4 0.725)
			(stroke
				(width 0.05)
				(type solid)
			)
			(fill no)
			(layer "F.CrtYd")
		)
		(fp_line
			(start 1.25 -0.5)
			(end -1.25 -0.5)
			(stroke
				(width 0.15)
				(type solid)
			)
			(layer "F.Fab")
		)
		(fp_line
			(start -1.25 -0.5)
			(end -1.25 0.15)
			(stroke
				(width 0.15)
				(type solid)
			)
			(layer "F.Fab")
		)
		(fp_line
			(start -1.25 0.15)
			(end -0.9 0.5)
			(stroke
				(width 0.15)
				(type solid)
			)
			(layer "F.Fab")
		)
		(fp_line
			(start 1.25 0.5)
			(end 1.25 -0.5)
			(stroke
				(width 0.15)
				(type solid)
			)
			(layer "F.Fab")
		)
		(fp_line
			(start -0.9 0.5)
			(end 1.25 0.5)
			(stroke
				(width 0.15)
				(type solid)
			)
			(layer "F.Fab")
		)
		(fp_text user "${REFERENCE}"
			(at -1.367 3.704 90)
			(layer "F.Fab")
			(effects
				(font
					(size 0.7 0.7)
					(thickness 0.15)
				)
				(justify left bottom)
			)
		)
		(fp_text user "Author: Antmicro"
			(at -1.367 4.905 90)
			(layer "F.Fab")
			(effects
				(font
					(size 0.7 0.7)
					(thickness 0.15)
				)
				(justify left bottom)
			)
		)
		(fp_text user "License: Apache-2.0"
			(at -1.367 6.105 90)
			(layer "F.Fab")
			(effects
				(font
					(size 0.7 0.7)
					(thickness 0.15)
				)
				(justify left bottom)
			)
		)
		(pad "1" smd rect
			(at -1 0.3875 90)
			(size 0.2 0.475)
			(layers "F.Cu" "F.Mask" "F.Paste")
			(net 251 "/Compute module/GPIO.AIN1")
			(pinfunction "CH1")
			(pintype "passive")
			(solder_mask_margin 0.05)
		)
		(pad "2" smd rect
			(at -0.5 0.3875 90)
			(size 0.2 0.475)
			(layers "F.Cu" "F.Mask" "F.Paste")
			(net 235 "/Compute module/GPIO.23")
			(pinfunction "CH2")
			(pintype "passive")
			(solder_mask_margin 0.05)
		)
		(pad "3" smd rect
			(at 0 0.3875 90)
			(size 0.2 0.475)
			(layers "F.Cu" "F.Mask" "F.Paste")
			(net 3 "GND")
			(pinfunction "GND")
			(pintype "passive")
			(solder_mask_margin 0.05)
		)
		(pad "4" smd rect
			(at 0.5 0.3875 90)
			(size 0.2 0.475)
			(layers "F.Cu" "F.Mask" "F.Paste")
			(net 233 "/Compute module/GPIO.24")
			(pinfunction "CH3")
			(pintype "passive")
			(solder_mask_margin 0.05)
		)
		(pad "5" smd rect
			(at 1 0.3875 90)
			(size 0.2 0.475)
			(layers "F.Cu" "F.Mask" "F.Paste")
			(net 230 "/Compute module/GPIO.25")
			(pinfunction "CH4")
			(pintype "passive")
			(solder_mask_margin 0.05)
		)
		(pad "6" smd rect
			(at 1 -0.3875 90)
			(size 0.2 0.475)
			(layers "F.Cu" "F.Mask" "F.Paste")
			(net 230 "/Compute module/GPIO.25")
			(pinfunction "CH4")
			(pintype "passive")
			(solder_mask_margin 0.05)
		)
		(pad "7" smd rect
			(at 0.5 -0.3875 90)
			(size 0.2 0.475)
			(layers "F.Cu" "F.Mask" "F.Paste")
			(net 233 "/Compute module/GPIO.24")
			(pinfunction "CH3")
			(pintype "passive")
			(solder_mask_margin 0.05)
		)
		(pad "8" smd rect
			(at 0 -0.3875 90)
			(size 0.2 0.475)
			(layers "F.Cu" "F.Mask" "F.Paste")
			(net 3 "GND")
			(pinfunction "GND")
			(pintype "passive")
			(solder_mask_margin 0.05)
		)
		(pad "9" smd rect
			(at -0.501 -0.3875 90)
			(size 0.2 0.475)
			(layers "F.Cu" "F.Mask" "F.Paste")
			(net 235 "/Compute module/GPIO.23")
			(pinfunction "CH2")
			(pintype "passive")
			(solder_mask_margin 0.05)
		)
		(pad "10" smd rect
			(at -1 -0.3875 90)
			(size 0.2 0.475)
			(layers "F.Cu" "F.Mask" "F.Paste")
			(net 251 "/Compute module/GPIO.AIN1")
			(pinfunction "CH1")
			(pintype "passive")
			(solder_mask_margin 0.05)
		)
	)
	(footprint "antmicro-footprints:QFN-28-1EP_6x6mm_P0.65mm_EP3.7x3.7mm"
		(layer "F.Cu")
		(at 95.217962 152.7915 -90)
		(property "Reference" "U204"
			(at 0.255 -4.44 90)
			(layer "F.SilkS")
			(effects
				(font
					(size 0.7 0.7)
					(thickness 0.15)
				)
				(justify right bottom)
			)
		)
		(property "Value" "MCP23017T-E_QFN"
			(at 0.15 4.95 90)
			(layer "F.Fab")
			(effects
				(font
					(size 0.7 0.7)
					(thickness 0.15)
				)
				(justify right bottom)
			)
		)
		(property "Datasheet" "https://ww1.microchip.com/downloads/aemDocuments/documents/APID/ProductDocuments/DataSheets/MCP23017-Data-Sheet-DS20001952.pdf"
			(at 0 0 270)
			(layer "F.Fab")
			(hide yes)
			(effects
				(font
					(size 1.27 1.27)
					(thickness 0.15)
				)
			)
		)
		(property "Manufacturer" "Microchip Technology"
			(at 0 0 270)
			(unlocked yes)
			(layer "F.Fab")
			(hide yes)
			(effects
				(font
					(size 1 1)
					(thickness 0.15)
				)
			)
		)
		(property "MPN" "MCP23017T-E/ML"
			(at 0 0 270)
			(unlocked yes)
			(layer "F.Fab")
			(hide yes)
			(effects
				(font
					(size 1 1)
					(thickness 0.15)
				)
			)
		)
		(property "Author" "Antmicro"
			(at 0 0 270)
			(unlocked yes)
			(layer "F.Fab")
			(hide yes)
			(effects
				(font
					(size 1 1)
					(thickness 0.15)
				)
			)
		)
		(property "License" "Apache-2.0"
			(at 0 0 270)
			(unlocked yes)
			(layer "F.Fab")
			(hide yes)
			(effects
				(font
					(size 1 1)
					(thickness 0.15)
				)
			)
		)
		(sheetname "/Compute module/")
		(sheetfile "compute-module.kicad_sch")
		(attr smd)
		(fp_line
			(start -3 3)
			(end -2.5 3)
			(stroke
				(width 0.15)
				(type solid)
			)
			(layer "F.SilkS")
		)
		(fp_line
			(start -3 3)
			(end -3 2.5)
			(stroke
				(width 0.15)
				(type solid)
			)
			(layer "F.SilkS")
		)
		(fp_line
			(start 3 3)
			(end 2.5 3)
			(stroke
				(width 0.15)
				(type solid)
			)
			(layer "F.SilkS")
		)
		(fp_line
			(start 3 3)
			(end 3 2.5)
			(stroke
				(width 0.15)
				(type solid)
			)
			(layer "F.SilkS")
		)
		(fp_line
			(start -3 -3)
			(end -3 -2.5)
			(stroke
				(width 0.15)
				(type solid)
			)
			(layer "F.SilkS")
		)
		(fp_line
			(start -3 -3)
			(end -2.5 -3)
			(stroke
				(width 0.15)
				(type solid)
			)
			(layer "F.SilkS")
		)
		(fp_line
			(start 3 -3)
			(end 3 -2.5)
			(stroke
				(width 0.15)
				(type solid)
			)
			(layer "F.SilkS")
		)
		(fp_line
			(start 3 -3)
			(end 2.5 -3)
			(stroke
				(width 0.15)
				(type solid)
			)
			(layer "F.SilkS")
		)
		(fp_circle
			(center -3.3 -2.4)
			(end -3.25 -2.4)
			(stroke
				(width 0.15)
				(type solid)
			)
			(fill yes)
			(layer "F.SilkS")
		)
		(fp_poly
			(pts
				(xy -1.17 -1.17) (xy 1.17 -1.17) (xy 1.17 1.17) (xy -1.17 1.17)
			)
			(stroke
				(width 0.01)
				(type solid)
			)
			(fill yes)
			(layer "F.Paste")
		)
		(fp_rect
			(start -3.5 -3.5)
			(end 3.5 3.5)
			(stroke
				(width 0.05)
				(type solid)
			)
			(fill no)
			(layer "F.CrtYd")
		)
		(fp_line
			(start -3 -1)
			(end -1 -3)
			(stroke
				(width 0.15)
				(type solid)
			)
			(layer "F.Fab")
		)
		(fp_rect
			(start -3 -3)
			(end 3 3)
			(stroke
				(width 0.15)
				(type solid)
			)
			(fill no)
			(layer "F.Fab")
		)
		(fp_text user "Author: Antmicro"
			(at -3.96 7.94 270)
			(layer "F.Fab")
			(effects
				(font
					(size 0.7 0.7)
					(thickness 0.15)
				)
				(justify left bottom)
			)
		)
		(fp_text user "${REFERENCE}"
			(at -3.96 6.74 270)
			(layer "F.Fab")
			(effects
				(font
					(size 0.7 0.7)
					(thickness 0.15)
				)
				(justify left bottom)
			)
		)
		(fp_text user "License: Apache-2.0"
			(at -3.96 9.14 270)
			(layer "F.Fab")
			(effects
				(font
					(size 0.7 0.7)
					(thickness 0.15)
				)
				(justify left bottom)
			)
		)
		(pad "1" smd rect
			(at -2.85 -1.95 270)
			(size 1 0.31)
			(layers "F.Cu" "F.Mask" "F.Paste")
			(net 118 "/Compute module/SDIO.CD")
			(pinfunction "GPB4")
			(pintype "bidirectional")
		)
		(pad "2" smd rect
			(at -2.85 -1.3 270)
			(size 1 0.31)
			(layers "F.Cu" "F.Mask" "F.Paste")
			(net 380 "/Compute module/NVMe_EN")
			(pinfunction "GPB5")
			(pintype "bidirectional")
		)
		(pad "3" smd rect
			(at -2.85 -0.65 270)
			(size 1 0.31)
			(layers "F.Cu" "F.Mask" "F.Paste")
			(net 284 "Net-(U204-GPB6)")
			(pinfunction "GPB6")
			(pintype "bidirectional")
		)
		(pad "4" smd rect
			(at -2.85 0 270)
			(size 1 0.31)
			(layers "F.Cu" "F.Mask" "F.Paste")
			(net 386 "/Compute module/~{POE EN}")
			(pinfunction "GPB7")
			(pintype "output")
		)
		(pad "5" smd rect
			(at -2.85 0.65 270)
			(size 1 0.31)
			(layers "F.Cu" "F.Mask" "F.Paste")
			(net 9 "+3V3")
			(pinfunction "VDD")
			(pintype "power_in")
		)
		(pad "6" smd rect
			(at -2.85 1.3 270)
			(size 1 0.31)
			(layers "F.Cu" "F.Mask" "F.Paste")
			(net 3 "GND")
			(pinfunction "VSS")
			(pintype "power_in")
		)
		(pad "7" smd rect
			(at -2.85 1.95 270)
			(size 1 0.31)
			(layers "F.Cu" "F.Mask" "F.Paste")
			(net 387 "unconnected-(U204-NC-Pad7)")
			(pinfunction "NC")
			(pintype "no_connect")
		)
		(pad "8" smd rect
			(at -1.95 2.85 270)
			(size 0.31 1)
			(layers "F.Cu" "F.Mask" "F.Paste")
			(net 142 "/CSI/I_{2}C1.SCL")
			(pinfunction "SCK")
			(pintype "input")
		)
		(pad "9" smd rect
			(at -1.3 2.85 270)
			(size 0.31 1)
			(layers "F.Cu" "F.Mask" "F.Paste")
			(net 143 "/CSI/I_{2}C1.SDA")
			(pinfunction "SDA")
			(pintype "bidirectional")
		)
		(pad "10" smd rect
			(at -0.65 2.85 270)
			(size 0.31 1)
			(layers "F.Cu" "F.Mask" "F.Paste")
			(net 388 "unconnected-(U204-NC-Pad10)")
			(pinfunction "NC")
			(pintype "no_connect")
		)
		(pad "11" smd rect
			(at 0 2.85 270)
			(size 0.31 1)
			(layers "F.Cu" "F.Mask" "F.Paste")
			(net 349 "Net-(U204-A0)")
			(pinfunction "A0")
			(pintype "input")
		)
		(pad "12" smd rect
			(at 0.65 2.85 270)
			(size 0.31 1)
			(layers "F.Cu" "F.Mask" "F.Paste")
			(net 346 "Net-(U204-A1)")
			(pinfunction "A1")
			(pintype "input")
		)
		(pad "13" smd rect
			(at 1.3 2.85 270)
			(size 0.31 1)
			(layers "F.Cu" "F.Mask" "F.Paste")
			(net 345 "Net-(U204-A2)")
			(pinfunction "A2")
			(pintype "input")
		)
		(pad "14" smd rect
			(at 1.95 2.85 270)
			(size 0.31 1)
			(layers "F.Cu" "F.Mask" "F.Paste")
			(net 348 "Net-(U204-~{RESET})")
			(pinfunction "~{RESET}")
			(pintype "input")
		)
		(pad "15" smd rect
			(at 2.85 1.95 270)
			(size 1 0.31)
			(layers "F.Cu" "F.Mask" "F.Paste")
			(net 389 "unconnected-(U204-INTB-Pad15)")
			(pinfunction "INTB")
			(pintype "output+no_connect")
		)
		(pad "16" smd rect
			(at 2.85 1.3 270)
			(size 1 0.31)
			(layers "F.Cu" "F.Mask" "F.Paste")
			(net 347 "/Compute module/ExpanderINT")
			(pinfunction "INTA")
			(pintype "output")
		)
		(pad "17" smd rect
			(at 2.85 0.65 270)
			(size 1 0.31)
			(layers "F.Cu" "F.Mask" "F.Paste")
			(net 285 "/Compute module/NFC.EN")
			(pinfunction "GPA0")
			(pintype "bidirectional")
		)
		(pad "18" smd rect
			(at 2.85 0 270)
			(size 1 0.31)
			(layers "F.Cu" "F.Mask" "F.Paste")
			(net 286 "/Compute module/NFC.IRQ")
			(pinfunction "GPA1")
			(pintype "bidirectional")
		)
		(pad "19" smd rect
			(at 2.85 -0.65 270)
			(size 1 0.31)
			(layers "F.Cu" "F.Mask" "F.Paste")
			(net 287 "/Compute module/NFC.DWL_REQ")
			(pinfunction "GPA2")
			(pintype "bidirectional")
		)
		(pad "20" smd rect
			(at 2.85 -1.3 270)
			(size 1 0.31)
			(layers "F.Cu" "F.Mask" "F.Paste")
			(net 276 "Net-(U204-GPA3)")
			(pinfunction "GPA3")
			(pintype "bidirectional")
		)
		(pad "21" smd rect
			(at 2.85 -1.95 270)
			(size 1 0.31)
			(layers "F.Cu" "F.Mask" "F.Paste")
			(net 121 "/Compute module/DSICtrl.~{IRQ2}")
			(pinfunction "GPA4")
			(pintype "bidirectional")
		)
		(pad "22" smd rect
			(at 1.95 -2.85 270)
			(size 0.31 1)
			(layers "F.Cu" "F.Mask" "F.Paste")
			(net 120 "/Compute module/DSICtrl.IRQ1")
			(pinfunction "GPA5")
			(pintype "bidirectional")
		)
		(pad "23" smd rect
			(at 1.3 -2.85 270)
			(size 0.31 1)
			(layers "F.Cu" "F.Mask" "F.Paste")
			(net 122 "/Compute module/DSICtrl.EN")
			(pinfunction "GPA6")
			(pintype "bidirectional")
		)
		(pad "24" smd rect
			(at 0.65 -2.85 270)
			(size 0.31 1)
			(layers "F.Cu" "F.Mask" "F.Paste")
			(net 123 "/Compute module/DSICtrl.~{RST}")
			(pinfunction "GPA7")
			(pintype "output")
		)
		(pad "25" smd rect
			(at 0 -2.85 270)
			(size 0.31 1)
			(layers "F.Cu" "F.Mask" "F.Paste")
			(net 125 "/Compute module/DSICtrl.GPIO")
			(pinfunction "GPB0")
			(pintype "bidirectional")
		)
		(pad "26" smd rect
			(at -0.65 -2.85 270)
			(size 0.31 1)
			(layers "F.Cu" "F.Mask" "F.Paste")
			(net 369 "/CSI/CamCtrl.EN")
			(pinfunction "GPB1")
			(pintype "bidirectional")
		)
		(pad "27" smd rect
			(at -1.3 -2.85 270)
			(size 0.31 1)
			(layers "F.Cu" "F.Mask" "F.Paste")
			(net 274 "/CSI/CamCtrl.VSYNC0")
			(pinfunction "GPB2")
			(pintype "bidirectional")
		)
		(pad "28" smd rect
			(at -1.95 -2.85 270)
			(size 0.31 1)
			(layers "F.Cu" "F.Mask" "F.Paste")
			(net 275 "/CSI/CamCtrl.VSYNC1")
			(pinfunction "GPB3")
			(pintype "bidirectional")
		)
		(pad "29" smd rect
			(at 0 0 270)
			(size 3.7 3.7)
			(layers "F.Cu" "F.Mask")
			(net 3 "GND")
			(pinfunction "EP")
			(pintype "power_in")
		)
	)
	(footprint "antmicro-footprints:R_0402_1005Metric"
		(layer "F.Cu")
		(at 131.937962 161.4965 90)
		(descr "Resistor SMD 0402")
		(tags "resistor SMD 0402")
		(property "Reference" "R601"
			(at -1.23 -1.91 90)
			(layer "F.SilkS")
			(effects
				(font
					(size 0.7 0.7)
					(thickness 0.15)
				)
				(justify left bottom)
			)
		)
		(property "Value" "R_100k_0402"
			(at -1.011843 1.772047 90)
			(layer "F.Fab")
			(effects
				(font
					(size 0.7 0.7)
					(thickness 0.15)
				)
				(justify left bottom)
			)
		)
		(property "Datasheet" "https://www.bourns.com/docs/product-datasheets/cr.pdf"
			(at 0 0 90)
			(layer "F.Fab")
			(hide yes)
			(effects
				(font
					(size 1.27 1.27)
					(thickness 0.15)
				)
			)
		)
		(property "Manufacturer" "Bourns"
			(at 0 0 90)
			(unlocked yes)
			(layer "F.Fab")
			(hide yes)
			(effects
				(font
					(size 1 1)
					(thickness 0.15)
				)
			)
		)
		(property "MPN" "CR0402-FX-1003GLF"
			(at 0 0 90)
			(unlocked yes)
			(layer "F.Fab")
			(hide yes)
			(effects
				(font
					(size 1 1)
					(thickness 0.15)
				)
			)
		)
		(property "Val" "100k"
			(at 0 0 90)
			(unlocked yes)
			(layer "F.Fab")
			(hide yes)
			(effects
				(font
					(size 1 1)
					(thickness 0.15)
				)
			)
		)
		(property "License" "Apache-2.0"
			(at 0 0 90)
			(unlocked yes)
			(layer "F.Fab")
			(hide yes)
			(effects
				(font
					(size 1 1)
					(thickness 0.15)
				)
			)
		)
		(property "Author" "Antmicro"
			(at 0 0 90)
			(unlocked yes)
			(layer "F.Fab")
			(hide yes)
			(effects
				(font
					(size 1 1)
					(thickness 0.15)
				)
			)
		)
		(property "Tolerance" "1%"
			(at 0 0 90)
			(unlocked yes)
			(layer "F.Fab")
			(hide yes)
			(effects
				(font
					(size 1 1)
					(thickness 0.15)
				)
			)
		)
		(sheetname "/CSI/")
		(sheetfile "csi.kicad_sch")
		(attr smd)
		(fp_rect
			(start -0.925 -0.47)
			(end 0.925 0.47)
			(stroke
				(width 0.05)
				(type default)
			)
			(fill no)
			(layer "F.CrtYd")
		)
		(fp_rect
			(start -0.5 -0.25)
			(end 0.5 0.25)
			(stroke
				(width 0.15)
				(type solid)
			)
			(fill no)
			(layer "F.Fab")
		)
		(fp_text user "Author: Antmicro"
			(at -0.95 4.169 90)
			(layer "F.Fab")
			(effects
				(font
					(size 0.7 0.7)
					(thickness 0.15)
				)
				(justify left bottom)
			)
		)
		(fp_text user "${REFERENCE}"
			(at -0.95 3.168 90)
			(layer "F.Fab")
			(effects
				(font
					(size 0.7 0.7)
					(thickness 0.15)
				)
				(justify left bottom)
			)
		)
		(fp_text user "License: Apache-2.0"
			(at -0.95 5.169 90)
			(layer "F.Fab")
			(effects
				(font
					(size 0.7 0.7)
					(thickness 0.15)
				)
				(justify left bottom)
			)
		)
		(pad "1" smd roundrect
			(at -0.48 0 90)
			(size 0.59 0.64)
			(layers "F.Cu" "F.Mask" "F.Paste")
			(roundrect_rratio 0.25)
			(net 3 "GND")
			(pintype "passive")
		)
		(pad "2" smd roundrect
			(at 0.48 0 90)
			(size 0.59 0.64)
			(layers "F.Cu" "F.Mask" "F.Paste")
			(roundrect_rratio 0.25)
			(net 369 "/CSI/CamCtrl.EN")
			(pintype "passive")
		)
	)
	(footprint "antmicro-footprints:TP_SMD_0.75mm"
		(layer "F.Cu")
		(at 95.877962 148.7365)
		(property "Reference" "TP211"
			(at 3.847038 2.5885 90)
			(layer "F.SilkS")
			(effects
				(font
					(size 0.7 0.7)
					(thickness 0.15)
				)
				(justify left bottom)
			)
		)
		(property "Value" "TP_0.75mm_SMD"
			(at 0 1.2 0)
			(layer "F.Fab")
			(effects
				(font
					(size 0.7 0.7)
					(thickness 0.15)
				)
				(justify left bottom)
			)
		)
		(property "Author" "Antmicro"
			(at 0 0 0)
			(unlocked yes)
			(layer "F.Fab")
			(hide yes)
			(effects
				(font
					(size 1 1)
					(thickness 0.15)
				)
			)
		)
		(property "License" "Apache-2.0"
			(at 0 0 0)
			(unlocked yes)
			(layer "F.Fab")
			(hide yes)
			(effects
				(font
					(size 1 1)
					(thickness 0.15)
				)
			)
		)
		(property "MPN" ""
			(at 0 0 0)
			(unlocked yes)
			(layer "F.Fab")
			(hide yes)
			(effects
				(font
					(size 1 1)
					(thickness 0.15)
				)
			)
		)
		(property "Manufacturer" ""
			(at 0 0 0)
			(unlocked yes)
			(layer "F.Fab")
			(hide yes)
			(effects
				(font
					(size 1 1)
					(thickness 0.15)
				)
			)
		)
		(sheetname "/Compute module/")
		(sheetfile "compute-module.kicad_sch")
		(attr exclude_from_pos_files exclude_from_bom)
		(fp_circle
			(center 0 0)
			(end 0.475 0)
			(stroke
				(width 0.05)
				(type default)
			)
			(fill no)
			(layer "F.CrtYd")
		)
		(fp_text user "${REFERENCE}"
			(at -0.4 2.7 0)
			(layer "F.Fab")
			(effects
				(font
					(size 0.7 0.7)
					(thickness 0.15)
				)
				(justify left bottom)
			)
		)
		(fp_text user "Author: Antmicro"
			(at -0.4 3.901 0)
			(layer "F.Fab")
			(effects
				(font
					(size 0.7 0.7)
					(thickness 0.15)
				)
				(justify left bottom)
			)
		)
		(fp_text user "License: Apache-2.0"
			(at -0.4 5.101 0)
			(layer "F.Fab")
			(effects
				(font
					(size 0.7 0.7)
					(thickness 0.15)
				)
				(justify left bottom)
			)
		)
		(pad "1" smd circle
			(at 0 0)
			(size 0.75 0.75)
			(layers "F.Cu" "F.Mask")
			(net 284 "Net-(U204-GPB6)")
			(pinfunction "1")
			(pintype "passive")
		)
	)
	(footprint "antmicro-footprints:FB_0402_1005Metric"
		(layer "F.Cu")
		(at 92.817962 131.4665 -90)
		(descr "Ferrite Bead SMD 0402")
		(tags "ferrite bead SMD 0402")
		(property "Reference" "FB902"
			(at -4.59 -0.4 90)
			(layer "F.SilkS")
			(effects
				(font
					(size 0.7 0.7)
					(thickness 0.15)
				)
				(justify right bottom)
			)
		)
		(property "Value" "FB_120Z_1.3A_Murata-BLM15PD_0402"
			(at 0 1.4 90)
			(layer "F.Fab")
			(effects
				(font
					(size 0.7 0.7)
					(thickness 0.15)
				)
				(justify right bottom)
			)
		)
		(property "Datasheet" "https://www.murata.com/en-us/products/productdata/8796740059166/ENFA0018.pdf"
			(at 0 0 270)
			(layer "F.Fab")
			(hide yes)
			(effects
				(font
					(size 1.27 1.27)
					(thickness 0.15)
				)
			)
		)
		(property "MPN" "BLM15PD121SN1D"
			(at 0 0 270)
			(unlocked yes)
			(layer "F.Fab")
			(hide yes)
			(effects
				(font
					(size 1 1)
					(thickness 0.15)
				)
			)
		)
		(property "Manufacturer" "Murata"
			(at 0 0 270)
			(unlocked yes)
			(layer "F.Fab")
			(hide yes)
			(effects
				(font
					(size 1 1)
					(thickness 0.15)
				)
			)
		)
		(property "Author" "Antmicro"
			(at 0 0 270)
			(unlocked yes)
			(layer "F.Fab")
			(hide yes)
			(effects
				(font
					(size 1 1)
					(thickness 0.15)
				)
			)
		)
		(property "License" "Apache-2.0"
			(at 0 0 270)
			(unlocked yes)
			(layer "F.Fab")
			(hide yes)
			(effects
				(font
					(size 1 1)
					(thickness 0.15)
				)
			)
		)
		(property "Val" "120Z/1.3A"
			(at 0 0 270)
			(unlocked yes)
			(layer "F.Fab")
			(hide yes)
			(effects
				(font
					(size 1 1)
					(thickness 0.15)
				)
			)
		)
		(property "Current" ""
			(at 0 0 270)
			(unlocked yes)
			(layer "F.Fab")
			(hide yes)
			(effects
				(font
					(size 1 1)
					(thickness 0.15)
				)
			)
		)
		(sheetname "/USB/")
		(sheetfile "usb.kicad_sch")
		(attr smd)
		(fp_rect
			(start -0.925 -0.47)
			(end 0.925 0.47)
			(stroke
				(width 0.05)
				(type default)
			)
			(fill no)
			(layer "F.CrtYd")
		)
		(fp_rect
			(start -0.5 -0.25)
			(end 0.5 0.25)
			(stroke
				(width 0.15)
				(type solid)
			)
			(fill no)
			(layer "F.Fab")
		)
		(fp_text user "${REFERENCE}"
			(at -0.95 3.168 270)
			(layer "F.Fab")
			(effects
				(font
					(size 0.7 0.7)
					(thickness 0.15)
				)
				(justify left bottom)
			)
		)
		(fp_text user "License: Apache-2.0"
			(at -0.95 5.169 270)
			(layer "F.Fab")
			(effects
				(font
					(size 0.7 0.7)
					(thickness 0.15)
				)
				(justify left bottom)
			)
		)
		(fp_text user "Author: Antmicro"
			(at -0.95 4.169 270)
			(layer "F.Fab")
			(effects
				(font
					(size 0.7 0.7)
					(thickness 0.15)
				)
				(justify left bottom)
			)
		)
		(pad "1" smd roundrect
			(at -0.48 0 270)
			(size 0.59 0.64)
			(layers "F.Cu" "F.Mask" "F.Paste")
			(roundrect_rratio 0.25)
			(net 27 "/USB/USB_3V3")
			(pintype "passive")
		)
		(pad "2" smd roundrect
			(at 0.48 0 270)
			(size 0.59 0.64)
			(layers "F.Cu" "F.Mask" "F.Paste")
			(roundrect_rratio 0.25)
			(net 32 "/USB/VCC_USB")
			(pintype "passive")
		)
	)
	(footprint "antmicro-footprints:C_0402_1005Metric"
		(layer "F.Cu")
		(at 93.117962 144.7165 -90)
		(descr "Capacitor SMD 0402")
		(tags "capacitor SMD 0402")
		(property "Reference" "C925"
			(at -0.8165 -2.25 180)
			(layer "F.SilkS")
			(effects
				(font
					(size 0.7 0.7)
					(thickness 0.15)
				)
				(justify right bottom)
			)
		)
		(property "Value" "C_4u7_0402"
			(at -1.022927 2.155213 90)
			(layer "F.Fab")
			(effects
				(font
					(size 0.7 0.7)
					(thickness 0.15)
				)
				(justify right bottom)
			)
		)
		(property "Datasheet" "https://www.murata.com/products/productdetail?partno=GRM155R61A475MEAA%23"
			(at 0 0 270)
			(layer "F.Fab")
			(hide yes)
			(effects
				(font
					(size 1.27 1.27)
					(thickness 0.15)
				)
			)
		)
		(property "Manufacturer" "Murata"
			(at 0 0 270)
			(unlocked yes)
			(layer "F.Fab")
			(hide yes)
			(effects
				(font
					(size 1 1)
					(thickness 0.15)
				)
			)
		)
		(property "MPN" "GRM155R61A475MEAAD"
			(at 0 0 270)
			(unlocked yes)
			(layer "F.Fab")
			(hide yes)
			(effects
				(font
					(size 1 1)
					(thickness 0.15)
				)
			)
		)
		(property "Val" "4u7"
			(at 0 0 270)
			(unlocked yes)
			(layer "F.Fab")
			(hide yes)
			(effects
				(font
					(size 1 1)
					(thickness 0.15)
				)
			)
		)
		(property "License" "Apache-2.0"
			(at 0 0 270)
			(unlocked yes)
			(layer "F.Fab")
			(hide yes)
			(effects
				(font
					(size 1 1)
					(thickness 0.15)
				)
			)
		)
		(property "Author" "Antmicro"
			(at 0 0 270)
			(unlocked yes)
			(layer "F.Fab")
			(hide yes)
			(effects
				(font
					(size 1 1)
					(thickness 0.15)
				)
			)
		)
		(property "Voltage" ""
			(at 0 0 270)
			(unlocked yes)
			(layer "F.Fab")
			(hide yes)
			(effects
				(font
					(size 1 1)
					(thickness 0.15)
				)
			)
		)
		(property "Dielectric" ""
			(at 0 0 270)
			(unlocked yes)
			(layer "F.Fab")
			(hide yes)
			(effects
				(font
					(size 1 1)
					(thickness 0.15)
				)
			)
		)
		(sheetname "/USB/")
		(sheetfile "usb.kicad_sch")
		(attr smd)
		(fp_rect
			(start -0.925 -0.47)
			(end 0.925 0.47)
			(stroke
				(width 0.05)
				(type default)
			)
			(fill no)
			(layer "F.CrtYd")
		)
		(fp_line
			(start -0.494 0.248)
			(end -0.494 -0.25)
			(stroke
				(width 0.15)
				(type solid)
			)
			(layer "F.Fab")
		)
		(fp_line
			(start 0.504 0.248)
			(end -0.494 0.248)
			(stroke
				(width 0.15)
				(type solid)
			)
			(layer "F.Fab")
		)
		(fp_line
			(start -0.494 -0.25)
			(end 0.504 -0.25)
			(stroke
				(width 0.15)
				(type solid)
			)
			(layer "F.Fab")
		)
		(fp_line
			(start 0.504 -0.25)
			(end 0.504 0.248)
			(stroke
				(width 0.15)
				(type solid)
			)
			(layer "F.Fab")
		)
		(fp_text user "License: Apache-2.0"
			(at -0.939 5.799 270)
			(layer "F.Fab")
			(effects
				(font
					(size 0.7 0.7)
					(thickness 0.15)
				)
				(justify left bottom)
			)
		)
		(fp_text user "${REFERENCE}"
			(at -0.939 4.599 270)
			(layer "F.Fab")
			(effects
				(font
					(size 0.7 0.7)
					(thickness 0.15)
				)
				(justify left bottom)
			)
		)
		(fp_text user "Author: Antmicro"
			(at -0.939 3.399 270)
			(layer "F.Fab")
			(effects
				(font
					(size 0.7 0.7)
					(thickness 0.15)
				)
				(justify left bottom)
			)
		)
		(pad "1" smd roundrect
			(at -0.48 0 270)
			(size 0.59 0.64)
			(layers "F.Cu" "F.Mask" "F.Paste")
			(roundrect_rratio 0.25)
			(net 30 "/USB/USB_1V2")
			(pintype "passive")
		)
		(pad "2" smd roundrect
			(at 0.48 0 270)
			(size 0.59 0.64)
			(layers "F.Cu" "F.Mask" "F.Paste")
			(roundrect_rratio 0.25)
			(net 3 "GND")
			(pintype "passive")
		)
	)
	(footprint "antmicro-footprints:UQFN-12_2x1.7mm_P0.4mm_Texas_RUT"
		(layer "F.Cu")
		(at 85.367962 152.2465 90)
		(descr "Texas_R_PUQFN-N12")
		(tags "Texas_R_PUQFN-N12")
		(property "Reference" "U201"
			(at -1.92 -1.35 180)
			(layer "F.SilkS")
			(effects
				(font
					(size 0.7 0.7)
					(thickness 0.15)
				)
				(justify left bottom)
			)
		)
		(property "Value" "TXB0104_UQFN"
			(at 0 2.35 90)
			(layer "F.Fab")
			(effects
				(font
					(size 0.7 0.7)
					(thickness 0.15)
				)
				(justify left bottom)
			)
		)
		(property "Datasheet" "http://www.ti.com/lit/ds/symlink/txb0104.pdf"
			(at 0 0 90)
			(layer "F.Fab")
			(hide yes)
			(effects
				(font
					(size 1.27 1.27)
					(thickness 0.15)
				)
			)
		)
		(property "Manufacturer" "Texas Instruments"
			(at 0 0 90)
			(unlocked yes)
			(layer "F.Fab")
			(hide yes)
			(effects
				(font
					(size 1 1)
					(thickness 0.15)
				)
			)
		)
		(property "MPN" "TXB0104RUTR"
			(at 0 0 90)
			(unlocked yes)
			(layer "F.Fab")
			(hide yes)
			(effects
				(font
					(size 1 1)
					(thickness 0.15)
				)
			)
		)
		(property "Author" "Antmicro"
			(at 0 0 90)
			(unlocked yes)
			(layer "F.Fab")
			(hide yes)
			(effects
				(font
					(size 1 1)
					(thickness 0.15)
				)
			)
		)
		(property "License" "Apache-2.0"
			(at 0 0 90)
			(unlocked yes)
			(layer "F.Fab")
			(hide yes)
			(effects
				(font
					(size 1 1)
					(thickness 0.15)
				)
			)
		)
		(property ki_fp_filters "Texas*R*PUQFN*N12*")
		(sheetname "/Compute module/")
		(sheetfile "compute-module.kicad_sch")
		(attr smd)
		(fp_line
			(start 0.597 -1.301)
			(end -0.55 -1.301)
			(stroke
				(width 0.15)
				(type solid)
			)
			(layer "F.SilkS")
		)
		(fp_line
			(start 0.497 1.3)
			(end -0.5 1.3)
			(stroke
				(width 0.15)
				(type solid)
			)
			(layer "F.SilkS")
		)
		(fp_circle
			(center -0.85 -1.2)
			(end -0.8 -1.2)
			(stroke
				(width 0.15)
				(type solid)
			)
			(fill yes)
			(layer "F.SilkS")
		)
		(fp_rect
			(start -1.1 -1.3)
			(end 1.1 1.3)
			(stroke
				(width 0.05)
				(type solid)
			)
			(fill no)
			(layer "F.CrtYd")
		)
		(fp_line
			(start 0.847 -1)
			(end 0.847 0.997)
			(stroke
				(width 0.15)
				(type solid)
			)
			(layer "F.Fab")
		)
		(fp_line
			(start -0.5 -1)
			(end 0.847 -1)
			(stroke
				(width 0.15)
				(type solid)
			)
			(layer "F.Fab")
		)
		(fp_line
			(start -0.5 -1)
			(end -0.85 -0.5)
			(stroke
				(width 0.15)
				(type solid)
			)
			(layer "F.Fab")
		)
		(fp_line
			(start 0.847 0.997)
			(end -0.85 0.997)
			(stroke
				(width 0.15)
				(type solid)
			)
			(layer "F.Fab")
		)
		(fp_line
			(start -0.85 0.997)
			(end -0.85 -0.5)
			(stroke
				(width 0.15)
				(type solid)
			)
			(layer "F.Fab")
		)
		(fp_text user "License: Apache-2.0"
			(at -1.1 6.75 90)
			(layer "F.Fab")
			(effects
				(font
					(size 0.7 0.7)
					(thickness 0.15)
				)
				(justify left bottom)
			)
		)
		(fp_text user "${REFERENCE}"
			(at -1.1 5.55 90)
			(layer "F.Fab")
			(effects
				(font
					(size 0.7 0.7)
					(thickness 0.15)
				)
				(justify left bottom)
			)
		)
		(fp_text user "Author: Antmicro"
			(at -1.1 4.35 90)
			(layer "F.Fab")
			(effects
				(font
					(size 0.7 0.7)
					(thickness 0.15)
				)
				(justify left bottom)
			)
		)
		(pad "1" smd rect
			(at -0.653 -0.803)
			(size 0.2 0.6)
			(layers "F.Cu" "F.Mask" "F.Paste")
			(net 18 "V_{IO}")
			(pinfunction "VCCA")
			(pintype "power_in")
		)
		(pad "1" smd rect
			(at -0.425 -0.975 90)
			(size 0.15 0.25)
			(layers "F.Cu" "F.Mask" "F.Paste")
			(net 18 "V_{IO}")
			(pinfunction "VCCA")
			(pintype "power_in")
		)
		(pad "2" smd rect
			(at -0.653 -0.403)
			(size 0.2 0.6)
			(layers "F.Cu" "F.Mask" "F.Paste")
			(net 225 "/Compute module/GPIO.5{slash}RXD3")
			(pinfunction "A1")
			(pintype "tri_state")
		)
		(pad "3" smd rect
			(at -0.653 0)
			(size 0.2 0.6)
			(layers "F.Cu" "F.Mask" "F.Paste")
			(net 240 "/Compute module/GPIO.4{slash}TXD3")
			(pinfunction "A2")
			(pintype "tri_state")
		)
		(pad "4" smd rect
			(at -0.653 0.4)
			(size 0.2 0.6)
			(layers "F.Cu" "F.Mask" "F.Paste")
			(net 229 "/Compute module/GPIO.9{slash}RXD4")
			(pinfunction "A3")
			(pintype "tri_state")
		)
		(pad "5" smd rect
			(at -0.653 0.8)
			(size 0.2 0.6)
			(layers "F.Cu" "F.Mask" "F.Paste")
			(net 228 "/Compute module/GPIO.8{slash}TXD4")
			(pinfunction "A4")
			(pintype "tri_state")
		)
		(pad "6" smd rect
			(at 0 0.8)
			(size 0.6 0.2)
			(layers "F.Cu" "F.Mask" "F.Paste")
			(net 3 "GND")
			(pinfunction "GND")
			(pintype "power_in")
		)
		(pad "7" smd rect
			(at 0.65 0.8)
			(size 0.2 0.6)
			(layers "F.Cu" "F.Mask" "F.Paste")
			(net 188 "/Compute module/UART.2.TX")
			(pinfunction "B4")
			(pintype "tri_state")
		)
		(pad "8" smd rect
			(at 0.65 0.4)
			(size 0.2 0.6)
			(layers "F.Cu" "F.Mask" "F.Paste")
			(net 189 "/Compute module/UART.2.RX")
			(pinfunction "B3")
			(pintype "tri_state")
		)
		(pad "9" smd rect
			(at 0.65 0)
			(size 0.2 0.6)
			(layers "F.Cu" "F.Mask" "F.Paste")
			(net 190 "/Compute module/UART.3.TX")
			(pinfunction "B2")
			(pintype "tri_state")
		)
		(pad "10" smd rect
			(at 0.65 -0.403)
			(size 0.2 0.6)
			(layers "F.Cu" "F.Mask" "F.Paste")
			(net 191 "/Compute module/UART.3.RX")
			(pinfunction "B1")
			(pintype "tri_state")
		)
		(pad "11" smd rect
			(at 0.65 -0.803)
			(size 0.2 0.6)
			(layers "F.Cu" "F.Mask" "F.Paste")
			(net 9 "+3V3")
			(pinfunction "VCCB")
			(pintype "power_in")
		)
		(pad "12" smd rect
			(at 0 -0.803)
			(size 0.6 0.2)
			(layers "F.Cu" "F.Mask" "F.Paste")
			(net 18 "V_{IO}")
			(pinfunction "OE")
			(pintype "input")
		)
	)
	(footprint "antmicro-footprints:R_0402_1005Metric"
		(layer "F.Cu")
		(at 104.272962 128.3865)
		(descr "Resistor SMD 0402")
		(tags "resistor SMD 0402")
		(property "Reference" "R925"
			(at 0.97 0.38 0)
			(layer "F.SilkS")
			(effects
				(font
					(size 0.7 0.7)
					(thickness 0.15)
				)
				(justify left bottom)
			)
		)
		(property "Value" "R_100k_0402"
			(at -1.011843 1.772047 0)
			(layer "F.Fab")
			(effects
				(font
					(size 0.7 0.7)
					(thickness 0.15)
				)
				(justify left bottom)
			)
		)
		(property "Datasheet" "https://www.bourns.com/docs/product-datasheets/cr.pdf"
			(at 0 0 0)
			(layer "F.Fab")
			(hide yes)
			(effects
				(font
					(size 1.27 1.27)
					(thickness 0.15)
				)
			)
		)
		(property "Manufacturer" "Bourns"
			(at 0 0 0)
			(unlocked yes)
			(layer "F.Fab")
			(hide yes)
			(effects
				(font
					(size 1 1)
					(thickness 0.15)
				)
			)
		)
		(property "MPN" "CR0402-FX-1003GLF"
			(at 0 0 0)
			(unlocked yes)
			(layer "F.Fab")
			(hide yes)
			(effects
				(font
					(size 1 1)
					(thickness 0.15)
				)
			)
		)
		(property "Val" "100k"
			(at 0 0 0)
			(unlocked yes)
			(layer "F.Fab")
			(hide yes)
			(effects
				(font
					(size 1 1)
					(thickness 0.15)
				)
			)
		)
		(property "License" "Apache-2.0"
			(at 0 0 0)
			(unlocked yes)
			(layer "F.Fab")
			(hide yes)
			(effects
				(font
					(size 1 1)
					(thickness 0.15)
				)
			)
		)
		(property "Author" "Antmicro"
			(at 0 0 0)
			(unlocked yes)
			(layer "F.Fab")
			(hide yes)
			(effects
				(font
					(size 1 1)
					(thickness 0.15)
				)
			)
		)
		(property "Tolerance" "1%"
			(at 0 0 0)
			(unlocked yes)
			(layer "F.Fab")
			(hide yes)
			(effects
				(font
					(size 1 1)
					(thickness 0.15)
				)
			)
		)
		(sheetname "/USB/")
		(sheetfile "usb.kicad_sch")
		(attr smd)
		(fp_rect
			(start -0.925 -0.47)
			(end 0.925 0.47)
			(stroke
				(width 0.05)
				(type default)
			)
			(fill no)
			(layer "F.CrtYd")
		)
		(fp_rect
			(start -0.5 -0.25)
			(end 0.5 0.25)
			(stroke
				(width 0.15)
				(type solid)
			)
			(fill no)
			(layer "F.Fab")
		)
		(fp_text user "${REFERENCE}"
			(at -0.95 3.168 0)
			(layer "F.Fab")
			(effects
				(font
					(size 0.7 0.7)
					(thickness 0.15)
				)
				(justify left bottom)
			)
		)
		(fp_text user "License: Apache-2.0"
			(at -0.95 5.169 0)
			(layer "F.Fab")
			(effects
				(font
					(size 0.7 0.7)
					(thickness 0.15)
				)
				(justify left bottom)
			)
		)
		(fp_text user "Author: Antmicro"
			(at -0.95 4.169 0)
			(layer "F.Fab")
			(effects
				(font
					(size 0.7 0.7)
					(thickness 0.15)
				)
				(justify left bottom)
			)
		)
		(pad "1" smd roundrect
			(at -0.48 0)
			(size 0.59 0.64)
			(layers "F.Cu" "F.Mask" "F.Paste")
			(roundrect_rratio 0.25)
			(net 28 "/USB/+5V_{CAP}")
			(pintype "passive")
		)
		(pad "2" smd roundrect
			(at 0.48 0)
			(size 0.59 0.64)
			(layers "F.Cu" "F.Mask" "F.Paste")
			(roundrect_rratio 0.25)
			(net 3 "GND")
			(pintype "passive")
		)
	)
	(footprint "antmicro-footprints:USB-C_Receptacle_GCT_USB4105-GF-A"
		(layer "F.Cu")
		(at 93.017962 115.6165 180)
		(property "Reference" "J901"
			(at -7.64 3.77 90)
			(layer "F.SilkS")
			(effects
				(font
					(size 0.7 0.7)
					(thickness 0.15)
				)
				(justify right bottom)
			)
		)
		(property "Value" "USB-C_GCT_USB4105-GF-A"
			(at 0 5 0)
			(layer "F.Fab")
			(effects
				(font
					(size 0.7 0.7)
					(thickness 0.15)
				)
				(justify right bottom)
			)
		)
		(property "Datasheet" "https://gct.co/files/drawings/usb4105.pdf"
			(at 0 0 180)
			(layer "F.Fab")
			(hide yes)
			(effects
				(font
					(size 1.27 1.27)
					(thickness 0.15)
				)
			)
		)
		(property "Manufacturer" "GCT"
			(at 0 0 180)
			(unlocked yes)
			(layer "F.Fab")
			(hide yes)
			(effects
				(font
					(size 1 1)
					(thickness 0.15)
				)
			)
		)
		(property "MPN" "USB4105-GF-A"
			(at 0 0 180)
			(unlocked yes)
			(layer "F.Fab")
			(hide yes)
			(effects
				(font
					(size 1 1)
					(thickness 0.15)
				)
			)
		)
		(property "Author" "Antmicro"
			(at 0 0 180)
			(unlocked yes)
			(layer "F.Fab")
			(hide yes)
			(effects
				(font
					(size 1 1)
					(thickness 0.15)
				)
			)
		)
		(property "License" "Apache-2.0"
			(at 0 0 180)
			(unlocked yes)
			(layer "F.Fab")
			(hide yes)
			(effects
				(font
					(size 1 1)
					(thickness 0.15)
				)
			)
		)
		(sheetname "/USB/")
		(sheetfile "usb.kicad_sch")
		(attr smd)
		(fp_line
			(start 4.788 3.854)
			(end 4.788 2.575)
			(stroke
				(width 0.15)
				(type solid)
			)
			(layer "F.SilkS")
		)
		(fp_line
			(start 4.788 -1.395)
			(end 4.788 -0.145)
			(stroke
				(width 0.15)
				(type solid)
			)
			(layer "F.SilkS")
		)
		(fp_line
			(start -4.79 3.854)
			(end 4.788 3.854)
			(stroke
				(width 0.15)
				(type solid)
			)
			(layer "F.SilkS")
		)
		(fp_line
			(start -4.79 2.575)
			(end -4.79 3.854)
			(stroke
				(width 0.15)
				(type solid)
			)
			(layer "F.SilkS")
		)
		(fp_line
			(start -4.79 -1.395)
			(end -4.79 -0.145)
			(stroke
				(width 0.15)
				(type solid)
			)
			(layer "F.SilkS")
		)
		(fp_circle
			(center -3.8 -4.27071)
			(end -3.75 -4.22071)
			(stroke
				(width 0.15)
				(type solid)
			)
			(fill yes)
			(layer "F.SilkS")
		)
		(fp_rect
			(start -5.1 -4.4)
			(end 5.1 3.9)
			(stroke
				(width 0.05)
				(type solid)
			)
			(fill no)
			(layer "F.CrtYd")
		)
		(fp_line
			(start 4.788 3.854)
			(end -4.79 3.854)
			(stroke
				(width 0.15)
				(type solid)
			)
			(layer "F.Fab")
		)
		(fp_line
			(start 4.788 -3.676)
			(end 4.788 3.854)
			(stroke
				(width 0.15)
				(type solid)
			)
			(layer "F.Fab")
		)
		(fp_line
			(start -4.702 3.854)
			(end 4.788 3.854)
			(stroke
				(width 0.15)
				(type solid)
			)
			(layer "F.Fab")
		)
		(fp_line
			(start -4.79 3.854)
			(end -4.79 -3.676)
			(stroke
				(width 0.15)
				(type solid)
			)
			(layer "F.Fab")
		)
		(fp_line
			(start -4.79 -3.676)
			(end 4.788 -3.676)
			(stroke
				(width 0.15)
				(type solid)
			)
			(layer "F.Fab")
		)
		(fp_text user "${REFERENCE}"
			(at -4.79 6.853 180)
			(layer "F.Fab")
			(effects
				(font
					(size 0.7 0.7)
					(thickness 0.15)
				)
				(justify left bottom)
			)
		)
		(fp_text user "PCB-EDGE"
			(at -4.79 5.853 180)
			(layer "F.Fab")
			(effects
				(font
					(size 0.7 0.7)
					(thickness 0.15)
				)
				(justify left bottom)
			)
		)
		(fp_text user "License: Apache-2.0"
			(at -4.79 8.855 180)
			(layer "F.Fab")
			(effects
				(font
					(size 0.7 0.7)
					(thickness 0.15)
				)
				(justify left bottom)
			)
		)
		(fp_text user "Author: Antmicro"
			(at -4.79 7.853 180)
			(layer "F.Fab")
			(effects
				(font
					(size 0.7 0.7)
					(thickness 0.15)
				)
				(justify left bottom)
			)
		)
		(pad "" np_thru_hole circle
			(at -2.891 -2.426 180)
			(size 0.65 0.65)
			(drill 0.65)
			(layers "*.Cu" "*.Mask")
		)
		(pad "" np_thru_hole circle
			(at 2.89 -2.426 180)
			(size 0.65 0.65)
			(drill 0.65)
			(layers "*.Cu" "*.Mask")
		)
		(pad "A1" smd roundrect
			(at -3.202 -3.5 180)
			(size 0.6 1.15)
			(layers "F.Cu" "F.Mask" "F.Paste")
			(roundrect_rratio 0.25)
			(net 3 "GND")
			(pinfunction "GND")
			(pintype "power_in")
		)
		(pad "A4" smd roundrect
			(at -2.4 -3.5 180)
			(size 0.6 1.15)
			(layers "F.Cu" "F.Mask" "F.Paste")
			(roundrect_rratio 0.25)
			(net 24 "/Compute module/USBA_VBUS")
			(pinfunction "VBUS")
			(pintype "power_in")
		)
		(pad "A5" smd roundrect
			(at -1.25 -3.5 180)
			(size 0.3 1.15)
			(layers "F.Cu" "F.Mask" "F.Paste")
			(roundrect_rratio 0.25)
			(net 203 "/USB/USBA_CC1")
			(pinfunction "CC_{1}")
			(pintype "bidirectional")
		)
		(pad "A6" smd roundrect
			(at -0.25 -3.5 180)
			(size 0.3 1.15)
			(layers "F.Cu" "F.Mask" "F.Paste")
			(roundrect_rratio 0.25)
			(net 205 "/USB/AD_P")
			(pinfunction "D_{A}+")
			(pintype "bidirectional")
		)
		(pad "A7" smd roundrect
			(at 0.248 -3.5 180)
			(size 0.3 1.15)
			(layers "F.Cu" "F.Mask" "F.Paste")
			(roundrect_rratio 0.25)
			(net 206 "/USB/AD_N")
			(pinfunction "D_{A}-")
			(pintype "bidirectional")
		)
		(pad "A8" smd roundrect
			(at 1.249 -3.5 180)
			(size 0.3 1.15)
			(layers "F.Cu" "F.Mask" "F.Paste")
			(roundrect_rratio 0.25)
			(net 322 "unconnected-(J901-SBU_{1}-PadA8)")
			(pinfunction "SBU_{1}")
			(pintype "bidirectional+no_connect")
		)
		(pad "A9" smd roundrect
			(at 2.398 -3.5 180)
			(size 0.6 1.15)
			(layers "F.Cu" "F.Mask" "F.Paste")
			(roundrect_rratio 0.25)
			(net 24 "/Compute module/USBA_VBUS")
			(pinfunction "VBUS")
			(pintype "passive")
		)
		(pad "A12" smd roundrect
			(at 3.2 -3.5 180)
			(size 0.6 1.15)
			(layers "F.Cu" "F.Mask" "F.Paste")
			(roundrect_rratio 0.25)
			(net 3 "GND")
			(pinfunction "GND")
			(pintype "passive")
		)
		(pad "B1" smd roundrect
			(at 3.2 -3.5 180)
			(size 0.6 1.15)
			(layers "F.Cu" "F.Mask" "F.Paste")
			(roundrect_rratio 0.25)
			(net 3 "GND")
			(pinfunction "GND")
			(pintype "passive")
		)
		(pad "B4" smd roundrect
			(at 2.398 -3.5 180)
			(size 0.6 1.15)
			(layers "F.Cu" "F.Mask" "F.Paste")
			(roundrect_rratio 0.25)
			(net 24 "/Compute module/USBA_VBUS")
			(pinfunction "VBUS")
			(pintype "passive")
		)
		(pad "B5" smd roundrect
			(at 1.749 -3.5 180)
			(size 0.3 1.15)
			(layers "F.Cu" "F.Mask" "F.Paste")
			(roundrect_rratio 0.25)
			(net 204 "/USB/USBA_CC2")
			(pinfunction "CC_{2}")
			(pintype "bidirectional")
		)
		(pad "B6" smd roundrect
			(at 0.748 -3.5 180)
			(size 0.3 1.15)
			(layers "F.Cu" "F.Mask" "F.Paste")
			(roundrect_rratio 0.25)
			(net 205 "/USB/AD_P")
			(pinfunction "D_{B}+")
			(pintype "bidirectional")
		)
		(pad "B7" smd roundrect
			(at -0.75 -3.5 180)
			(size 0.3 1.15)
			(layers "F.Cu" "F.Mask" "F.Paste")
			(roundrect_rratio 0.25)
			(net 206 "/USB/AD_N")
			(pinfunction "D_{B}-")
			(pintype "bidirectional")
		)
		(pad "B8" smd roundrect
			(at -1.75 -3.5 180)
			(size 0.3 1.15)
			(layers "F.Cu" "F.Mask" "F.Paste")
			(roundrect_rratio 0.25)
			(net 321 "unconnected-(J901-SBU_{2}-PadB8)")
			(pinfunction "SBU_{2}")
			(pintype "bidirectional+no_connect")
		)
		(pad "B9" smd roundrect
			(at -2.4 -3.5 180)
			(size 0.6 1.15)
			(layers "F.Cu" "F.Mask" "F.Paste")
			(roundrect_rratio 0.25)
			(net 24 "/Compute module/USBA_VBUS")
			(pinfunction "VBUS")
			(pintype "passive")
		)
		(pad "B12" smd roundrect
			(at -3.202 -3.5 180)
			(size 0.6 1.15)
			(layers "F.Cu" "F.Mask" "F.Paste")
			(roundrect_rratio 0.25)
			(net 3 "GND")
			(pinfunction "GND")
			(pintype "passive")
		)
		(pad "SH" thru_hole oval
			(at -4.321 -2.926 180)
			(size 1.05 2.1)
			(drill oval 0.6 1.7)
			(layers "*.Cu" "*.Mask")
			(remove_unused_layers no)
			(net 3 "GND")
			(pinfunction "SH")
			(pintype "passive")
		)
		(pad "SH" thru_hole oval
			(at -4.321 1.255 180)
			(size 1 2)
			(drill oval 0.6 1.4)
			(layers "*.Cu" "*.Mask")
			(remove_unused_layers no)
			(net 3 "GND")
			(pinfunction "SH")
			(pintype "passive")
		)
		(pad "SH" thru_hole oval
			(at 4.32 -2.926 180)
			(size 1.05 2.1)
			(drill oval 0.6 1.7)
			(layers "*.Cu" "*.Mask")
			(remove_unused_layers no)
			(net 3 "GND")
			(pinfunction "SH")
			(pintype "passive")
		)
		(pad "SH" thru_hole oval
			(at 4.32 1.255 180)
			(size 1 2)
			(drill oval 0.6 1.4)
			(layers "*.Cu" "*.Mask")
			(remove_unused_layers no)
			(net 3 "GND")
			(pinfunction "SH")
			(pintype "passive")
		)
	)
	(footprint "antmicro-footprints:C_0402_1005Metric"
		(layer "F.Cu")
		(at 71.317962 167.0565 -90)
		(descr "Capacitor SMD 0402")
		(tags "capacitor SMD 0402")
		(property "Reference" "C802"
			(at -1.7065 0.517962 90)
			(layer "F.SilkS")
			(effects
				(font
					(size 0.7 0.7)
					(thickness 0.15)
				)
				(justify right bottom)
			)
		)
		(property "Value" "C_1u_0402"
			(at -1.022927 2.155213 90)
			(layer "F.Fab")
			(effects
				(font
					(size 0.7 0.7)
					(thickness 0.15)
				)
				(justify right bottom)
			)
		)
		(property "Datasheet" "https://product.tdk.com/en/search/capacitor/ceramic/mlcc/info?part_no=C1005X6S1A105K050BC"
			(at 0 0 270)
			(layer "F.Fab")
			(hide yes)
			(effects
				(font
					(size 1.27 1.27)
					(thickness 0.15)
				)
			)
		)
		(property "MPN" "C1005X6S1A105K050BC"
			(at 0 0 270)
			(unlocked yes)
			(layer "F.Fab")
			(hide yes)
			(effects
				(font
					(size 1 1)
					(thickness 0.15)
				)
			)
		)
		(property "Manufacturer" "TDK"
			(at 0 0 270)
			(unlocked yes)
			(layer "F.Fab")
			(hide yes)
			(effects
				(font
					(size 1 1)
					(thickness 0.15)
				)
			)
		)
		(property "License" "Apache-2.0"
			(at 0 0 270)
			(unlocked yes)
			(layer "F.Fab")
			(hide yes)
			(effects
				(font
					(size 1 1)
					(thickness 0.15)
				)
			)
		)
		(property "Author" "Antmicro"
			(at 0 0 270)
			(unlocked yes)
			(layer "F.Fab")
			(hide yes)
			(effects
				(font
					(size 1 1)
					(thickness 0.15)
				)
			)
		)
		(property "Val" "1u"
			(at 0 0 270)
			(unlocked yes)
			(layer "F.Fab")
			(hide yes)
			(effects
				(font
					(size 1 1)
					(thickness 0.15)
				)
			)
		)
		(property "Voltage" ""
			(at 0 0 270)
			(unlocked yes)
			(layer "F.Fab")
			(hide yes)
			(effects
				(font
					(size 1 1)
					(thickness 0.15)
				)
			)
		)
		(property "Dielectric" ""
			(at 0 0 270)
			(unlocked yes)
			(layer "F.Fab")
			(hide yes)
			(effects
				(font
					(size 1 1)
					(thickness 0.15)
				)
			)
		)
		(sheetname "/Peripherals/")
		(sheetfile "peripherals.kicad_sch")
		(attr smd)
		(fp_rect
			(start -0.925 -0.47)
			(end 0.925 0.47)
			(stroke
				(width 0.05)
				(type default)
			)
			(fill no)
			(layer "F.CrtYd")
		)
		(fp_line
			(start -0.494 0.248)
			(end -0.494 -0.25)
			(stroke
				(width 0.15)
				(type solid)
			)
			(layer "F.Fab")
		)
		(fp_line
			(start 0.504 0.248)
			(end -0.494 0.248)
			(stroke
				(width 0.15)
				(type solid)
			)
			(layer "F.Fab")
		)
		(fp_line
			(start -0.494 -0.25)
			(end 0.504 -0.25)
			(stroke
				(width 0.15)
				(type solid)
			)
			(layer "F.Fab")
		)
		(fp_line
			(start 0.504 -0.25)
			(end 0.504 0.248)
			(stroke
				(width 0.15)
				(type solid)
			)
			(layer "F.Fab")
		)
		(fp_text user "Author: Antmicro"
			(at -0.939 3.399 270)
			(layer "F.Fab")
			(effects
				(font
					(size 0.7 0.7)
					(thickness 0.15)
				)
				(justify left bottom)
			)
		)
		(fp_text user "${REFERENCE}"
			(at -0.939 4.599 270)
			(layer "F.Fab")
			(effects
				(font
					(size 0.7 0.7)
					(thickness 0.15)
				)
				(justify left bottom)
			)
		)
		(fp_text user "License: Apache-2.0"
			(at -0.939 5.799 270)
			(layer "F.Fab")
			(effects
				(font
					(size 0.7 0.7)
					(thickness 0.15)
				)
				(justify left bottom)
			)
		)
		(pad "1" smd roundrect
			(at -0.48 0 270)
			(size 0.59 0.64)
			(layers "F.Cu" "F.Mask" "F.Paste")
			(roundrect_rratio 0.25)
			(net 3 "GND")
			(pintype "passive")
		)
		(pad "2" smd roundrect
			(at 0.48 0 270)
			(size 0.59 0.64)
			(layers "F.Cu" "F.Mask" "F.Paste")
			(roundrect_rratio 0.25)
			(net 9 "+3V3")
			(pintype "passive")
		)
	)
	(footprint "antmicro-footprints:R_0402_1005Metric"
		(layer "F.Cu")
		(at 58.992962 177.3255 180)
		(descr "Resistor SMD 0402")
		(tags "resistor SMD 0402")
		(property "Reference" "R809"
			(at -1.507038 -0.4245 0)
			(layer "F.SilkS")
			(effects
				(font
					(size 0.7 0.7)
					(thickness 0.15)
				)
				(justify right top)
			)
		)
		(property "Value" "R_0R_0402"
			(at -1.011843 1.772046 0)
			(layer "F.Fab")
			(effects
				(font
					(size 0.7 0.7)
					(thickness 0.15)
				)
				(justify right top)
			)
		)
		(property "Datasheet" "https://industrial.panasonic.com/cdbs/www-data/pdf/RDA0000/AOA0000C301.pdf"
			(at 0 0 0)
			(layer "F.Fab")
			(hide yes)
			(effects
				(font
					(size 1.27 1.27)
					(thickness 0.15)
				)
			)
		)
		(property "Description" "SMD Chip Resistor, Jumper, 0 ohm, 100 mW, 0402 [1005 Metric], Thick Film, General Purpose"
			(at 0 0 0)
			(layer "F.Fab")
			(hide yes)
			(effects
				(font
					(size 1.27 1.27)
					(thickness 0.15)
				)
			)
		)
		(property "MPN" "ERJ2GE0R00X"
			(at 0 0 180)
			(unlocked yes)
			(layer "F.Fab")
			(hide yes)
			(effects
				(font
					(size 1 1)
					(thickness 0.15)
				)
			)
		)
		(property "Manufacturer" "Panasonic"
			(at 0 0 180)
			(unlocked yes)
			(layer "F.Fab")
			(hide yes)
			(effects
				(font
					(size 1 1)
					(thickness 0.15)
				)
			)
		)
		(property "License" "Apache-2.0"
			(at 0 0 180)
			(unlocked yes)
			(layer "F.Fab")
			(hide yes)
			(effects
				(font
					(size 1 1)
					(thickness 0.15)
				)
			)
		)
		(property "Author" "Antmicro"
			(at 0 0 180)
			(unlocked yes)
			(layer "F.Fab")
			(hide yes)
			(effects
				(font
					(size 1 1)
					(thickness 0.15)
				)
			)
		)
		(property "Val" "0R"
			(at 0 0 180)
			(unlocked yes)
			(layer "F.Fab")
			(hide yes)
			(effects
				(font
					(size 1 1)
					(thickness 0.15)
				)
			)
		)
		(property "Tolerance" "~"
			(at 0 0 180)
			(unlocked yes)
			(layer "F.Fab")
			(hide yes)
			(effects
				(font
					(size 1 1)
					(thickness 0.15)
				)
			)
		)
		(property "Current" "1A"
			(at 0 0 180)
			(unlocked yes)
			(layer "F.Fab")
			(hide yes)
			(effects
				(font
					(size 1 1)
					(thickness 0.15)
				)
			)
		)
		(sheetname "/Peripherals/")
		(sheetfile "peripherals.kicad_sch")
		(attr smd)
		(fp_poly
			(pts
				(xy -0.925 -0.47) (xy 0.925 -0.47) (xy 0.925 0.47) (xy -0.925 0.47)
			)
			(stroke
				(width 0.05)
				(type default)
			)
			(fill no)
			(layer "F.CrtYd")
		)
		(fp_poly
			(pts
				(xy -0.5 -0.25) (xy 0.5 -0.25) (xy 0.5 0.25) (xy -0.5 0.25)
			)
			(stroke
				(width 0.15)
				(type solid)
			)
			(fill no)
			(layer "F.Fab")
		)
		(fp_text user "License: Apache-2.0"
			(at -0.949999 5.169 0)
			(layer "F.Fab")
			(effects
				(font
					(size 0.7 0.7)
					(thickness 0.15)
				)
				(justify right top)
			)
		)
		(fp_text user "${REFERENCE}"
			(at -0.95 3.168 0)
			(layer "F.Fab")
			(effects
				(font
					(size 0.7 0.7)
					(thickness 0.15)
				)
				(justify right top)
			)
		)
		(fp_text user "Author: Antmicro"
			(at -0.95 4.169 0)
			(layer "F.Fab")
			(effects
				(font
					(size 0.7 0.7)
					(thickness 0.15)
				)
				(justify right top)
			)
		)
		(pad "1" smd roundrect
			(at -0.48 0 180)
			(size 0.59 0.64)
			(layers "F.Cu" "F.Mask" "F.Paste")
			(roundrect_rratio 0.25)
			(net 100 "Net-(C811-Pad2)")
			(pintype "passive")
		)
		(pad "2" smd roundrect
			(at 0.48 0 180)
			(size 0.59 0.64)
			(layers "F.Cu" "F.Mask" "F.Paste")
			(roundrect_rratio 0.25)
			(net 320 "Net-(J804-Pad2)")
			(pintype "passive")
		)
	)
	(footprint "antmicro-footprints:R_0402_1005Metric"
		(layer "F.Cu")
		(at 120.3 155.5915 180)
		(descr "Resistor SMD 0402")
		(tags "resistor SMD 0402")
		(property "Reference" "R219"
			(at -4.3 -0.175 180)
			(layer "F.SilkS")
			(effects
				(font
					(size 0.7 0.7)
					(thickness 0.15)
				)
				(justify left bottom)
			)
		)
		(property "Value" "R_0R_0402"
			(at -1.011843 1.772047 180)
			(layer "F.Fab")
			(effects
				(font
					(size 0.7 0.7)
					(thickness 0.15)
				)
				(justify left bottom)
			)
		)
		(property "Datasheet" "https://industrial.panasonic.com/cdbs/www-data/pdf/RDA0000/AOA0000C301.pdf"
			(at 0 0 180)
			(layer "F.Fab")
			(hide yes)
			(effects
				(font
					(size 1.27 1.27)
					(thickness 0.15)
				)
			)
		)
		(property "Manufacturer" "Panasonic"
			(at 0 0 180)
			(unlocked yes)
			(layer "F.Fab")
			(hide yes)
			(effects
				(font
					(size 1 1)
					(thickness 0.15)
				)
			)
		)
		(property "MPN" "ERJ2GE0R00X"
			(at 0 0 180)
			(unlocked yes)
			(layer "F.Fab")
			(hide yes)
			(effects
				(font
					(size 1 1)
					(thickness 0.15)
				)
			)
		)
		(property "Val" "0R"
			(at 0 0 180)
			(unlocked yes)
			(layer "F.Fab")
			(hide yes)
			(effects
				(font
					(size 1 1)
					(thickness 0.15)
				)
			)
		)
		(property "License" "Apache-2.0"
			(at 0 0 180)
			(unlocked yes)
			(layer "F.Fab")
			(hide yes)
			(effects
				(font
					(size 1 1)
					(thickness 0.15)
				)
			)
		)
		(property "Author" "Antmicro"
			(at 0 0 180)
			(unlocked yes)
			(layer "F.Fab")
			(hide yes)
			(effects
				(font
					(size 1 1)
					(thickness 0.15)
				)
			)
		)
		(property "Tolerance" "~"
			(at 0 0 180)
			(unlocked yes)
			(layer "F.Fab")
			(hide yes)
			(effects
				(font
					(size 1 1)
					(thickness 0.15)
				)
			)
		)
		(property "Current" "1A"
			(at 0 0 180)
			(unlocked yes)
			(layer "F.Fab")
			(hide yes)
			(effects
				(font
					(size 1 1)
					(thickness 0.15)
				)
			)
		)
		(sheetname "/Compute module/")
		(sheetfile "compute-module.kicad_sch")
		(attr smd)
		(fp_rect
			(start -0.925 -0.47)
			(end 0.925 0.47)
			(stroke
				(width 0.05)
				(type default)
			)
			(fill no)
			(layer "F.CrtYd")
		)
		(fp_rect
			(start -0.5 -0.25)
			(end 0.5 0.25)
			(stroke
				(width 0.15)
				(type solid)
			)
			(fill no)
			(layer "F.Fab")
		)
		(fp_text user "${REFERENCE}"
			(at -0.95 3.168 180)
			(layer "F.Fab")
			(effects
				(font
					(size 0.7 0.7)
					(thickness 0.15)
				)
				(justify left bottom)
			)
		)
		(fp_text user "Author: Antmicro"
			(at -0.95 4.169 180)
			(layer "F.Fab")
			(effects
				(font
					(size 0.7 0.7)
					(thickness 0.15)
				)
				(justify left bottom)
			)
		)
		(fp_text user "License: Apache-2.0"
			(at -0.95 5.169 180)
			(layer "F.Fab")
			(effects
				(font
					(size 0.7 0.7)
					(thickness 0.15)
				)
				(justify left bottom)
			)
		)
		(pad "1" smd roundrect
			(at -0.48 0 180)
			(size 0.59 0.64)
			(layers "F.Cu" "F.Mask" "F.Paste")
			(roundrect_rratio 0.25)
			(net 166 "/Compute module/NVMe.RX1_N")
			(pintype "passive")
		)
		(pad "2" smd roundrect
			(at 0.48 0 180)
			(size 0.59 0.64)
			(layers "F.Cu" "F.Mask" "F.Paste")
			(roundrect_rratio 0.25)
			(net 148 "/Compute module/R1_N")
			(pintype "passive")
		)
	)
	(footprint "antmicro-footprints:C_0402_1005Metric"
		(layer "F.Cu")
		(at 83.567962 139.332236 180)
		(descr "Capacitor SMD 0402")
		(tags "capacitor SMD 0402")
		(property "Reference" "C922"
			(at 1.12 -0.484264 0)
			(layer "F.SilkS")
			(effects
				(font
					(size 0.7 0.7)
					(thickness 0.15)
				)
				(justify right bottom)
			)
		)
		(property "Value" "C_100n_0402"
			(at -1.022927 2.155213 0)
			(layer "F.Fab")
			(effects
				(font
					(size 0.7 0.7)
					(thickness 0.15)
				)
				(justify right bottom)
			)
		)
		(property "Datasheet" "https://www.murata.com/products/productdetail?partno=GRM155R61H104KE14%23"
			(at 0 0 180)
			(layer "F.Fab")
			(hide yes)
			(effects
				(font
					(size 1.27 1.27)
					(thickness 0.15)
				)
			)
		)
		(property "Manufacturer" "Murata"
			(at 0 0 180)
			(unlocked yes)
			(layer "F.Fab")
			(hide yes)
			(effects
				(font
					(size 1 1)
					(thickness 0.15)
				)
			)
		)
		(property "MPN" "GRM155R61H104KE14D"
			(at 0 0 180)
			(unlocked yes)
			(layer "F.Fab")
			(hide yes)
			(effects
				(font
					(size 1 1)
					(thickness 0.15)
				)
			)
		)
		(property "Val" "100n"
			(at 0 0 180)
			(unlocked yes)
			(layer "F.Fab")
			(hide yes)
			(effects
				(font
					(size 1 1)
					(thickness 0.15)
				)
			)
		)
		(property "License" "Apache-2.0"
			(at 0 0 180)
			(unlocked yes)
			(layer "F.Fab")
			(hide yes)
			(effects
				(font
					(size 1 1)
					(thickness 0.15)
				)
			)
		)
		(property "Author" "Antmicro"
			(at 0 0 180)
			(unlocked yes)
			(layer "F.Fab")
			(hide yes)
			(effects
				(font
					(size 1 1)
					(thickness 0.15)
				)
			)
		)
		(property "Voltage" "50V"
			(at 0 0 180)
			(unlocked yes)
			(layer "F.Fab")
			(hide yes)
			(effects
				(font
					(size 1 1)
					(thickness 0.15)
				)
			)
		)
		(property "Dielectric" "X5R"
			(at 0 0 180)
			(unlocked yes)
			(layer "F.Fab")
			(hide yes)
			(effects
				(font
					(size 1 1)
					(thickness 0.15)
				)
			)
		)
		(sheetname "/USB/")
		(sheetfile "usb.kicad_sch")
		(attr smd)
		(fp_rect
			(start -0.925 -0.47)
			(end 0.925 0.47)
			(stroke
				(width 0.05)
				(type default)
			)
			(fill no)
			(layer "F.CrtYd")
		)
		(fp_line
			(start 0.504 0.248)
			(end -0.494 0.248)
			(stroke
				(width 0.15)
				(type solid)
			)
			(layer "F.Fab")
		)
		(fp_line
			(start 0.504 -0.25)
			(end 0.504 0.248)
			(stroke
				(width 0.15)
				(type solid)
			)
			(layer "F.Fab")
		)
		(fp_line
			(start -0.494 0.248)
			(end -0.494 -0.25)
			(stroke
				(width 0.15)
				(type solid)
			)
			(layer "F.Fab")
		)
		(fp_line
			(start -0.494 -0.25)
			(end 0.504 -0.25)
			(stroke
				(width 0.15)
				(type solid)
			)
			(layer "F.Fab")
		)
		(fp_text user "License: Apache-2.0"
			(at -0.939 5.799 180)
			(layer "F.Fab")
			(effects
				(font
					(size 0.7 0.7)
					(thickness 0.15)
				)
				(justify left bottom)
			)
		)
		(fp_text user "${REFERENCE}"
			(at -0.939 4.599 180)
			(layer "F.Fab")
			(effects
				(font
					(size 0.7 0.7)
					(thickness 0.15)
				)
				(justify left bottom)
			)
		)
		(fp_text user "Author: Antmicro"
			(at -0.939 3.399 180)
			(layer "F.Fab")
			(effects
				(font
					(size 0.7 0.7)
					(thickness 0.15)
				)
				(justify left bottom)
			)
		)
		(pad "1" smd roundrect
			(at -0.48 0 180)
			(size 0.59 0.64)
			(layers "F.Cu" "F.Mask" "F.Paste")
			(roundrect_rratio 0.25)
			(net 27 "/USB/USB_3V3")
			(pintype "passive")
		)
		(pad "2" smd roundrect
			(at 0.48 0 180)
			(size 0.59 0.64)
			(layers "F.Cu" "F.Mask" "F.Paste")
			(roundrect_rratio 0.25)
			(net 3 "GND")
			(pintype "passive")
		)
	)
	(footprint "antmicro-footprints:R_0402_1005Metric"
		(layer "F.Cu")
		(at 102.067962 144.6165 180)
		(descr "Resistor SMD 0402")
		(tags "resistor SMD 0402")
		(property "Reference" "R929"
			(at -3.6 -0.45 0)
			(layer "F.SilkS")
			(effects
				(font
					(size 0.7 0.7)
					(thickness 0.15)
				)
				(justify right bottom)
			)
		)
		(property "Value" "R_10k_0402"
			(at -1.011843 1.772047 0)
			(layer "F.Fab")
			(effects
				(font
					(size 0.7 0.7)
					(thickness 0.15)
				)
				(justify right bottom)
			)
		)
		(property "Datasheet" "https://www.bourns.com/docs/product-datasheets/cr.pdf"
			(at 0 0 180)
			(layer "F.Fab")
			(hide yes)
			(effects
				(font
					(size 1.27 1.27)
					(thickness 0.15)
				)
			)
		)
		(property "Manufacturer" "Bourns"
			(at 0 0 180)
			(unlocked yes)
			(layer "F.Fab")
			(hide yes)
			(effects
				(font
					(size 1 1)
					(thickness 0.15)
				)
			)
		)
		(property "MPN" "CR0402-FX-1002GLF"
			(at 0 0 180)
			(unlocked yes)
			(layer "F.Fab")
			(hide yes)
			(effects
				(font
					(size 1 1)
					(thickness 0.15)
				)
			)
		)
		(property "Val" "10k"
			(at 0 0 180)
			(unlocked yes)
			(layer "F.Fab")
			(hide yes)
			(effects
				(font
					(size 1 1)
					(thickness 0.15)
				)
			)
		)
		(property "License" "Apache-2.0"
			(at 0 0 180)
			(unlocked yes)
			(layer "F.Fab")
			(hide yes)
			(effects
				(font
					(size 1 1)
					(thickness 0.15)
				)
			)
		)
		(property "Author" "Antmicro"
			(at 0 0 180)
			(unlocked yes)
			(layer "F.Fab")
			(hide yes)
			(effects
				(font
					(size 1 1)
					(thickness 0.15)
				)
			)
		)
		(property "Tolerance" "1%"
			(at 0 0 180)
			(unlocked yes)
			(layer "F.Fab")
			(hide yes)
			(effects
				(font
					(size 1 1)
					(thickness 0.15)
				)
			)
		)
		(sheetname "/USB/")
		(sheetfile "usb.kicad_sch")
		(attr smd)
		(fp_rect
			(start -0.925 -0.47)
			(end 0.925 0.47)
			(stroke
				(width 0.05)
				(type default)
			)
			(fill no)
			(layer "F.CrtYd")
		)
		(fp_rect
			(start -0.5 -0.25)
			(end 0.5 0.25)
			(stroke
				(width 0.15)
				(type solid)
			)
			(fill no)
			(layer "F.Fab")
		)
		(fp_text user "License: Apache-2.0"
			(at -0.95 5.169 180)
			(layer "F.Fab")
			(effects
				(font
					(size 0.7 0.7)
					(thickness 0.15)
				)
				(justify left bottom)
			)
		)
		(fp_text user "Author: Antmicro"
			(at -0.95 4.169 180)
			(layer "F.Fab")
			(effects
				(font
					(size 0.7 0.7)
					(thickness 0.15)
				)
				(justify left bottom)
			)
		)
		(fp_text user "${REFERENCE}"
			(at -0.95 3.168 180)
			(layer "F.Fab")
			(effects
				(font
					(size 0.7 0.7)
					(thickness 0.15)
				)
				(justify left bottom)
			)
		)
		(pad "1" smd roundrect
			(at -0.48 0 180)
			(size 0.59 0.64)
			(layers "F.Cu" "F.Mask" "F.Paste")
			(roundrect_rratio 0.25)
			(net 490 "Net-(Q905-G)")
			(pintype "passive")
		)
		(pad "2" smd roundrect
			(at 0.48 0 180)
			(size 0.59 0.64)
			(layers "F.Cu" "F.Mask" "F.Paste")
			(roundrect_rratio 0.25)
			(net 3 "GND")
			(pintype "passive")
		)
	)
	(footprint "antmicro-footprints:TP_SMD_0.75mm"
		(layer "F.Cu")
		(at 70.567962 178.2915 -90)
		(property "Reference" "TP803"
			(at 1.3085 2.867962 0)
			(layer "F.SilkS")
			(effects
				(font
					(size 0.7 0.65)
					(thickness 0.15)
				)
				(justify left bottom)
			)
		)
		(property "Value" "TP_0.75mm_SMD"
			(at 0 1.2 270)
			(layer "F.Fab")
			(effects
				(font
					(size 0.7 0.7)
					(thickness 0.15)
				)
				(justify left bottom)
			)
		)
		(property "Author" "Antmicro"
			(at 0 0 270)
			(unlocked yes)
			(layer "F.Fab")
			(hide yes)
			(effects
				(font
					(size 1 1)
					(thickness 0.15)
				)
			)
		)
		(property "License" "Apache-2.0"
			(at 0 0 270)
			(unlocked yes)
			(layer "F.Fab")
			(hide yes)
			(effects
				(font
					(size 1 1)
					(thickness 0.15)
				)
			)
		)
		(property "MPN" ""
			(at 0 0 270)
			(unlocked yes)
			(layer "F.Fab")
			(hide yes)
			(effects
				(font
					(size 1 1)
					(thickness 0.15)
				)
			)
		)
		(property "Manufacturer" ""
			(at 0 0 270)
			(unlocked yes)
			(layer "F.Fab")
			(hide yes)
			(effects
				(font
					(size 1 1)
					(thickness 0.15)
				)
			)
		)
		(sheetname "/Peripherals/")
		(sheetfile "peripherals.kicad_sch")
		(attr exclude_from_pos_files exclude_from_bom)
		(fp_circle
			(center 0 0)
			(end 0.475 0)
			(stroke
				(width 0.05)
				(type default)
			)
			(fill no)
			(layer "F.CrtYd")
		)
		(fp_text user "${REFERENCE}"
			(at -0.4 2.7 270)
			(layer "F.Fab")
			(effects
				(font
					(size 0.7 0.7)
					(thickness 0.15)
				)
				(justify left bottom)
			)
		)
		(fp_text user "License: Apache-2.0"
			(at -0.4 5.101 270)
			(layer "F.Fab")
			(effects
				(font
					(size 0.7 0.7)
					(thickness 0.15)
				)
				(justify left bottom)
			)
		)
		(fp_text user "Author: Antmicro"
			(at -0.4 3.901 270)
			(layer "F.Fab")
			(effects
				(font
					(size 0.7 0.7)
					(thickness 0.15)
				)
				(justify left bottom)
			)
		)
		(pad "1" smd circle
			(at 0 0 270)
			(size 0.75 0.75)
			(layers "F.Cu" "F.Mask")
			(net 383 "Net-(U801-V_{DD(HF)})")
			(pinfunction "1")
			(pintype "passive")
		)
	)
	(footprint "antmicro-footprints:R_0402_1005Metric"
		(layer "F.Cu")
		(at 54.847962 128.8965)
		(descr "Resistor SMD 0402")
		(tags "resistor SMD 0402")
		(property "Reference" "R406"
			(at -1.49 -5.38 0)
			(layer "F.SilkS")
			(effects
				(font
					(size 0.7 0.7)
					(thickness 0.15)
				)
				(justify left bottom)
			)
		)
		(property "Value" "R_24k9_0402"
			(at -1.011843 1.772047 0)
			(layer "F.Fab")
			(effects
				(font
					(size 0.7 0.7)
					(thickness 0.15)
				)
				(justify left bottom)
			)
		)
		(property "Datasheet" "https://www.bourns.com/docs/product-datasheets/cr.pdf"
			(at 0 0 0)
			(layer "F.Fab")
			(hide yes)
			(effects
				(font
					(size 1.27 1.27)
					(thickness 0.15)
				)
			)
		)
		(property "Manufacturer" "Bourns"
			(at 0 0 0)
			(unlocked yes)
			(layer "F.Fab")
			(hide yes)
			(effects
				(font
					(size 1 1)
					(thickness 0.15)
				)
			)
		)
		(property "MPN" "CR0402-FX-2492GLF"
			(at 0 0 0)
			(unlocked yes)
			(layer "F.Fab")
			(hide yes)
			(effects
				(font
					(size 1 1)
					(thickness 0.15)
				)
			)
		)
		(property "Val" "24k9"
			(at 0 0 0)
			(unlocked yes)
			(layer "F.Fab")
			(hide yes)
			(effects
				(font
					(size 1 1)
					(thickness 0.15)
				)
			)
		)
		(property "License" "Apache-2.0"
			(at 0 0 0)
			(unlocked yes)
			(layer "F.Fab")
			(hide yes)
			(effects
				(font
					(size 1 1)
					(thickness 0.15)
				)
			)
		)
		(property "Author" "Antmicro"
			(at 0 0 0)
			(unlocked yes)
			(layer "F.Fab")
			(hide yes)
			(effects
				(font
					(size 1 1)
					(thickness 0.15)
				)
			)
		)
		(property "Tolerance" "1%"
			(at 0 0 0)
			(unlocked yes)
			(layer "F.Fab")
			(hide yes)
			(effects
				(font
					(size 1 1)
					(thickness 0.15)
				)
			)
		)
		(sheetname "/Ethernet/")
		(sheetfile "ethernet.kicad_sch")
		(attr smd)
		(fp_rect
			(start -0.925 -0.47)
			(end 0.925 0.47)
			(stroke
				(width 0.05)
				(type default)
			)
			(fill no)
			(layer "F.CrtYd")
		)
		(fp_rect
			(start -0.5 -0.25)
			(end 0.5 0.25)
			(stroke
				(width 0.15)
				(type solid)
			)
			(fill no)
			(layer "F.Fab")
		)
		(fp_text user "License: Apache-2.0"
			(at -0.95 5.169 0)
			(layer "F.Fab")
			(effects
				(font
					(size 0.7 0.7)
					(thickness 0.15)
				)
				(justify left bottom)
			)
		)
		(fp_text user "${REFERENCE}"
			(at -0.95 3.168 0)
			(layer "F.Fab")
			(effects
				(font
					(size 0.7 0.7)
					(thickness 0.15)
				)
				(justify left bottom)
			)
		)
		(fp_text user "Author: Antmicro"
			(at -0.95 4.169 0)
			(layer "F.Fab")
			(effects
				(font
					(size 0.7 0.7)
					(thickness 0.15)
				)
				(justify left bottom)
			)
		)
		(pad "1" smd roundrect
			(at -0.48 0)
			(size 0.59 0.64)
			(layers "F.Cu" "F.Mask" "F.Paste")
			(roundrect_rratio 0.25)
			(net 361 "/Ethernet/DEN")
			(pintype "passive")
		)
		(pad "2" smd roundrect
			(at 0.48 0)
			(size 0.59 0.64)
			(layers "F.Cu" "F.Mask" "F.Paste")
			(roundrect_rratio 0.25)
			(net 33 "/Ethernet/VDD")
			(pintype "passive")
		)
	)
	(footprint "antmicro-footprints:C_0402_1005Metric"
		(layer "F.Cu")
		(at 95.592962 141.1165)
		(descr "Capacitor SMD 0402")
		(tags "capacitor SMD 0402")
		(property "Reference" "C915"
			(at 0.625 0.05 0)
			(layer "F.SilkS")
			(effects
				(font
					(size 0.7 0.7)
					(thickness 0.15)
				)
				(justify left bottom)
			)
		)
		(property "Value" "C_100n_0402"
			(at -1.022927 2.155213 0)
			(layer "F.Fab")
			(effects
				(font
					(size 0.7 0.7)
					(thickness 0.15)
				)
				(justify left bottom)
			)
		)
		(property "Datasheet" "https://www.murata.com/products/productdetail?partno=GRM155R61H104KE14%23"
			(at 0 0 0)
			(layer "F.Fab")
			(hide yes)
			(effects
				(font
					(size 1.27 1.27)
					(thickness 0.15)
				)
			)
		)
		(property "Manufacturer" "Murata"
			(at 0 0 0)
			(unlocked yes)
			(layer "F.Fab")
			(hide yes)
			(effects
				(font
					(size 1 1)
					(thickness 0.15)
				)
			)
		)
		(property "MPN" "GRM155R61H104KE14D"
			(at 0 0 0)
			(unlocked yes)
			(layer "F.Fab")
			(hide yes)
			(effects
				(font
					(size 1 1)
					(thickness 0.15)
				)
			)
		)
		(property "Val" "100n"
			(at 0 0 0)
			(unlocked yes)
			(layer "F.Fab")
			(hide yes)
			(effects
				(font
					(size 1 1)
					(thickness 0.15)
				)
			)
		)
		(property "License" "Apache-2.0"
			(at 0 0 0)
			(unlocked yes)
			(layer "F.Fab")
			(hide yes)
			(effects
				(font
					(size 1 1)
					(thickness 0.15)
				)
			)
		)
		(property "Author" "Antmicro"
			(at 0 0 0)
			(unlocked yes)
			(layer "F.Fab")
			(hide yes)
			(effects
				(font
					(size 1 1)
					(thickness 0.15)
				)
			)
		)
		(property "Voltage" "50V"
			(at 0 0 0)
			(unlocked yes)
			(layer "F.Fab")
			(hide yes)
			(effects
				(font
					(size 1 1)
					(thickness 0.15)
				)
			)
		)
		(property "Dielectric" "X5R"
			(at 0 0 0)
			(unlocked yes)
			(layer "F.Fab")
			(hide yes)
			(effects
				(font
					(size 1 1)
					(thickness 0.15)
				)
			)
		)
		(sheetname "/USB/")
		(sheetfile "usb.kicad_sch")
		(attr smd)
		(fp_rect
			(start -0.925 -0.47)
			(end 0.925 0.47)
			(stroke
				(width 0.05)
				(type default)
			)
			(fill no)
			(layer "F.CrtYd")
		)
		(fp_line
			(start -0.494 -0.25)
			(end 0.504 -0.25)
			(stroke
				(width 0.15)
				(type solid)
			)
			(layer "F.Fab")
		)
		(fp_line
			(start -0.494 0.248)
			(end -0.494 -0.25)
			(stroke
				(width 0.15)
				(type solid)
			)
			(layer "F.Fab")
		)
		(fp_line
			(start 0.504 -0.25)
			(end 0.504 0.248)
			(stroke
				(width 0.15)
				(type solid)
			)
			(layer "F.Fab")
		)
		(fp_line
			(start 0.504 0.248)
			(end -0.494 0.248)
			(stroke
				(width 0.15)
				(type solid)
			)
			(layer "F.Fab")
		)
		(fp_text user "${REFERENCE}"
			(at -0.939 4.599 0)
			(layer "F.Fab")
			(effects
				(font
					(size 0.7 0.7)
					(thickness 0.15)
				)
				(justify left bottom)
			)
		)
		(fp_text user "Author: Antmicro"
			(at -0.939 3.399 0)
			(layer "F.Fab")
			(effects
				(font
					(size 0.7 0.7)
					(thickness 0.15)
				)
				(justify left bottom)
			)
		)
		(fp_text user "License: Apache-2.0"
			(at -0.939 5.799 0)
			(layer "F.Fab")
			(effects
				(font
					(size 0.7 0.7)
					(thickness 0.15)
				)
				(justify left bottom)
			)
		)
		(pad "1" smd roundrect
			(at -0.48 0)
			(size 0.59 0.64)
			(layers "F.Cu" "F.Mask" "F.Paste")
			(roundrect_rratio 0.25)
			(net 27 "/USB/USB_3V3")
			(pintype "passive")
		)
		(pad "2" smd roundrect
			(at 0.48 0)
			(size 0.59 0.64)
			(layers "F.Cu" "F.Mask" "F.Paste")
			(roundrect_rratio 0.25)
			(net 3 "GND")
			(pintype "passive")
		)
	)
	(footprint "antmicro-footprints:R_0402_1005Metric"
		(layer "F.Cu")
		(at 53.017962 135.3415 90)
		(descr "Resistor SMD 0402")
		(tags "resistor SMD 0402")
		(property "Reference" "R416"
			(at -1.8693 -4.072162 180)
			(layer "F.SilkS")
			(effects
				(font
					(size 0.7 0.7)
					(thickness 0.15)
				)
				(justify left bottom)
			)
		)
		(property "Value" "R_100k_0402"
			(at -1.011843 1.772047 90)
			(layer "F.Fab")
			(effects
				(font
					(size 0.7 0.7)
					(thickness 0.15)
				)
				(justify left bottom)
			)
		)
		(property "Datasheet" "https://www.bourns.com/docs/product-datasheets/cr.pdf"
			(at 0 0 90)
			(layer "F.Fab")
			(hide yes)
			(effects
				(font
					(size 1.27 1.27)
					(thickness 0.15)
				)
			)
		)
		(property "Manufacturer" "Bourns"
			(at 0 0 90)
			(unlocked yes)
			(layer "F.Fab")
			(hide yes)
			(effects
				(font
					(size 1 1)
					(thickness 0.15)
				)
			)
		)
		(property "MPN" "CR0402-FX-1003GLF"
			(at 0 0 90)
			(unlocked yes)
			(layer "F.Fab")
			(hide yes)
			(effects
				(font
					(size 1 1)
					(thickness 0.15)
				)
			)
		)
		(property "Val" "100k"
			(at 0 0 90)
			(unlocked yes)
			(layer "F.Fab")
			(hide yes)
			(effects
				(font
					(size 1 1)
					(thickness 0.15)
				)
			)
		)
		(property "License" "Apache-2.0"
			(at 0 0 90)
			(unlocked yes)
			(layer "F.Fab")
			(hide yes)
			(effects
				(font
					(size 1 1)
					(thickness 0.15)
				)
			)
		)
		(property "Author" "Antmicro"
			(at 0 0 90)
			(unlocked yes)
			(layer "F.Fab")
			(hide yes)
			(effects
				(font
					(size 1 1)
					(thickness 0.15)
				)
			)
		)
		(property "Tolerance" "1%"
			(at 0 0 90)
			(unlocked yes)
			(layer "F.Fab")
			(hide yes)
			(effects
				(font
					(size 1 1)
					(thickness 0.15)
				)
			)
		)
		(sheetname "/Ethernet/")
		(sheetfile "ethernet.kicad_sch")
		(attr smd)
		(fp_rect
			(start -0.925 -0.47)
			(end 0.925 0.47)
			(stroke
				(width 0.05)
				(type default)
			)
			(fill no)
			(layer "F.CrtYd")
		)
		(fp_rect
			(start -0.5 -0.25)
			(end 0.5 0.25)
			(stroke
				(width 0.15)
				(type solid)
			)
			(fill no)
			(layer "F.Fab")
		)
		(fp_text user "License: Apache-2.0"
			(at -0.95 5.169 90)
			(layer "F.Fab")
			(effects
				(font
					(size 0.7 0.7)
					(thickness 0.15)
				)
				(justify left bottom)
			)
		)
		(fp_text user "Author: Antmicro"
			(at -0.95 4.169 90)
			(layer "F.Fab")
			(effects
				(font
					(size 0.7 0.7)
					(thickness 0.15)
				)
				(justify left bottom)
			)
		)
		(fp_text user "${REFERENCE}"
			(at -0.95 3.168 90)
			(layer "F.Fab")
			(effects
				(font
					(size 0.7 0.7)
					(thickness 0.15)
				)
				(justify left bottom)
			)
		)
		(pad "1" smd roundrect
			(at -0.48 0 90)
			(size 0.59 0.64)
			(layers "F.Cu" "F.Mask" "F.Paste")
			(roundrect_rratio 0.25)
			(net 1 "GNDD")
			(pintype "passive")
		)
		(pad "2" smd roundrect
			(at 0.48 0 90)
			(size 0.59 0.64)
			(layers "F.Cu" "F.Mask" "F.Paste")
			(roundrect_rratio 0.25)
			(net 339 "/Ethernet/POE_ACTIVE")
			(pintype "passive")
		)
	)
	(footprint "antmicro-footprints:C_0402_1005Metric"
		(layer "F.Cu")
		(at 63.617962 178.2005 180)
		(descr "Capacitor SMD 0402")
		(tags "capacitor SMD 0402")
		(property "Reference" "C821"
			(at 13.367962 1.4505 0)
			(layer "F.SilkS")
			(effects
				(font
					(size 0.7 0.7)
					(thickness 0.15)
				)
				(justify right top)
			)
		)
		(property "Value" "C_36p_0402"
			(at -1.022927 2.155213 0)
			(layer "F.Fab")
			(effects
				(font
					(size 0.7 0.7)
					(thickness 0.15)
				)
				(justify right top)
			)
		)
		(property "Datasheet" "https://eu.mouser.com/datasheet/3/5926/1/C0GNP0_Dielectric.pdf"
			(at 0 0 0)
			(layer "F.Fab")
			(hide yes)
			(effects
				(font
					(size 1.27 1.27)
					(thickness 0.15)
				)
			)
		)
		(property "Description" "Multilayer Ceramic Capacitors MLCC, 36 pF, 25V, 0402, C0G, 5%"
			(at 0 0 0)
			(layer "F.Fab")
			(hide yes)
			(effects
				(font
					(size 1.27 1.27)
					(thickness 0.15)
				)
			)
		)
		(property "MPN" "04023A360JAT2A"
			(at 0 0 180)
			(unlocked yes)
			(layer "F.Fab")
			(hide yes)
			(effects
				(font
					(size 1 1)
					(thickness 0.15)
				)
			)
		)
		(property "Manufacturer" "KYOCERA AVX"
			(at 0 0 180)
			(unlocked yes)
			(layer "F.Fab")
			(hide yes)
			(effects
				(font
					(size 1 1)
					(thickness 0.15)
				)
			)
		)
		(property "License" "Apache-2.0"
			(at 0 0 180)
			(unlocked yes)
			(layer "F.Fab")
			(hide yes)
			(effects
				(font
					(size 1 1)
					(thickness 0.15)
				)
			)
		)
		(property "Author" "Antmicro"
			(at 0 0 180)
			(unlocked yes)
			(layer "F.Fab")
			(hide yes)
			(effects
				(font
					(size 1 1)
					(thickness 0.15)
				)
			)
		)
		(property "Val" "36pF"
			(at 0 0 180)
			(unlocked yes)
			(layer "F.Fab")
			(hide yes)
			(effects
				(font
					(size 1 1)
					(thickness 0.15)
				)
			)
		)
		(property "Voltage" "25 V"
			(at 0 0 180)
			(unlocked yes)
			(layer "F.Fab")
			(hide yes)
			(effects
				(font
					(size 1 1)
					(thickness 0.15)
				)
			)
		)
		(property "Dielectric" "C0G (NP0)"
			(at 0 0 180)
			(unlocked yes)
			(layer "F.Fab")
			(hide yes)
			(effects
				(font
					(size 1 1)
					(thickness 0.15)
				)
			)
		)
		(sheetname "/Peripherals/")
		(sheetfile "peripherals.kicad_sch")
		(attr smd)
		(fp_rect
			(start -0.925 -0.47)
			(end 0.925 0.47)
			(stroke
				(width 0.05)
				(type default)
			)
			(fill no)
			(layer "F.CrtYd")
		)
		(fp_line
			(start 0.504 0.248)
			(end -0.494 0.248)
			(stroke
				(width 0.15)
				(type solid)
			)
			(layer "F.Fab")
		)
		(fp_line
			(start 0.504 -0.25)
			(end 0.504 0.248)
			(stroke
				(width 0.15)
				(type solid)
			)
			(layer "F.Fab")
		)
		(fp_line
			(start -0.494 0.248)
			(end -0.494 -0.25)
			(stroke
				(width 0.15)
				(type solid)
			)
			(layer "F.Fab")
		)
		(fp_line
			(start -0.494 -0.25)
			(end 0.504 -0.25)
			(stroke
				(width 0.15)
				(type solid)
			)
			(layer "F.Fab")
		)
		(fp_text user "Author: Antmicro"
			(at -0.939 3.399 0)
			(layer "F.Fab")
			(effects
				(font
					(size 0.7 0.7)
					(thickness 0.15)
				)
				(justify right top)
			)
		)
		(fp_text user "License: Apache-2.0"
			(at -0.939 5.799 0)
			(layer "F.Fab")
			(effects
				(font
					(size 0.7 0.7)
					(thickness 0.15)
				)
				(justify right top)
			)
		)
		(fp_text user "${REFERENCE}"
			(at -0.939 4.599 0)
			(layer "F.Fab")
			(effects
				(font
					(size 0.7 0.7)
					(thickness 0.15)
				)
				(justify right top)
			)
		)
		(pad "1" smd roundrect
			(at -0.48 0 180)
			(size 0.59 0.64)
			(layers "F.Cu" "F.Mask" "F.Paste")
			(roundrect_rratio 0.25)
			(net 109 "Net-(C816-Pad2)")
			(pintype "passive")
		)
		(pad "2" smd roundrect
			(at 0.48 0 180)
			(size 0.59 0.64)
			(layers "F.Cu" "F.Mask" "F.Paste")
			(roundrect_rratio 0.25)
			(net 100 "Net-(C811-Pad2)")
			(pintype "passive")
		)
	)
	(footprint "antmicro-footprints:TP_SMD_0.75mm"
		(layer "F.Cu")
		(at 88.09 131.94 180)
		(property "Reference" "TP913"
			(at -0.18 4.11 0)
			(layer "F.SilkS")
			(effects
				(font
					(size 0.7 0.7)
					(thickness 0.15)
				)
				(justify right bottom)
			)
		)
		(property "Value" "TP_0.75mm_SMD"
			(at 0 1.2 0)
			(layer "F.Fab")
			(effects
				(font
					(size 0.7 0.7)
					(thickness 0.15)
				)
				(justify right bottom)
			)
		)
		(property "MPN" ""
			(at 0 0 180)
			(unlocked yes)
			(layer "F.Fab")
			(hide yes)
			(effects
				(font
					(size 1 1)
					(thickness 0.15)
				)
			)
		)
		(property "Manufacturer" ""
			(at 0 0 180)
			(unlocked yes)
			(layer "F.Fab")
			(hide yes)
			(effects
				(font
					(size 1 1)
					(thickness 0.15)
				)
			)
		)
		(property "Author" "Antmicro"
			(at 0 0 180)
			(unlocked yes)
			(layer "F.Fab")
			(hide yes)
			(effects
				(font
					(size 1 1)
					(thickness 0.15)
				)
			)
		)
		(property "License" "Apache-2.0"
			(at 0 0 180)
			(unlocked yes)
			(layer "F.Fab")
			(hide yes)
			(effects
				(font
					(size 1 1)
					(thickness 0.15)
				)
			)
		)
		(sheetname "/USB/")
		(sheetfile "usb.kicad_sch")
		(attr exclude_from_pos_files exclude_from_bom)
		(fp_circle
			(center 0 0)
			(end 0.475 0)
			(stroke
				(width 0.05)
				(type default)
			)
			(fill no)
			(layer "F.CrtYd")
		)
		(fp_text user "License: Apache-2.0"
			(at -0.4 5.101 180)
			(layer "F.Fab")
			(effects
				(font
					(size 0.7 0.7)
					(thickness 0.15)
				)
				(justify left bottom)
			)
		)
		(fp_text user "Author: Antmicro"
			(at -0.4 3.901 180)
			(layer "F.Fab")
			(effects
				(font
					(size 0.7 0.7)
					(thickness 0.15)
				)
				(justify left bottom)
			)
		)
		(fp_text user "${REFERENCE}"
			(at -0.4 2.7 180)
			(layer "F.Fab")
			(effects
				(font
					(size 0.7 0.7)
					(thickness 0.15)
				)
				(justify left bottom)
			)
		)
		(pad "1" smd circle
			(at 0 0 180)
			(size 0.75 0.75)
			(layers "F.Cu" "F.Mask")
			(net 438 "Net-(U905-PD2_SVBUS)")
			(pinfunction "1")
			(pintype "passive")
		)
	)
	(footprint "antmicro-footprints:TP_SMD_0.75mm"
		(layer "F.Cu")
		(at 83.292962 124.4665 180)
		(property "Reference" "TP903"
			(at -3.715 -0.11 0)
			(layer "F.SilkS")
			(effects
				(font
					(size 0.7 0.7)
					(thickness 0.15)
				)
				(justify right bottom)
			)
		)
		(property "Value" "TP_0.75mm_SMD"
			(at 0 1.2 0)
			(layer "F.Fab")
			(effects
				(font
					(size 0.7 0.7)
					(thickness 0.15)
				)
				(justify right bottom)
			)
		)
		(property "MPN" ""
			(at 0 0 180)
			(unlocked yes)
			(layer "F.Fab")
			(hide yes)
			(effects
				(font
					(size 1 1)
					(thickness 0.15)
				)
			)
		)
		(property "Manufacturer" ""
			(at 0 0 180)
			(unlocked yes)
			(layer "F.Fab")
			(hide yes)
			(effects
				(font
					(size 1 1)
					(thickness 0.15)
				)
			)
		)
		(property "Author" "Antmicro"
			(at 0 0 180)
			(unlocked yes)
			(layer "F.Fab")
			(hide yes)
			(effects
				(font
					(size 1 1)
					(thickness 0.15)
				)
			)
		)
		(property "License" "Apache-2.0"
			(at 0 0 180)
			(unlocked yes)
			(layer "F.Fab")
			(hide yes)
			(effects
				(font
					(size 1 1)
					(thickness 0.15)
				)
			)
		)
		(sheetname "/USB/")
		(sheetfile "usb.kicad_sch")
		(attr exclude_from_pos_files exclude_from_bom)
		(fp_circle
			(center 0 0)
			(end 0.475 0)
			(stroke
				(width 0.05)
				(type default)
			)
			(fill no)
			(layer "F.CrtYd")
		)
		(fp_text user "License: Apache-2.0"
			(at -0.4 5.101 180)
			(layer "F.Fab")
			(effects
				(font
					(size 0.7 0.7)
					(thickness 0.15)
				)
				(justify left bottom)
			)
		)
		(fp_text user "${REFERENCE}"
			(at -0.4 2.7 180)
			(layer "F.Fab")
			(effects
				(font
					(size 0.7 0.7)
					(thickness 0.15)
				)
				(justify left bottom)
			)
		)
		(fp_text user "Author: Antmicro"
			(at -0.4 3.901 180)
			(layer "F.Fab")
			(effects
				(font
					(size 0.7 0.7)
					(thickness 0.15)
				)
				(justify left bottom)
			)
		)
		(pad "1" smd circle
			(at 0 0 180)
			(size 0.75 0.75)
			(layers "F.Cu" "F.Mask")
			(net 113 "/USB/OUT_FTDI")
			(pinfunction "1")
			(pintype "passive")
		)
	)
	(footprint "antmicro-footprints:R_0402_1005Metric"
		(layer "F.Cu")
		(at 54.827962 132.7765)
		(descr "Resistor SMD 0402")
		(tags "resistor SMD 0402")
		(property "Reference" "R415"
			(at -1.215446 -5.279197 0)
			(layer "F.SilkS")
			(effects
				(font
					(size 0.7 0.7)
					(thickness 0.15)
				)
				(justify left bottom)
			)
		)
		(property "Value" "R_470k_0402"
			(at -1.011843 1.772047 0)
			(layer "F.Fab")
			(effects
				(font
					(size 0.7 0.7)
					(thickness 0.15)
				)
				(justify left bottom)
			)
		)
		(property "Datasheet" "https://www.bourns.com/docs/product-datasheets/cr.pdf"
			(at 0 0 0)
			(layer "F.Fab")
			(hide yes)
			(effects
				(font
					(size 1.27 1.27)
					(thickness 0.15)
				)
			)
		)
		(property "Manufacturer" "Bourns"
			(at 0 0 0)
			(unlocked yes)
			(layer "F.Fab")
			(hide yes)
			(effects
				(font
					(size 1 1)
					(thickness 0.15)
				)
			)
		)
		(property "MPN" "CR0402-FX-4703GLF"
			(at 0 0 0)
			(unlocked yes)
			(layer "F.Fab")
			(hide yes)
			(effects
				(font
					(size 1 1)
					(thickness 0.15)
				)
			)
		)
		(property "Val" "470k"
			(at 0 0 0)
			(unlocked yes)
			(layer "F.Fab")
			(hide yes)
			(effects
				(font
					(size 1 1)
					(thickness 0.15)
				)
			)
		)
		(property "License" "Apache-2.0"
			(at 0 0 0)
			(unlocked yes)
			(layer "F.Fab")
			(hide yes)
			(effects
				(font
					(size 1 1)
					(thickness 0.15)
				)
			)
		)
		(property "Author" "Antmicro"
			(at 0 0 0)
			(unlocked yes)
			(layer "F.Fab")
			(hide yes)
			(effects
				(font
					(size 1 1)
					(thickness 0.15)
				)
			)
		)
		(property "Tolerance" "1%"
			(at 0 0 0)
			(unlocked yes)
			(layer "F.Fab")
			(hide yes)
			(effects
				(font
					(size 1 1)
					(thickness 0.15)
				)
			)
		)
		(sheetname "/Ethernet/")
		(sheetfile "ethernet.kicad_sch")
		(attr smd)
		(fp_rect
			(start -0.925 -0.47)
			(end 0.925 0.47)
			(stroke
				(width 0.05)
				(type default)
			)
			(fill no)
			(layer "F.CrtYd")
		)
		(fp_rect
			(start -0.5 -0.25)
			(end 0.5 0.25)
			(stroke
				(width 0.15)
				(type solid)
			)
			(fill no)
			(layer "F.Fab")
		)
		(fp_text user "Author: Antmicro"
			(at -0.95 4.169 0)
			(layer "F.Fab")
			(effects
				(font
					(size 0.7 0.7)
					(thickness 0.15)
				)
				(justify left bottom)
			)
		)
		(fp_text user "License: Apache-2.0"
			(at -0.95 5.169 0)
			(layer "F.Fab")
			(effects
				(font
					(size 0.7 0.7)
					(thickness 0.15)
				)
				(justify left bottom)
			)
		)
		(fp_text user "${REFERENCE}"
			(at -0.95 3.168 0)
			(layer "F.Fab")
			(effects
				(font
					(size 0.7 0.7)
					(thickness 0.15)
				)
				(justify left bottom)
			)
		)
		(pad "1" smd roundrect
			(at -0.48 0)
			(size 0.59 0.64)
			(layers "F.Cu" "F.Mask" "F.Paste")
			(roundrect_rratio 0.25)
			(net 339 "/Ethernet/POE_ACTIVE")
			(pintype "passive")
		)
		(pad "2" smd roundrect
			(at 0.48 0)
			(size 0.59 0.64)
			(layers "F.Cu" "F.Mask" "F.Paste")
			(roundrect_rratio 0.25)
			(net 33 "/Ethernet/VDD")
			(pintype "passive")
		)
	)
	(footprint "antmicro-footprints:C_0402_1005Metric"
		(layer "F.Cu")
		(at 75.877962 122.8265)
		(descr "Capacitor SMD 0402")
		(tags "capacitor SMD 0402")
		(property "Reference" "C902"
			(at -1.97 2.25 90)
			(layer "F.SilkS")
			(effects
				(font
					(size 0.7 0.7)
					(thickness 0.15)
				)
				(justify left bottom)
			)
		)
		(property "Value" "C_100n_0402"
			(at -1.022927 2.155213 0)
			(layer "F.Fab")
			(effects
				(font
					(size 0.7 0.7)
					(thickness 0.15)
				)
				(justify left bottom)
			)
		)
		(property "Datasheet" "https://www.murata.com/products/productdetail?partno=GRM155R61H104KE14%23"
			(at 0 0 0)
			(layer "F.Fab")
			(hide yes)
			(effects
				(font
					(size 1.27 1.27)
					(thickness 0.15)
				)
			)
		)
		(property "MPN" "GRM155R61H104KE14D"
			(at 0 0 0)
			(unlocked yes)
			(layer "F.Fab")
			(hide yes)
			(effects
				(font
					(size 1 1)
					(thickness 0.15)
				)
			)
		)
		(property "Manufacturer" "Murata"
			(at 0 0 0)
			(unlocked yes)
			(layer "F.Fab")
			(hide yes)
			(effects
				(font
					(size 1 1)
					(thickness 0.15)
				)
			)
		)
		(property "License" "Apache-2.0"
			(at 0 0 0)
			(unlocked yes)
			(layer "F.Fab")
			(hide yes)
			(effects
				(font
					(size 1 1)
					(thickness 0.15)
				)
			)
		)
		(property "Author" "Antmicro"
			(at 0 0 0)
			(unlocked yes)
			(layer "F.Fab")
			(hide yes)
			(effects
				(font
					(size 1 1)
					(thickness 0.15)
				)
			)
		)
		(property "Val" "100n"
			(at 0 0 0)
			(unlocked yes)
			(layer "F.Fab")
			(hide yes)
			(effects
				(font
					(size 1 1)
					(thickness 0.15)
				)
			)
		)
		(property "Voltage" "50V"
			(at 0 0 0)
			(unlocked yes)
			(layer "F.Fab")
			(hide yes)
			(effects
				(font
					(size 1 1)
					(thickness 0.15)
				)
			)
		)
		(property "Dielectric" "X5R"
			(at 0 0 0)
			(unlocked yes)
			(layer "F.Fab")
			(hide yes)
			(effects
				(font
					(size 1 1)
					(thickness 0.15)
				)
			)
		)
		(sheetname "/USB/")
		(sheetfile "usb.kicad_sch")
		(attr smd)
		(fp_rect
			(start -0.925 -0.47)
			(end 0.925 0.47)
			(stroke
				(width 0.05)
				(type default)
			)
			(fill no)
			(layer "F.CrtYd")
		)
		(fp_line
			(start -0.494 -0.25)
			(end 0.504 -0.25)
			(stroke
				(width 0.15)
				(type solid)
			)
			(layer "F.Fab")
		)
		(fp_line
			(start -0.494 0.248)
			(end -0.494 -0.25)
			(stroke
				(width 0.15)
				(type solid)
			)
			(layer "F.Fab")
		)
		(fp_line
			(start 0.504 -0.25)
			(end 0.504 0.248)
			(stroke
				(width 0.15)
				(type solid)
			)
			(layer "F.Fab")
		)
		(fp_line
			(start 0.504 0.248)
			(end -0.494 0.248)
			(stroke
				(width 0.15)
				(type solid)
			)
			(layer "F.Fab")
		)
		(fp_text user "Author: Antmicro"
			(at -0.939 3.399 0)
			(layer "F.Fab")
			(effects
				(font
					(size 0.7 0.7)
					(thickness 0.15)
				)
				(justify left bottom)
			)
		)
		(fp_text user "${REFERENCE}"
			(at -0.939 4.599 0)
			(layer "F.Fab")
			(effects
				(font
					(size 0.7 0.7)
					(thickness 0.15)
				)
				(justify left bottom)
			)
		)
		(fp_text user "License: Apache-2.0"
			(at -0.939 5.799 0)
			(layer "F.Fab")
			(effects
				(font
					(size 0.7 0.7)
					(thickness 0.15)
				)
				(justify left bottom)
			)
		)
		(pad "1" smd roundrect
			(at -0.48 0)
			(size 0.59 0.64)
			(layers "F.Cu" "F.Mask" "F.Paste")
			(roundrect_rratio 0.25)
			(net 3 "GND")
			(pintype "passive")
		)
		(pad "2" smd roundrect
			(at 0.48 0)
			(size 0.59 0.64)
			(layers "F.Cu" "F.Mask" "F.Paste")
			(roundrect_rratio 0.25)
			(net 26 "/USB/USBD_VBUS")
			(pintype "passive")
		)
	)
	(footprint "antmicro-footprints:C_0402_1005Metric"
		(layer "F.Cu")
		(at 133.317962 123.7915)
		(descr "Capacitor SMD 0402")
		(tags "capacitor SMD 0402")
		(property "Reference" "C201"
			(at -1.2 8.105 0)
			(layer "F.SilkS")
			(effects
				(font
					(size 0.7 0.7)
					(thickness 0.15)
				)
				(justify left bottom)
			)
		)
		(property "Value" "C_100n_0402"
			(at -1.022927 2.155213 0)
			(layer "F.Fab")
			(effects
				(font
					(size 0.7 0.7)
					(thickness 0.15)
				)
				(justify left bottom)
			)
		)
		(property "Datasheet" "https://www.murata.com/products/productdetail?partno=GRM155R61H104KE14%23"
			(at 0 0 0)
			(layer "F.Fab")
			(hide yes)
			(effects
				(font
					(size 1.27 1.27)
					(thickness 0.15)
				)
			)
		)
		(property "Manufacturer" "Murata"
			(at 0 0 0)
			(unlocked yes)
			(layer "F.Fab")
			(hide yes)
			(effects
				(font
					(size 1 1)
					(thickness 0.15)
				)
			)
		)
		(property "MPN" "GRM155R61H104KE14D"
			(at 0 0 0)
			(unlocked yes)
			(layer "F.Fab")
			(hide yes)
			(effects
				(font
					(size 1 1)
					(thickness 0.15)
				)
			)
		)
		(property "Val" "100n"
			(at 0 0 0)
			(unlocked yes)
			(layer "F.Fab")
			(hide yes)
			(effects
				(font
					(size 1 1)
					(thickness 0.15)
				)
			)
		)
		(property "License" "Apache-2.0"
			(at 0 0 0)
			(unlocked yes)
			(layer "F.Fab")
			(hide yes)
			(effects
				(font
					(size 1 1)
					(thickness 0.15)
				)
			)
		)
		(property "Author" "Antmicro"
			(at 0 0 0)
			(unlocked yes)
			(layer "F.Fab")
			(hide yes)
			(effects
				(font
					(size 1 1)
					(thickness 0.15)
				)
			)
		)
		(property "Voltage" "50V"
			(at 0 0 0)
			(unlocked yes)
			(layer "F.Fab")
			(hide yes)
			(effects
				(font
					(size 1 1)
					(thickness 0.15)
				)
			)
		)
		(property "Dielectric" "X5R"
			(at 0 0 0)
			(unlocked yes)
			(layer "F.Fab")
			(hide yes)
			(effects
				(font
					(size 1 1)
					(thickness 0.15)
				)
			)
		)
		(sheetname "/Compute module/")
		(sheetfile "compute-module.kicad_sch")
		(attr smd)
		(fp_rect
			(start -0.925 -0.47)
			(end 0.925 0.47)
			(stroke
				(width 0.05)
				(type default)
			)
			(fill no)
			(layer "F.CrtYd")
		)
		(fp_line
			(start -0.494 -0.25)
			(end 0.504 -0.25)
			(stroke
				(width 0.15)
				(type solid)
			)
			(layer "F.Fab")
		)
		(fp_line
			(start -0.494 0.248)
			(end -0.494 -0.25)
			(stroke
				(width 0.15)
				(type solid)
			)
			(layer "F.Fab")
		)
		(fp_line
			(start 0.504 -0.25)
			(end 0.504 0.248)
			(stroke
				(width 0.15)
				(type solid)
			)
			(layer "F.Fab")
		)
		(fp_line
			(start 0.504 0.248)
			(end -0.494 0.248)
			(stroke
				(width 0.15)
				(type solid)
			)
			(layer "F.Fab")
		)
		(fp_text user "License: Apache-2.0"
			(at -0.939 5.799 0)
			(layer "F.Fab")
			(effects
				(font
					(size 0.7 0.7)
					(thickness 0.15)
				)
				(justify left bottom)
			)
		)
		(fp_text user "${REFERENCE}"
			(at -0.939 4.599 0)
			(layer "F.Fab")
			(effects
				(font
					(size 0.7 0.7)
					(thickness 0.15)
				)
				(justify left bottom)
			)
		)
		(fp_text user "Author: Antmicro"
			(at -0.939 3.399 0)
			(layer "F.Fab")
			(effects
				(font
					(size 0.7 0.7)
					(thickness 0.15)
				)
				(justify left bottom)
			)
		)
		(pad "1" smd roundrect
			(at -0.48 0)
			(size 0.59 0.64)
			(layers "F.Cu" "F.Mask" "F.Paste")
			(roundrect_rratio 0.25)
			(net 3 "GND")
			(pintype "passive")
		)
		(pad "2" smd roundrect
			(at 0.48 0)
			(size 0.59 0.64)
			(layers "F.Cu" "F.Mask" "F.Paste")
			(roundrect_rratio 0.25)
			(net 2 "Net-(D203-A)")
			(pintype "passive")
		)
	)
	(footprint "antmicro-footprints:LED_0603_1608Metric_G"
		(layer "F.Cu")
		(at 84.892962 120.7415 180)
		(descr "LED SMD 0603 Green")
		(tags "LED SMD 0603 Green")
		(property "Reference" "D906"
			(at -3.125 -1.4 0)
			(layer "F.SilkS")
			(effects
				(font
					(size 0.7 0.7)
					(thickness 0.15)
				)
				(justify right bottom)
			)
		)
		(property "Value" "LED_G_0603_KP-1608CGCK"
			(at -0.001 1.599 0)
			(layer "F.Fab")
			(effects
				(font
					(size 0.7 0.7)
					(thickness 0.15)
				)
				(justify right bottom)
			)
		)
		(property "Datasheet" "http://www.kingbright.com/attachments/file/psearch//000/00/00/KP-1608CGCK(Ver.23B).pdf"
			(at 0 0 180)
			(layer "F.Fab")
			(hide yes)
			(effects
				(font
					(size 1.27 1.27)
					(thickness 0.15)
				)
			)
		)
		(property "MPN" "KP-1608CGCK"
			(at 0 0 180)
			(unlocked yes)
			(layer "F.Fab")
			(hide yes)
			(effects
				(font
					(size 1 1)
					(thickness 0.15)
				)
			)
		)
		(property "Manufacturer" "Kingbright"
			(at 0 0 180)
			(unlocked yes)
			(layer "F.Fab")
			(hide yes)
			(effects
				(font
					(size 1 1)
					(thickness 0.15)
				)
			)
		)
		(property "Color" "Green"
			(at 0 0 180)
			(unlocked yes)
			(layer "F.Fab")
			(hide yes)
			(effects
				(font
					(size 1 1)
					(thickness 0.15)
				)
			)
		)
		(property "Author" "Antmicro"
			(at 0 0 180)
			(unlocked yes)
			(layer "F.Fab")
			(hide yes)
			(effects
				(font
					(size 1 1)
					(thickness 0.15)
				)
			)
		)
		(property "License" "Apache-2.0"
			(at 0 0 180)
			(unlocked yes)
			(layer "F.Fab")
			(hide yes)
			(effects
				(font
					(size 1 1)
					(thickness 0.15)
				)
			)
		)
		(sheetname "/USB/")
		(sheetfile "usb.kicad_sch")
		(attr smd)
		(fp_line
			(start 0.22 0.35)
			(end -0.22 0.35)
			(stroke
				(width 0.15)
				(type solid)
			)
			(layer "F.SilkS")
		)
		(fp_line
			(start 0.22 -0.35)
			(end -0.22 -0.35)
			(stroke
				(width 0.15)
				(type solid)
			)
			(layer "F.SilkS")
		)
		(fp_line
			(start 0.105328 0.201008)
			(end 0.105328 -0.198992)
			(stroke
				(width 0.1)
				(type solid)
			)
			(layer "F.SilkS")
		)
		(fp_line
			(start 0.105328 0.201008)
			(end -0.094672 0.001008)
			(stroke
				(width 0.1)
				(type solid)
			)
			(layer "F.SilkS")
		)
		(fp_line
			(start 0.105328 0.001008)
			(end 0.24 0.001)
			(stroke
				(width 0.1)
				(type solid)
			)
			(layer "F.SilkS")
		)
		(fp_line
			(start -0.094672 0.201008)
			(end -0.094672 -0.198992)
			(stroke
				(width 0.1)
				(type solid)
			)
			(layer "F.SilkS")
		)
		(fp_line
			(start -0.094672 0.001008)
			(end 0.105328 -0.198992)
			(stroke
				(width 0.1)
				(type solid)
			)
			(layer "F.SilkS")
		)
		(fp_line
			(start -0.094672 0.001008)
			(end -0.24 0.001008)
			(stroke
				(width 0.1)
				(type solid)
			)
			(layer "F.SilkS")
		)
		(fp_line
			(start -1.18 -0.319)
			(end -1.18 0.321)
			(stroke
				(width 0.15)
				(type solid)
			)
			(layer "F.SilkS")
		)
		(fp_rect
			(start 1.25 0.65)
			(end -1.25 -0.65)
			(stroke
				(width 0.05)
				(type solid)
			)
			(fill no)
			(layer "F.CrtYd")
		)
		(fp_line
			(start 0.599 0)
			(end 0.201 0)
			(stroke
				(width 0.15)
				(type solid)
			)
			(layer "F.Fab")
		)
		(fp_line
			(start 0.201 0.2)
			(end 0.201 0)
			(stroke
				(width 0.15)
				(type solid)
			)
			(layer "F.Fab")
		)
		(fp_line
			(start 0.201 0)
			(end 0.201 -0.202)
			(stroke
				(width 0.15)
				(type solid)
			)
			(layer "F.Fab")
		)
		(fp_line
			(start 0.201 -0.202)
			(end -0.101 0)
			(stroke
				(width 0.15)
				(type solid)
			)
			(layer "F.Fab")
		)
		(fp_line
			(start -0.101 0)
			(end 0.201 0.2)
			(stroke
				(width 0.15)
				(type solid)
			)
			(layer "F.Fab")
		)
		(fp_line
			(start -0.199 0.2)
			(end -0.199 0.1)
			(stroke
				(width 0.15)
				(type solid)
			)
			(layer "F.Fab")
		)
		(fp_line
			(start -0.199 0)
			(end -0.597 0)
			(stroke
				(width 0.15)
				(type solid)
			)
			(layer "F.Fab")
		)
		(fp_line
			(start -0.199 -0.202)
			(end -0.199 0.1)
			(stroke
				(width 0.15)
				(type solid)
			)
			(layer "F.Fab")
		)
		(fp_rect
			(start 0.848 0.4)
			(end -0.85 -0.402)
			(stroke
				(width 0.15)
				(type solid)
			)
			(fill no)
			(layer "F.Fab")
		)
		(fp_text user "Author: Antmicro"
			(at -1.4224 4.799 180)
			(layer "F.Fab")
			(effects
				(font
					(size 0.7 0.7)
					(thickness 0.15)
				)
				(justify left bottom)
			)
		)
		(fp_text user "${REFERENCE}"
			(at -1.4224 5.999 180)
			(layer "F.Fab")
			(effects
				(font
					(size 0.7 0.7)
					(thickness 0.15)
				)
				(justify left bottom)
			)
		)
		(fp_text user "License: Apache-2.0"
			(at -1.4224 3.599 180)
			(layer "F.Fab")
			(effects
				(font
					(size 0.7 0.7)
					(thickness 0.15)
				)
				(justify left bottom)
			)
		)
		(pad "1" smd roundrect
			(at -0.7 0)
			(size 0.8 1)
			(layers "F.Cu" "F.Mask" "F.Paste")
			(roundrect_rratio 0.2)
			(net 498 "Net-(D906-C)")
			(pinfunction "C")
			(pintype "passive")
		)
		(pad "2" smd roundrect
			(at 0.7 0)
			(size 0.8 1)
			(layers "F.Cu" "F.Mask" "F.Paste")
			(roundrect_rratio 0.2)
			(net 483 "Net-(D906-A)")
			(pinfunction "A")
			(pintype "passive")
		)
	)
	(footprint "antmicro-footprints:R_0402_1005Metric"
		(layer "F.Cu")
		(at 84.392962 154.8915 180)
		(descr "Resistor SMD 0402")
		(tags "resistor SMD 0402")
		(property "Reference" "R261"
			(at -3.615 -0.46 0)
			(layer "F.SilkS")
			(effects
				(font
					(size 0.7 0.7)
					(thickness 0.15)
				)
				(justify right bottom)
			)
		)
		(property "Value" "R_100k_0402"
			(at -1.011843 1.772047 0)
			(layer "F.Fab")
			(effects
				(font
					(size 0.7 0.7)
					(thickness 0.15)
				)
				(justify right bottom)
			)
		)
		(property "Datasheet" "https://www.bourns.com/docs/product-datasheets/cr.pdf"
			(at 0 0 180)
			(layer "F.Fab")
			(hide yes)
			(effects
				(font
					(size 1.27 1.27)
					(thickness 0.15)
				)
			)
		)
		(property "MPN" "CR0402-FX-1003GLF"
			(at 0 0 180)
			(unlocked yes)
			(layer "F.Fab")
			(hide yes)
			(effects
				(font
					(size 1 1)
					(thickness 0.15)
				)
			)
		)
		(property "Manufacturer" "Bourns"
			(at 0 0 180)
			(unlocked yes)
			(layer "F.Fab")
			(hide yes)
			(effects
				(font
					(size 1 1)
					(thickness 0.15)
				)
			)
		)
		(property "License" "Apache-2.0"
			(at 0 0 180)
			(unlocked yes)
			(layer "F.Fab")
			(hide yes)
			(effects
				(font
					(size 1 1)
					(thickness 0.15)
				)
			)
		)
		(property "Author" "Antmicro"
			(at 0 0 180)
			(unlocked yes)
			(layer "F.Fab")
			(hide yes)
			(effects
				(font
					(size 1 1)
					(thickness 0.15)
				)
			)
		)
		(property "Val" "100k"
			(at 0 0 180)
			(unlocked yes)
			(layer "F.Fab")
			(hide yes)
			(effects
				(font
					(size 1 1)
					(thickness 0.15)
				)
			)
		)
		(property "Tolerance" "1%"
			(at 0 0 180)
			(unlocked yes)
			(layer "F.Fab")
			(hide yes)
			(effects
				(font
					(size 1 1)
					(thickness 0.15)
				)
			)
		)
		(sheetname "/Compute module/")
		(sheetfile "compute-module.kicad_sch")
		(attr smd)
		(fp_rect
			(start -0.925 -0.47)
			(end 0.925 0.47)
			(stroke
				(width 0.05)
				(type default)
			)
			(fill no)
			(layer "F.CrtYd")
		)
		(fp_rect
			(start -0.5 -0.25)
			(end 0.5 0.25)
			(stroke
				(width 0.15)
				(type solid)
			)
			(fill no)
			(layer "F.Fab")
		)
		(fp_text user "Author: Antmicro"
			(at -0.95 4.169 180)
			(layer "F.Fab")
			(effects
				(font
					(size 0.7 0.7)
					(thickness 0.15)
				)
				(justify left bottom)
			)
		)
		(fp_text user "License: Apache-2.0"
			(at -0.95 5.169 180)
			(layer "F.Fab")
			(effects
				(font
					(size 0.7 0.7)
					(thickness 0.15)
				)
				(justify left bottom)
			)
		)
		(fp_text user "${REFERENCE}"
			(at -0.95 3.168 180)
			(layer "F.Fab")
			(effects
				(font
					(size 0.7 0.7)
					(thickness 0.15)
				)
				(justify left bottom)
			)
		)
		(pad "1" smd roundrect
			(at -0.48 0 180)
			(size 0.59 0.64)
			(layers "F.Cu" "F.Mask" "F.Paste")
			(roundrect_rratio 0.25)
			(net 444 "Net-(Q211-D)")
			(pintype "passive")
		)
		(pad "2" smd roundrect
			(at 0.48 0 180)
			(size 0.59 0.64)
			(layers "F.Cu" "F.Mask" "F.Paste")
			(roundrect_rratio 0.25)
			(net 24 "/Compute module/USBA_VBUS")
			(pintype "passive")
		)
	)
	(footprint "antmicro-footprints:Nexperia_DFN-10_2.5x1mm_P0.5mm"
		(layer "F.Cu")
		(at 142.292962 147.3665 90)
		(property "Reference" "D802"
			(at -7.17 0.305 90)
			(layer "F.SilkS")
			(effects
				(font
					(size 0.7 0.7)
					(thickness 0.15)
				)
				(justify left bottom)
			)
		)
		(property "Value" "PUSB3F96X_PASS"
			(at -0.016 1.705 90)
			(layer "F.Fab")
			(effects
				(font
					(size 0.7 0.7)
					(thickness 0.15)
				)
				(justify left bottom)
			)
		)
		(property "Datasheet" "https://mouser.com/datasheet/2/916/PUSB3F96-1600324.pdf"
			(at 0 0 90)
			(layer "F.Fab")
			(hide yes)
			(effects
				(font
					(size 1.27 1.27)
					(thickness 0.15)
				)
			)
		)
		(property "Manufacturer" "Nexperia"
			(at 0 0 90)
			(unlocked yes)
			(layer "F.Fab")
			(hide yes)
			(effects
				(font
					(size 1 1)
					(thickness 0.15)
				)
			)
		)
		(property "MPN" "PUSB3F96X"
			(at 0 0 90)
			(unlocked yes)
			(layer "F.Fab")
			(hide yes)
			(effects
				(font
					(size 1 1)
					(thickness 0.15)
				)
			)
		)
		(property "Author" "Antmicro"
			(at 0 0 90)
			(unlocked yes)
			(layer "F.Fab")
			(hide yes)
			(effects
				(font
					(size 1 1)
					(thickness 0.15)
				)
			)
		)
		(property "License" "Apache-2.0"
			(at 0 0 90)
			(unlocked yes)
			(layer "F.Fab")
			(hide yes)
			(effects
				(font
					(size 1 1)
					(thickness 0.15)
				)
			)
		)
		(sheetname "/Peripherals/")
		(sheetfile "peripherals.kicad_sch")
		(attr smd)
		(fp_line
			(start -1.375 -0.4)
			(end -1.375 0.4)
			(stroke
				(width 0.15)
				(type solid)
			)
			(layer "F.SilkS")
		)
		(fp_line
			(start 1.375 0.4)
			(end 1.375 -0.4)
			(stroke
				(width 0.15)
				(type solid)
			)
			(layer "F.SilkS")
		)
		(fp_circle
			(center -1.4 0.7)
			(end -1.349 0.7)
			(stroke
				(width 0.15)
				(type solid)
			)
			(fill yes)
			(layer "F.SilkS")
		)
		(fp_rect
			(start -1.4 -0.725)
			(end 1.4 0.725)
			(stroke
				(width 0.05)
				(type solid)
			)
			(fill no)
			(layer "F.CrtYd")
		)
		(fp_line
			(start 1.25 -0.5)
			(end -1.25 -0.5)
			(stroke
				(width 0.15)
				(type solid)
			)
			(layer "F.Fab")
		)
		(fp_line
			(start -1.25 -0.5)
			(end -1.25 0.15)
			(stroke
				(width 0.15)
				(type solid)
			)
			(layer "F.Fab")
		)
		(fp_line
			(start -1.25 0.15)
			(end -0.9 0.5)
			(stroke
				(width 0.15)
				(type solid)
			)
			(layer "F.Fab")
		)
		(fp_line
			(start 1.25 0.5)
			(end 1.25 -0.5)
			(stroke
				(width 0.15)
				(type solid)
			)
			(layer "F.Fab")
		)
		(fp_line
			(start -0.9 0.5)
			(end 1.25 0.5)
			(stroke
				(width 0.15)
				(type solid)
			)
			(layer "F.Fab")
		)
		(fp_text user "Author: Antmicro"
			(at -1.367 4.905 90)
			(layer "F.Fab")
			(effects
				(font
					(size 0.7 0.7)
					(thickness 0.15)
				)
				(justify left bottom)
			)
		)
		(fp_text user "License: Apache-2.0"
			(at -1.367 6.105 90)
			(layer "F.Fab")
			(effects
				(font
					(size 0.7 0.7)
					(thickness 0.15)
				)
				(justify left bottom)
			)
		)
		(fp_text user "${REFERENCE}"
			(at -1.367 3.704 90)
			(layer "F.Fab")
			(effects
				(font
					(size 0.7 0.7)
					(thickness 0.15)
				)
				(justify left bottom)
			)
		)
		(pad "1" smd rect
			(at -1 0.3875 90)
			(size 0.2 0.475)
			(layers "F.Cu" "F.Mask" "F.Paste")
			(net 238 "/Compute module/GPIO.17")
			(pinfunction "CH1")
			(pintype "passive")
			(solder_mask_margin 0.05)
		)
		(pad "2" smd rect
			(at -0.5 0.3875 90)
			(size 0.2 0.475)
			(layers "F.Cu" "F.Mask" "F.Paste")
			(net 236 "/Compute module/GPIO.27")
			(pinfunction "CH2")
			(pintype "passive")
			(solder_mask_margin 0.05)
		)
		(pad "3" smd rect
			(at 0 0.3875 90)
			(size 0.2 0.475)
			(layers "F.Cu" "F.Mask" "F.Paste")
			(net 3 "GND")
			(pinfunction "GND")
			(pintype "passive")
			(solder_mask_margin 0.05)
		)
		(pad "4" smd rect
			(at 0.5 0.3875 90)
			(size 0.2 0.475)
			(layers "F.Cu" "F.Mask" "F.Paste")
			(net 234 "/Compute module/GPIO.22")
			(pinfunction "CH3")
			(pintype "passive")
			(solder_mask_margin 0.05)
		)
		(pad "5" smd rect
			(at 1 0.3875 90)
			(size 0.2 0.475)
			(layers "F.Cu" "F.Mask" "F.Paste")
			(net 232 "/Compute module/GPIO.10")
			(pinfunction "CH4")
			(pintype "passive")
			(solder_mask_margin 0.05)
		)
		(pad "6" smd rect
			(at 1 -0.3875 90)
			(size 0.2 0.475)
			(layers "F.Cu" "F.Mask" "F.Paste")
			(net 232 "/Compute module/GPIO.10")
			(pinfunction "CH4")
			(pintype "passive")
			(solder_mask_margin 0.05)
		)
		(pad "7" smd rect
			(at 0.5 -0.3875 90)
			(size 0.2 0.475)
			(layers "F.Cu" "F.Mask" "F.Paste")
			(net 234 "/Compute module/GPIO.22")
			(pinfunction "CH3")
			(pintype "passive")
			(solder_mask_margin 0.05)
		)
		(pad "8" smd rect
			(at 0 -0.3875 90)
			(size 0.2 0.475)
			(layers "F.Cu" "F.Mask" "F.Paste")
			(net 3 "GND")
			(pinfunction "GND")
			(pintype "passive")
			(solder_mask_margin 0.05)
		)
		(pad "9" smd rect
			(at -0.501 -0.3875 90)
			(size 0.2 0.475)
			(layers "F.Cu" "F.Mask" "F.Paste")
			(net 236 "/Compute module/GPIO.27")
			(pinfunction "CH2")
			(pintype "passive")
			(solder_mask_margin 0.05)
		)
		(pad "10" smd rect
			(at -1 -0.3875 90)
			(size 0.2 0.475)
			(layers "F.Cu" "F.Mask" "F.Paste")
			(net 238 "/Compute module/GPIO.17")
			(pinfunction "CH1")
			(pintype "passive")
			(solder_mask_margin 0.05)
		)
	)
	(footprint "antmicro-footprints:R_0402_1005Metric"
		(layer "F.Cu")
		(at 120.3 157.0415 180)
		(descr "Resistor SMD 0402")
		(tags "resistor SMD 0402")
		(property "Reference" "R222"
			(at -4.3 -0.175 180)
			(layer "F.SilkS")
			(effects
				(font
					(size 0.7 0.7)
					(thickness 0.15)
				)
				(justify left bottom)
			)
		)
		(property "Value" "R_0R_0402"
			(at -1.011843 1.772047 180)
			(layer "F.Fab")
			(effects
				(font
					(size 0.7 0.7)
					(thickness 0.15)
				)
				(justify left bottom)
			)
		)
		(property "Datasheet" "https://industrial.panasonic.com/cdbs/www-data/pdf/RDA0000/AOA0000C301.pdf"
			(at 0 0 180)
			(layer "F.Fab")
			(hide yes)
			(effects
				(font
					(size 1.27 1.27)
					(thickness 0.15)
				)
			)
		)
		(property "Manufacturer" "Panasonic"
			(at 0 0 180)
			(unlocked yes)
			(layer "F.Fab")
			(hide yes)
			(effects
				(font
					(size 1 1)
					(thickness 0.15)
				)
			)
		)
		(property "MPN" "ERJ2GE0R00X"
			(at 0 0 180)
			(unlocked yes)
			(layer "F.Fab")
			(hide yes)
			(effects
				(font
					(size 1 1)
					(thickness 0.15)
				)
			)
		)
		(property "Val" "0R"
			(at 0 0 180)
			(unlocked yes)
			(layer "F.Fab")
			(hide yes)
			(effects
				(font
					(size 1 1)
					(thickness 0.15)
				)
			)
		)
		(property "License" "Apache-2.0"
			(at 0 0 180)
			(unlocked yes)
			(layer "F.Fab")
			(hide yes)
			(effects
				(font
					(size 1 1)
					(thickness 0.15)
				)
			)
		)
		(property "Author" "Antmicro"
			(at 0 0 180)
			(unlocked yes)
			(layer "F.Fab")
			(hide yes)
			(effects
				(font
					(size 1 1)
					(thickness 0.15)
				)
			)
		)
		(property "Tolerance" "~"
			(at 0 0 180)
			(unlocked yes)
			(layer "F.Fab")
			(hide yes)
			(effects
				(font
					(size 1 1)
					(thickness 0.15)
				)
			)
		)
		(property "Current" "1A"
			(at 0 0 180)
			(unlocked yes)
			(layer "F.Fab")
			(hide yes)
			(effects
				(font
					(size 1 1)
					(thickness 0.15)
				)
			)
		)
		(sheetname "/Compute module/")
		(sheetfile "compute-module.kicad_sch")
		(attr smd)
		(fp_rect
			(start -0.925 -0.47)
			(end 0.925 0.47)
			(stroke
				(width 0.05)
				(type default)
			)
			(fill no)
			(layer "F.CrtYd")
		)
		(fp_rect
			(start -0.5 -0.25)
			(end 0.5 0.25)
			(stroke
				(width 0.15)
				(type solid)
			)
			(fill no)
			(layer "F.Fab")
		)
		(fp_text user "License: Apache-2.0"
			(at -0.95 5.169 180)
			(layer "F.Fab")
			(effects
				(font
					(size 0.7 0.7)
					(thickness 0.15)
				)
				(justify left bottom)
			)
		)
		(fp_text user "Author: Antmicro"
			(at -0.95 4.169 180)
			(layer "F.Fab")
			(effects
				(font
					(size 0.7 0.7)
					(thickness 0.15)
				)
				(justify left bottom)
			)
		)
		(fp_text user "${REFERENCE}"
			(at -0.95 3.168 180)
			(layer "F.Fab")
			(effects
				(font
					(size 0.7 0.7)
					(thickness 0.15)
				)
				(justify left bottom)
			)
		)
		(pad "1" smd roundrect
			(at -0.48 0 180)
			(size 0.59 0.64)
			(layers "F.Cu" "F.Mask" "F.Paste")
			(roundrect_rratio 0.25)
			(net 159 "/Compute module/NVMe.RX3_P")
			(pintype "passive")
		)
		(pad "2" smd roundrect
			(at 0.48 0 180)
			(size 0.59 0.64)
			(layers "F.Cu" "F.Mask" "F.Paste")
			(roundrect_rratio 0.25)
			(net 154 "/Compute module/R3_P")
			(pintype "passive")
		)
	)
	(footprint "antmicro-footprints:R_0402_1005Metric"
		(layer "F.Cu")
		(at 142.727962 126.4565 180)
		(descr "Resistor SMD 0402")
		(tags "resistor SMD 0402")
		(property "Reference" "R211"
			(at -1.07 -0.37 90)
			(layer "F.SilkS")
			(effects
				(font
					(size 0.7 0.7)
					(thickness 0.15)
				)
				(justify right bottom)
			)
		)
		(property "Value" "R_470R_0402"
			(at -1.011843 1.772047 0)
			(layer "F.Fab")
			(effects
				(font
					(size 0.7 0.7)
					(thickness 0.15)
				)
				(justify right bottom)
			)
		)
		(property "Datasheet" "https://www.bourns.com/docs/product-datasheets/cr.pdf"
			(at 0 0 180)
			(layer "F.Fab")
			(hide yes)
			(effects
				(font
					(size 1.27 1.27)
					(thickness 0.15)
				)
			)
		)
		(property "Manufacturer" "Bourns"
			(at 0 0 180)
			(unlocked yes)
			(layer "F.Fab")
			(hide yes)
			(effects
				(font
					(size 1 1)
					(thickness 0.15)
				)
			)
		)
		(property "MPN" "CR0402-FX-4700GLF"
			(at 0 0 180)
			(unlocked yes)
			(layer "F.Fab")
			(hide yes)
			(effects
				(font
					(size 1 1)
					(thickness 0.15)
				)
			)
		)
		(property "Val" "470R"
			(at 0 0 180)
			(unlocked yes)
			(layer "F.Fab")
			(hide yes)
			(effects
				(font
					(size 1 1)
					(thickness 0.15)
				)
			)
		)
		(property "License" "Apache-2.0"
			(at 0 0 180)
			(unlocked yes)
			(layer "F.Fab")
			(hide yes)
			(effects
				(font
					(size 1 1)
					(thickness 0.15)
				)
			)
		)
		(property "Author" "Antmicro"
			(at 0 0 180)
			(unlocked yes)
			(layer "F.Fab")
			(hide yes)
			(effects
				(font
					(size 1 1)
					(thickness 0.15)
				)
			)
		)
		(property "Tolerance" "1%"
			(at 0 0 180)
			(unlocked yes)
			(layer "F.Fab")
			(hide yes)
			(effects
				(font
					(size 1 1)
					(thickness 0.15)
				)
			)
		)
		(sheetname "/Compute module/")
		(sheetfile "compute-module.kicad_sch")
		(attr smd)
		(fp_rect
			(start -0.925 -0.47)
			(end 0.925 0.47)
			(stroke
				(width 0.05)
				(type default)
			)
			(fill no)
			(layer "F.CrtYd")
		)
		(fp_rect
			(start -0.5 -0.25)
			(end 0.5 0.25)
			(stroke
				(width 0.15)
				(type solid)
			)
			(fill no)
			(layer "F.Fab")
		)
		(fp_text user "${REFERENCE}"
			(at -0.95 3.168 180)
			(layer "F.Fab")
			(effects
				(font
					(size 0.7 0.7)
					(thickness 0.15)
				)
				(justify left bottom)
			)
		)
		(fp_text user "Author: Antmicro"
			(at -0.95 4.169 180)
			(layer "F.Fab")
			(effects
				(font
					(size 0.7 0.7)
					(thickness 0.15)
				)
				(justify left bottom)
			)
		)
		(fp_text user "License: Apache-2.0"
			(at -0.95 5.169 180)
			(layer "F.Fab")
			(effects
				(font
					(size 0.7 0.7)
					(thickness 0.15)
				)
				(justify left bottom)
			)
		)
		(pad "1" smd roundrect
			(at -0.48 0 180)
			(size 0.59 0.64)
			(layers "F.Cu" "F.Mask" "F.Paste")
			(roundrect_rratio 0.25)
			(net 342 "Net-(R211-Pad1)")
			(pintype "passive")
		)
		(pad "2" smd roundrect
			(at 0.48 0 180)
			(size 0.59 0.64)
			(layers "F.Cu" "F.Mask" "F.Paste")
			(roundrect_rratio 0.25)
			(net 329 "Net-(Q207-G)")
			(pintype "passive")
		)
	)
	(footprint "antmicro-footprints:Choke_Murata-DLW21"
		(layer "F.Cu")
		(at 93.518962 124.153999 -90)
		(property "Reference" "T901"
			(at -2.21957 1.012162 90)
			(layer "F.SilkS")
			(effects
				(font
					(size 0.7 0.7)
					(thickness 0.15)
				)
				(justify right bottom)
			)
		)
		(property "Value" "Choke_DLW21SN900SQ2L"
			(at 0.4 1.778 90)
			(layer "F.Fab")
			(effects
				(font
					(size 0.7 0.7)
					(thickness 0.15)
				)
				(justify right bottom)
			)
		)
		(property "Datasheet" "https://www.murata.com/en-us/products/productdetail?partno=DLW21SN900SQ2%23"
			(at 0 0 270)
			(layer "F.Fab")
			(hide yes)
			(effects
				(font
					(size 1.27 1.27)
					(thickness 0.15)
				)
			)
		)
		(property "Manufacturer" "Murata"
			(at 0 0 270)
			(unlocked yes)
			(layer "F.Fab")
			(hide yes)
			(effects
				(font
					(size 1 1)
					(thickness 0.15)
				)
			)
		)
		(property "MPN" "DLW21SN900SQ2L"
			(at 0 0 270)
			(unlocked yes)
			(layer "F.Fab")
			(hide yes)
			(effects
				(font
					(size 1 1)
					(thickness 0.15)
				)
			)
		)
		(property "IMax" "0.33 A"
			(at 0 0 270)
			(unlocked yes)
			(layer "F.Fab")
			(hide yes)
			(effects
				(font
					(size 1 1)
					(thickness 0.15)
				)
			)
		)
		(property "Author" "Antmicro"
			(at 0 0 270)
			(unlocked yes)
			(layer "F.Fab")
			(hide yes)
			(effects
				(font
					(size 1 1)
					(thickness 0.15)
				)
			)
		)
		(property "License" "Apache-2.0"
			(at 0 0 270)
			(unlocked yes)
			(layer "F.Fab")
			(hide yes)
			(effects
				(font
					(size 1 1)
					(thickness 0.15)
				)
			)
		)
		(property ki_fp_filters "IND_ACM9070_TDK")
		(sheetname "/USB/")
		(sheetfile "usb.kicad_sch")
		(attr smd)
		(fp_line
			(start 1 0.8)
			(end -1 0.8)
			(stroke
				(width 0.15)
				(type solid)
			)
			(layer "F.SilkS")
		)
		(fp_line
			(start -1 -0.8)
			(end 1 -0.8)
			(stroke
				(width 0.15)
				(type solid)
			)
			(layer "F.SilkS")
		)
		(fp_circle
			(center -1.475 0.775)
			(end -1.425 0.775)
			(stroke
				(width 0.15)
				(type solid)
			)
			(fill yes)
			(layer "F.SilkS")
		)
		(fp_rect
			(start -1.55 -0.85)
			(end 1.55 0.85)
			(stroke
				(width 0.05)
				(type solid)
			)
			(fill no)
			(layer "F.CrtYd")
		)
		(fp_line
			(start -1 0.35)
			(end -0.75 0.6)
			(stroke
				(width 0.15)
				(type solid)
			)
			(layer "F.Fab")
		)
		(fp_rect
			(start -1 -0.6)
			(end 1 0.6)
			(stroke
				(width 0.15)
				(type solid)
			)
			(fill no)
			(layer "F.Fab")
		)
		(fp_text user "License: Apache-2.0"
			(at -1.55 6.178 270)
			(layer "F.Fab")
			(effects
				(font
					(size 0.7 0.7)
					(thickness 0.15)
				)
				(justify left bottom)
			)
		)
		(fp_text user "Author: Antmicro"
			(at -1.55 4.978 270)
			(layer "F.Fab")
			(effects
				(font
					(size 0.7 0.7)
					(thickness 0.15)
				)
				(justify left bottom)
			)
		)
		(fp_text user "${REFERENCE}"
			(at -1.55 3.778 270)
			(layer "F.Fab")
			(effects
				(font
					(size 0.7 0.7)
					(thickness 0.15)
				)
				(justify left bottom)
			)
		)
		(pad "1" smd roundrect
			(at -0.85 0.4 270)
			(size 0.9 0.4)
			(layers "F.Cu" "F.Mask" "F.Paste")
			(roundrect_rratio 0.1)
			(net 205 "/USB/AD_P")
			(pinfunction "1")
			(pintype "passive")
		)
		(pad "2" smd roundrect
			(at 0.85 0.4 270)
			(size 0.9 0.4)
			(layers "F.Cu" "F.Mask" "F.Paste")
			(roundrect_rratio 0.1)
			(net 39 "/Compute module/USB.D_P")
			(pinfunction "2")
			(pintype "passive")
		)
		(pad "3" smd roundrect
			(at 0.85 -0.4 270)
			(size 0.9 0.4)
			(layers "F.Cu" "F.Mask" "F.Paste")
			(roundrect_rratio 0.1)
			(net 38 "/Compute module/USB.D_N")
			(pinfunction "3")
			(pintype "passive")
		)
		(pad "4" smd roundrect
			(at -0.85 -0.4 270)
			(size 0.9 0.4)
			(layers "F.Cu" "F.Mask" "F.Paste")
			(roundrect_rratio 0.1)
			(net 206 "/USB/AD_N")
			(pinfunction "4")
			(pintype "passive")
		)
	)
	(footprint "antmicro-footprints:SOT-523"
		(layer "F.Cu")
		(at 79.792962 169.8415 90)
		(property "Reference" "Q208"
			(at -1.6985 1.657038 180)
			(layer "F.SilkS")
			(effects
				(font
					(size 0.7 0.7)
					(thickness 0.15)
				)
				(justify left bottom)
			)
		)
		(property "Value" "PJE138K"
			(at 0.1 1.824 90)
			(layer "F.Fab")
			(effects
				(font
					(size 0.7 0.7)
					(thickness 0.15)
				)
				(justify left bottom)
			)
		)
		(property "Datasheet" "https://www.mouser.com/datasheet/2/1057/PJE138K-1876698.pdf"
			(at 0 0 90)
			(layer "F.Fab")
			(hide yes)
			(effects
				(font
					(size 1.27 1.27)
					(thickness 0.15)
				)
			)
		)
		(property "MPN" "PJE138K_R1_00001"
			(at 0 0 90)
			(unlocked yes)
			(layer "F.Fab")
			(hide yes)
			(effects
				(font
					(size 1 1)
					(thickness 0.15)
				)
			)
		)
		(property "Manufacturer" "PANJIT"
			(at 0 0 90)
			(unlocked yes)
			(layer "F.Fab")
			(hide yes)
			(effects
				(font
					(size 1 1)
					(thickness 0.15)
				)
			)
		)
		(property "Author" "Antmicro"
			(at 0 0 90)
			(unlocked yes)
			(layer "F.Fab")
			(hide yes)
			(effects
				(font
					(size 1 1)
					(thickness 0.15)
				)
			)
		)
		(property "License" "Apache-2.0"
			(at 0 0 90)
			(unlocked yes)
			(layer "F.Fab")
			(hide yes)
			(effects
				(font
					(size 1 1)
					(thickness 0.15)
				)
			)
		)
		(sheetname "/Compute module/")
		(sheetfile "compute-module.kicad_sch")
		(attr smd)
		(fp_line
			(start -0.277 -0.551)
			(end -0.277 -0.75)
			(stroke
				(width 0.15)
				(type solid)
			)
			(layer "F.SilkS")
		)
		(fp_line
			(start -0.725 -0.551)
			(end -0.277 -0.551)
			(stroke
				(width 0.15)
				(type solid)
			)
			(layer "F.SilkS")
		)
		(fp_line
			(start -0.927 -0.351)
			(end -0.725 -0.551)
			(stroke
				(width 0.15)
				(type solid)
			)
			(layer "F.SilkS")
		)
		(fp_line
			(start -0.927 -0.051)
			(end -0.927 -0.351)
			(stroke
				(width 0.15)
				(type solid)
			)
			(layer "F.SilkS")
		)
		(fp_circle
			(center -0.9652 0.9652)
			(end -0.9152 0.9652)
			(stroke
				(width 0.15)
				(type solid)
			)
			(fill yes)
			(layer "F.SilkS")
		)
		(fp_line
			(start 1.1 -1.16)
			(end 1.1 1.15)
			(stroke
				(width 0.05)
				(type solid)
			)
			(layer "F.CrtYd")
		)
		(fp_line
			(start -1.12 -1.16)
			(end 1.1 -1.16)
			(stroke
				(width 0.05)
				(type solid)
			)
			(layer "F.CrtYd")
		)
		(fp_line
			(start -1.12 -1.16)
			(end -1.12 1.15)
			(stroke
				(width 0.05)
				(type solid)
			)
			(layer "F.CrtYd")
		)
		(fp_line
			(start -1.12 1.15)
			(end 1.1 1.15)
			(stroke
				(width 0.05)
				(type solid)
			)
			(layer "F.CrtYd")
		)
		(fp_line
			(start 0.8 -0.425)
			(end -0.652 -0.425)
			(stroke
				(width 0.15)
				(type solid)
			)
			(layer "F.Fab")
		)
		(fp_line
			(start 0.8 -0.425)
			(end 0.8 0.424)
			(stroke
				(width 0.15)
				(type solid)
			)
			(layer "F.Fab")
		)
		(fp_line
			(start -0.652 -0.425)
			(end -0.802 -0.276)
			(stroke
				(width 0.15)
				(type solid)
			)
			(layer "F.Fab")
		)
		(fp_line
			(start -0.802 -0.276)
			(end -0.802 0.424)
			(stroke
				(width 0.15)
				(type solid)
			)
			(layer "F.Fab")
		)
		(fp_line
			(start 0.8 0.424)
			(end -0.802 0.424)
			(stroke
				(width 0.15)
				(type solid)
			)
			(layer "F.Fab")
		)
		(fp_circle
			(center -0.9652 0.9652)
			(end -0.9144 0.9652)
			(stroke
				(width 0.15)
				(type solid)
			)
			(fill no)
			(layer "F.Fab")
		)
		(fp_text user "${REFERENCE}"
			(at -1.12 3.824 90)
			(layer "F.Fab")
			(effects
				(font
					(size 0.7 0.7)
					(thickness 0.15)
				)
				(justify left bottom)
			)
		)
		(fp_text user "License: Apache-2.0"
			(at -1.12 5.024 90)
			(layer "F.Fab")
			(effects
				(font
					(size 0.7 0.7)
					(thickness 0.15)
				)
				(justify left bottom)
			)
		)
		(fp_text user "Author: Antmicro"
			(at -1.12 6.224 90)
			(layer "F.Fab")
			(effects
				(font
					(size 0.7 0.7)
					(thickness 0.15)
				)
				(justify left bottom)
			)
		)
		(pad "1" smd rect
			(at -0.5 0.65 90)
			(size 0.4 0.51)
			(layers "F.Cu" "F.Mask" "F.Paste")
			(net 2 "Net-(D203-A)")
			(pinfunction "G")
			(pintype "input")
		)
		(pad "2" smd rect
			(at 0.498 0.65 90)
			(size 0.4 0.51)
			(layers "F.Cu" "F.Mask" "F.Paste")
			(net 3 "GND")
			(pinfunction "S")
			(pintype "passive")
		)
		(pad "3" smd rect
			(at 0 -0.652 90)
			(size 0.4 0.51)
			(layers "F.Cu" "F.Mask" "F.Paste")
			(net 255 "/Compute module/~{RPi_RST}")
			(pinfunction "D")
			(pintype "passive")
		)
	)
	(footprint "antmicro-footprints:R_0402_1005Metric"
		(layer "F.Cu")
		(at 116.477962 138.2665 90)
		(descr "Resistor SMD 0402")
		(tags "resistor SMD 0402")
		(property "Reference" "R326"
			(at -3.72 0.37 90)
			(layer "F.SilkS")
			(effects
				(font
					(size 0.7 0.7)
					(thickness 0.15)
				)
				(justify left bottom)
			)
		)
		(property "Value" "R_470R_0402"
			(at -1.011843 1.772047 90)
			(layer "F.Fab")
			(effects
				(font
					(size 0.7 0.7)
					(thickness 0.15)
				)
				(justify left bottom)
			)
		)
		(property "Datasheet" "https://www.bourns.com/docs/product-datasheets/cr.pdf"
			(at 0 0 90)
			(layer "F.Fab")
			(hide yes)
			(effects
				(font
					(size 1.27 1.27)
					(thickness 0.15)
				)
			)
		)
		(property "Manufacturer" "Bourns"
			(at 0 0 90)
			(unlocked yes)
			(layer "F.Fab")
			(hide yes)
			(effects
				(font
					(size 1 1)
					(thickness 0.15)
				)
			)
		)
		(property "MPN" "CR0402-FX-4700GLF"
			(at 0 0 90)
			(unlocked yes)
			(layer "F.Fab")
			(hide yes)
			(effects
				(font
					(size 1 1)
					(thickness 0.15)
				)
			)
		)
		(property "Val" "470R"
			(at 0 0 90)
			(unlocked yes)
			(layer "F.Fab")
			(hide yes)
			(effects
				(font
					(size 1 1)
					(thickness 0.15)
				)
			)
		)
		(property "License" "Apache-2.0"
			(at 0 0 90)
			(unlocked yes)
			(layer "F.Fab")
			(hide yes)
			(effects
				(font
					(size 1 1)
					(thickness 0.15)
				)
			)
		)
		(property "Author" "Antmicro"
			(at 0 0 90)
			(unlocked yes)
			(layer "F.Fab")
			(hide yes)
			(effects
				(font
					(size 1 1)
					(thickness 0.15)
				)
			)
		)
		(property "Tolerance" "1%"
			(at 0 0 90)
			(unlocked yes)
			(layer "F.Fab")
			(hide yes)
			(effects
				(font
					(size 1 1)
					(thickness 0.15)
				)
			)
		)
		(sheetname "/Supply/")
		(sheetfile "supply.kicad_sch")
		(attr smd)
		(fp_rect
			(start -0.925 -0.47)
			(end 0.925 0.47)
			(stroke
				(width 0.05)
				(type default)
			)
			(fill no)
			(layer "F.CrtYd")
		)
		(fp_rect
			(start -0.5 -0.25)
			(end 0.5 0.25)
			(stroke
				(width 0.15)
				(type solid)
			)
			(fill no)
			(layer "F.Fab")
		)
		(fp_text user "License: Apache-2.0"
			(at -0.95 5.169 90)
			(layer "F.Fab")
			(effects
				(font
					(size 0.7 0.7)
					(thickness 0.15)
				)
				(justify left bottom)
			)
		)
		(fp_text user "Author: Antmicro"
			(at -0.95 4.169 90)
			(layer "F.Fab")
			(effects
				(font
					(size 0.7 0.7)
					(thickness 0.15)
				)
				(justify left bottom)
			)
		)
		(fp_text user "${REFERENCE}"
			(at -0.95 3.168 90)
			(layer "F.Fab")
			(effects
				(font
					(size 0.7 0.7)
					(thickness 0.15)
				)
				(justify left bottom)
			)
		)
		(pad "1" smd roundrect
			(at -0.48 0 90)
			(size 0.59 0.64)
			(layers "F.Cu" "F.Mask" "F.Paste")
			(roundrect_rratio 0.25)
			(net 475 "Net-(D305-A)")
			(pintype "passive")
		)
		(pad "2" smd roundrect
			(at 0.48 0 90)
			(size 0.59 0.64)
			(layers "F.Cu" "F.Mask" "F.Paste")
			(roundrect_rratio 0.25)
			(net 65 "3V3_SSD")
			(pintype "passive")
		)
	)
	(footprint "antmicro-footprints:C_0402_1005Metric"
		(layer "F.Cu")
		(at 95.592962 138.782236)
		(descr "Capacitor SMD 0402")
		(tags "capacitor SMD 0402")
		(property "Reference" "C916"
			(at 1.235 0.394264 180)
			(layer "F.SilkS")
			(effects
				(font
					(size 0.7 0.7)
					(thickness 0.15)
				)
				(justify left bottom)
			)
		)
		(property "Value" "C_100n_0402"
			(at -1.022927 2.155213 0)
			(layer "F.Fab")
			(effects
				(font
					(size 0.7 0.7)
					(thickness 0.15)
				)
				(justify left bottom)
			)
		)
		(property "Datasheet" "https://www.murata.com/products/productdetail?partno=GRM155R61H104KE14%23"
			(at 0 0 0)
			(layer "F.Fab")
			(hide yes)
			(effects
				(font
					(size 1.27 1.27)
					(thickness 0.15)
				)
			)
		)
		(property "Manufacturer" "Murata"
			(at 0 0 0)
			(unlocked yes)
			(layer "F.Fab")
			(hide yes)
			(effects
				(font
					(size 1 1)
					(thickness 0.15)
				)
			)
		)
		(property "MPN" "GRM155R61H104KE14D"
			(at 0 0 0)
			(unlocked yes)
			(layer "F.Fab")
			(hide yes)
			(effects
				(font
					(size 1 1)
					(thickness 0.15)
				)
			)
		)
		(property "Val" "100n"
			(at 0 0 0)
			(unlocked yes)
			(layer "F.Fab")
			(hide yes)
			(effects
				(font
					(size 1 1)
					(thickness 0.15)
				)
			)
		)
		(property "License" "Apache-2.0"
			(at 0 0 0)
			(unlocked yes)
			(layer "F.Fab")
			(hide yes)
			(effects
				(font
					(size 1 1)
					(thickness 0.15)
				)
			)
		)
		(property "Author" "Antmicro"
			(at 0 0 0)
			(unlocked yes)
			(layer "F.Fab")
			(hide yes)
			(effects
				(font
					(size 1 1)
					(thickness 0.15)
				)
			)
		)
		(property "Voltage" "50V"
			(at 0 0 0)
			(unlocked yes)
			(layer "F.Fab")
			(hide yes)
			(effects
				(font
					(size 1 1)
					(thickness 0.15)
				)
			)
		)
		(property "Dielectric" "X5R"
			(at 0 0 0)
			(unlocked yes)
			(layer "F.Fab")
			(hide yes)
			(effects
				(font
					(size 1 1)
					(thickness 0.15)
				)
			)
		)
		(sheetname "/USB/")
		(sheetfile "usb.kicad_sch")
		(attr smd)
		(fp_rect
			(start -0.925 -0.47)
			(end 0.925 0.47)
			(stroke
				(width 0.05)
				(type default)
			)
			(fill no)
			(layer "F.CrtYd")
		)
		(fp_line
			(start -0.494 -0.25)
			(end 0.504 -0.25)
			(stroke
				(width 0.15)
				(type solid)
			)
			(layer "F.Fab")
		)
		(fp_line
			(start -0.494 0.248)
			(end -0.494 -0.25)
			(stroke
				(width 0.15)
				(type solid)
			)
			(layer "F.Fab")
		)
		(fp_line
			(start 0.504 -0.25)
			(end 0.504 0.248)
			(stroke
				(width 0.15)
				(type solid)
			)
			(layer "F.Fab")
		)
		(fp_line
			(start 0.504 0.248)
			(end -0.494 0.248)
			(stroke
				(width 0.15)
				(type solid)
			)
			(layer "F.Fab")
		)
		(fp_text user "License: Apache-2.0"
			(at -0.939 5.799 0)
			(layer "F.Fab")
			(effects
				(font
					(size 0.7 0.7)
					(thickness 0.15)
				)
				(justify left bottom)
			)
		)
		(fp_text user "Author: Antmicro"
			(at -0.939 3.399 0)
			(layer "F.Fab")
			(effects
				(font
					(size 0.7 0.7)
					(thickness 0.15)
				)
				(justify left bottom)
			)
		)
		(fp_text user "${REFERENCE}"
			(at -0.939 4.599 0)
			(layer "F.Fab")
			(effects
				(font
					(size 0.7 0.7)
					(thickness 0.15)
				)
				(justify left bottom)
			)
		)
		(pad "1" smd roundrect
			(at -0.48 0)
			(size 0.59 0.64)
			(layers "F.Cu" "F.Mask" "F.Paste")
			(roundrect_rratio 0.25)
			(net 30 "/USB/USB_1V2")
			(pintype "passive")
		)
		(pad "2" smd roundrect
			(at 0.48 0)
			(size 0.59 0.64)
			(layers "F.Cu" "F.Mask" "F.Paste")
			(roundrect_rratio 0.25)
			(net 3 "GND")
			(pintype "passive")
		)
	)
	(footprint "antmicro-footprints:R_0402_1005Metric"
		(layer "F.Cu")
		(at 120.3 154.6415 180)
		(descr "Resistor SMD 0402")
		(tags "resistor SMD 0402")
		(property "Reference" "R218"
			(at -4.3 -0.175 180)
			(layer "F.SilkS")
			(effects
				(font
					(size 0.7 0.7)
					(thickness 0.15)
				)
				(justify left bottom)
			)
		)
		(property "Value" "R_0R_0402"
			(at -1.011843 1.772047 180)
			(layer "F.Fab")
			(effects
				(font
					(size 0.7 0.7)
					(thickness 0.15)
				)
				(justify left bottom)
			)
		)
		(property "Datasheet" "https://industrial.panasonic.com/cdbs/www-data/pdf/RDA0000/AOA0000C301.pdf"
			(at 0 0 180)
			(layer "F.Fab")
			(hide yes)
			(effects
				(font
					(size 1.27 1.27)
					(thickness 0.15)
				)
			)
		)
		(property "Manufacturer" "Panasonic"
			(at 0 0 180)
			(unlocked yes)
			(layer "F.Fab")
			(hide yes)
			(effects
				(font
					(size 1 1)
					(thickness 0.15)
				)
			)
		)
		(property "MPN" "ERJ2GE0R00X"
			(at 0 0 180)
			(unlocked yes)
			(layer "F.Fab")
			(hide yes)
			(effects
				(font
					(size 1 1)
					(thickness 0.15)
				)
			)
		)
		(property "Val" "0R"
			(at 0 0 180)
			(unlocked yes)
			(layer "F.Fab")
			(hide yes)
			(effects
				(font
					(size 1 1)
					(thickness 0.15)
				)
			)
		)
		(property "License" "Apache-2.0"
			(at 0 0 180)
			(unlocked yes)
			(layer "F.Fab")
			(hide yes)
			(effects
				(font
					(size 1 1)
					(thickness 0.15)
				)
			)
		)
		(property "Author" "Antmicro"
			(at 0 0 180)
			(unlocked yes)
			(layer "F.Fab")
			(hide yes)
			(effects
				(font
					(size 1 1)
					(thickness 0.15)
				)
			)
		)
		(property "Tolerance" "~"
			(at 0 0 180)
			(unlocked yes)
			(layer "F.Fab")
			(hide yes)
			(effects
				(font
					(size 1 1)
					(thickness 0.15)
				)
			)
		)
		(property "Current" "1A"
			(at 0 0 180)
			(unlocked yes)
			(layer "F.Fab")
			(hide yes)
			(effects
				(font
					(size 1 1)
					(thickness 0.15)
				)
			)
		)
		(sheetname "/Compute module/")
		(sheetfile "compute-module.kicad_sch")
		(attr smd)
		(fp_rect
			(start -0.925 -0.47)
			(end 0.925 0.47)
			(stroke
				(width 0.05)
				(type default)
			)
			(fill no)
			(layer "F.CrtYd")
		)
		(fp_rect
			(start -0.5 -0.25)
			(end 0.5 0.25)
			(stroke
				(width 0.15)
				(type solid)
			)
			(fill no)
			(layer "F.Fab")
		)
		(fp_text user "License: Apache-2.0"
			(at -0.95 5.169 180)
			(layer "F.Fab")
			(effects
				(font
					(size 0.7 0.7)
					(thickness 0.15)
				)
				(justify left bottom)
			)
		)
		(fp_text user "${REFERENCE}"
			(at -0.95 3.168 180)
			(layer "F.Fab")
			(effects
				(font
					(size 0.7 0.7)
					(thickness 0.15)
				)
				(justify left bottom)
			)
		)
		(fp_text user "Author: Antmicro"
			(at -0.95 4.169 180)
			(layer "F.Fab")
			(effects
				(font
					(size 0.7 0.7)
					(thickness 0.15)
				)
				(justify left bottom)
			)
		)
		(pad "1" smd roundrect
			(at -0.48 0 180)
			(size 0.59 0.64)
			(layers "F.Cu" "F.Mask" "F.Paste")
			(roundrect_rratio 0.25)
			(net 167 "/Compute module/NVMe.RX1_P")
			(pintype "passive")
		)
		(pad "2" smd roundrect
			(at 0.48 0 180)
			(size 0.59 0.64)
			(layers "F.Cu" "F.Mask" "F.Paste")
			(roundrect_rratio 0.25)
			(net 147 "/Compute module/R1_P")
			(pintype "passive")
		)
	)
	(footprint "antmicro-footprints:R_0402_1005Metric"
		(layer "F.Cu")
		(at 117.88 155.8415 180)
		(descr "Resistor SMD 0402")
		(tags "resistor SMD 0402")
		(property "Reference" "R220"
			(at -3.5 -0.325 180)
			(layer "F.SilkS")
			(effects
				(font
					(size 0.7 0.7)
					(thickness 0.15)
				)
				(justify left bottom)
			)
		)
		(property "Value" "R_0R_0402"
			(at -1.011843 1.772047 180)
			(layer "F.Fab")
			(effects
				(font
					(size 0.7 0.7)
					(thickness 0.15)
				)
				(justify left bottom)
			)
		)
		(property "Datasheet" "https://industrial.panasonic.com/cdbs/www-data/pdf/RDA0000/AOA0000C301.pdf"
			(at 0 0 180)
			(layer "F.Fab")
			(hide yes)
			(effects
				(font
					(size 1.27 1.27)
					(thickness 0.15)
				)
			)
		)
		(property "Manufacturer" "Panasonic"
			(at 0 0 180)
			(unlocked yes)
			(layer "F.Fab")
			(hide yes)
			(effects
				(font
					(size 1 1)
					(thickness 0.15)
				)
			)
		)
		(property "MPN" "ERJ2GE0R00X"
			(at 0 0 180)
			(unlocked yes)
			(layer "F.Fab")
			(hide yes)
			(effects
				(font
					(size 1 1)
					(thickness 0.15)
				)
			)
		)
		(property "Val" "0R"
			(at 0 0 180)
			(unlocked yes)
			(layer "F.Fab")
			(hide yes)
			(effects
				(font
					(size 1 1)
					(thickness 0.15)
				)
			)
		)
		(property "License" "Apache-2.0"
			(at 0 0 180)
			(unlocked yes)
			(layer "F.Fab")
			(hide yes)
			(effects
				(font
					(size 1 1)
					(thickness 0.15)
				)
			)
		)
		(property "Author" "Antmicro"
			(at 0 0 180)
			(unlocked yes)
			(layer "F.Fab")
			(hide yes)
			(effects
				(font
					(size 1 1)
					(thickness 0.15)
				)
			)
		)
		(property "Tolerance" "~"
			(at 0 0 180)
			(unlocked yes)
			(layer "F.Fab")
			(hide yes)
			(effects
				(font
					(size 1 1)
					(thickness 0.15)
				)
			)
		)
		(property "Current" "1A"
			(at 0 0 180)
			(unlocked yes)
			(layer "F.Fab")
			(hide yes)
			(effects
				(font
					(size 1 1)
					(thickness 0.15)
				)
			)
		)
		(sheetname "/Compute module/")
		(sheetfile "compute-module.kicad_sch")
		(attr smd)
		(fp_rect
			(start -0.925 -0.47)
			(end 0.925 0.47)
			(stroke
				(width 0.05)
				(type default)
			)
			(fill no)
			(layer "F.CrtYd")
		)
		(fp_rect
			(start -0.5 -0.25)
			(end 0.5 0.25)
			(stroke
				(width 0.15)
				(type solid)
			)
			(fill no)
			(layer "F.Fab")
		)
		(fp_text user "Author: Antmicro"
			(at -0.95 4.169 180)
			(layer "F.Fab")
			(effects
				(font
					(size 0.7 0.7)
					(thickness 0.15)
				)
				(justify left bottom)
			)
		)
		(fp_text user "License: Apache-2.0"
			(at -0.95 5.169 180)
			(layer "F.Fab")
			(effects
				(font
					(size 0.7 0.7)
					(thickness 0.15)
				)
				(justify left bottom)
			)
		)
		(fp_text user "${REFERENCE}"
			(at -0.95 3.168 180)
			(layer "F.Fab")
			(effects
				(font
					(size 0.7 0.7)
					(thickness 0.15)
				)
				(justify left bottom)
			)
		)
		(pad "1" smd roundrect
			(at -0.48 0 180)
			(size 0.59 0.64)
			(layers "F.Cu" "F.Mask" "F.Paste")
			(roundrect_rratio 0.25)
			(net 165 "/Compute module/NVMe.TX2_P")
			(pintype "passive")
		)
		(pad "2" smd roundrect
			(at 0.48 0 180)
			(size 0.59 0.64)
			(layers "F.Cu" "F.Mask" "F.Paste")
			(roundrect_rratio 0.25)
			(net 150 "/Compute module/T2_P")
			(pintype "passive")
		)
	)
	(footprint "antmicro-footprints:C_0402_1005Metric"
		(layer "F.Cu")
		(at 83.542962 153.1415 -90)
		(descr "Capacitor SMD 0402")
		(tags "capacitor SMD 0402")
		(property "Reference" "C204"
			(at -0.865 0.475 90)
			(layer "F.SilkS")
			(effects
				(font
					(size 0.7 0.7)
					(thickness 0.15)
				)
				(justify right bottom)
			)
		)
		(property "Value" "C_100n_0402"
			(at -1.022927 2.155213 90)
			(layer "F.Fab")
			(effects
				(font
					(size 0.7 0.7)
					(thickness 0.15)
				)
				(justify right bottom)
			)
		)
		(property "Datasheet" "https://www.murata.com/products/productdetail?partno=GRM155R61H104KE14%23"
			(at 0 0 270)
			(layer "F.Fab")
			(hide yes)
			(effects
				(font
					(size 1.27 1.27)
					(thickness 0.15)
				)
			)
		)
		(property "MPN" "GRM155R61H104KE14D"
			(at 0 0 270)
			(unlocked yes)
			(layer "F.Fab")
			(hide yes)
			(effects
				(font
					(size 1 1)
					(thickness 0.15)
				)
			)
		)
		(property "Manufacturer" "Murata"
			(at 0 0 270)
			(unlocked yes)
			(layer "F.Fab")
			(hide yes)
			(effects
				(font
					(size 1 1)
					(thickness 0.15)
				)
			)
		)
		(property "License" "Apache-2.0"
			(at 0 0 270)
			(unlocked yes)
			(layer "F.Fab")
			(hide yes)
			(effects
				(font
					(size 1 1)
					(thickness 0.15)
				)
			)
		)
		(property "Author" "Antmicro"
			(at 0 0 270)
			(unlocked yes)
			(layer "F.Fab")
			(hide yes)
			(effects
				(font
					(size 1 1)
					(thickness 0.15)
				)
			)
		)
		(property "Val" "100n"
			(at 0 0 270)
			(unlocked yes)
			(layer "F.Fab")
			(hide yes)
			(effects
				(font
					(size 1 1)
					(thickness 0.15)
				)
			)
		)
		(property "Voltage" "50V"
			(at 0 0 270)
			(unlocked yes)
			(layer "F.Fab")
			(hide yes)
			(effects
				(font
					(size 1 1)
					(thickness 0.15)
				)
			)
		)
		(property "Dielectric" "X5R"
			(at 0 0 270)
			(unlocked yes)
			(layer "F.Fab")
			(hide yes)
			(effects
				(font
					(size 1 1)
					(thickness 0.15)
				)
			)
		)
		(sheetname "/Compute module/")
		(sheetfile "compute-module.kicad_sch")
		(attr smd)
		(fp_rect
			(start -0.925 -0.47)
			(end 0.925 0.47)
			(stroke
				(width 0.05)
				(type default)
			)
			(fill no)
			(layer "F.CrtYd")
		)
		(fp_line
			(start -0.494 0.248)
			(end -0.494 -0.25)
			(stroke
				(width 0.15)
				(type solid)
			)
			(layer "F.Fab")
		)
		(fp_line
			(start 0.504 0.248)
			(end -0.494 0.248)
			(stroke
				(width 0.15)
				(type solid)
			)
			(layer "F.Fab")
		)
		(fp_line
			(start -0.494 -0.25)
			(end 0.504 -0.25)
			(stroke
				(width 0.15)
				(type solid)
			)
			(layer "F.Fab")
		)
		(fp_line
			(start 0.504 -0.25)
			(end 0.504 0.248)
			(stroke
				(width 0.15)
				(type solid)
			)
			(layer "F.Fab")
		)
		(fp_text user "${REFERENCE}"
			(at -0.939 4.599 270)
			(layer "F.Fab")
			(effects
				(font
					(size 0.7 0.7)
					(thickness 0.15)
				)
				(justify left bottom)
			)
		)
		(fp_text user "Author: Antmicro"
			(at -0.939 3.399 270)
			(layer "F.Fab")
			(effects
				(font
					(size 0.7 0.7)
					(thickness 0.15)
				)
				(justify left bottom)
			)
		)
		(fp_text user "License: Apache-2.0"
			(at -0.939 5.799 270)
			(layer "F.Fab")
			(effects
				(font
					(size 0.7 0.7)
					(thickness 0.15)
				)
				(justify left bottom)
			)
		)
		(pad "1" smd roundrect
			(at -0.48 0 270)
			(size 0.59 0.64)
			(layers "F.Cu" "F.Mask" "F.Paste")
			(roundrect_rratio 0.25)
			(net 3 "GND")
			(pintype "passive")
		)
		(pad "2" smd roundrect
			(at 0.48 0 270)
			(size 0.59 0.64)
			(layers "F.Cu" "F.Mask" "F.Paste")
			(roundrect_rratio 0.25)
			(net 18 "V_{IO}")
			(pintype "passive")
		)
	)
	(footprint "antmicro-footprints:R_0402_1005Metric"
		(layer "F.Cu")
		(at 95.092962 133.807236 -90)
		(descr "Resistor SMD 0402")
		(tags "resistor SMD 0402")
		(property "Reference" "R922"
			(at -0.930736 -1.385 90)
			(layer "F.SilkS")
			(effects
				(font
					(size 0.7 0.7)
					(thickness 0.15)
				)
				(justify right bottom)
			)
		)
		(property "Value" "R_12k_0402"
			(at -1.011843 1.772047 90)
			(layer "F.Fab")
			(effects
				(font
					(size 0.7 0.7)
					(thickness 0.15)
				)
				(justify right bottom)
			)
		)
		(property "Datasheet" "https://www.bourns.com/docs/product-datasheets/cr.pdf"
			(at 0 0 270)
			(layer "F.Fab")
			(hide yes)
			(effects
				(font
					(size 1.27 1.27)
					(thickness 0.15)
				)
			)
		)
		(property "Manufacturer" "Bourns"
			(at 0 0 270)
			(unlocked yes)
			(layer "F.Fab")
			(hide yes)
			(effects
				(font
					(size 1 1)
					(thickness 0.15)
				)
			)
		)
		(property "MPN" "CR0402-FX-1202GLF"
			(at 0 0 270)
			(unlocked yes)
			(layer "F.Fab")
			(hide yes)
			(effects
				(font
					(size 1 1)
					(thickness 0.15)
				)
			)
		)
		(property "Val" "12k"
			(at 0 0 270)
			(unlocked yes)
			(layer "F.Fab")
			(hide yes)
			(effects
				(font
					(size 1 1)
					(thickness 0.15)
				)
			)
		)
		(property "License" "Apache-2.0"
			(at 0 0 270)
			(unlocked yes)
			(layer "F.Fab")
			(hide yes)
			(effects
				(font
					(size 1 1)
					(thickness 0.15)
				)
			)
		)
		(property "Author" "Antmicro"
			(at 0 0 270)
			(unlocked yes)
			(layer "F.Fab")
			(hide yes)
			(effects
				(font
					(size 1 1)
					(thickness 0.15)
				)
			)
		)
		(property "Tolerance" "1%"
			(at 0 0 270)
			(unlocked yes)
			(layer "F.Fab")
			(hide yes)
			(effects
				(font
					(size 1 1)
					(thickness 0.15)
				)
			)
		)
		(sheetname "/USB/")
		(sheetfile "usb.kicad_sch")
		(attr smd)
		(fp_rect
			(start -0.925 -0.47)
			(end 0.925 0.47)
			(stroke
				(width 0.05)
				(type default)
			)
			(fill no)
			(layer "F.CrtYd")
		)
		(fp_rect
			(start -0.5 -0.25)
			(end 0.5 0.25)
			(stroke
				(width 0.15)
				(type solid)
			)
			(fill no)
			(layer "F.Fab")
		)
		(fp_text user "License: Apache-2.0"
			(at -0.95 5.169 270)
			(layer "F.Fab")
			(effects
				(font
					(size 0.7 0.7)
					(thickness 0.15)
				)
				(justify left bottom)
			)
		)
		(fp_text user "${REFERENCE}"
			(at -0.95 3.168 270)
			(layer "F.Fab")
			(effects
				(font
					(size 0.7 0.7)
					(thickness 0.15)
				)
				(justify left bottom)
			)
		)
		(fp_text user "Author: Antmicro"
			(at -0.95 4.169 270)
			(layer "F.Fab")
			(effects
				(font
					(size 0.7 0.7)
					(thickness 0.15)
				)
				(justify left bottom)
			)
		)
		(pad "1" smd roundrect
			(at -0.48 0 270)
			(size 0.59 0.64)
			(layers "F.Cu" "F.Mask" "F.Paste")
			(roundrect_rratio 0.25)
			(net 3 "GND")
			(pintype "passive")
		)
		(pad "2" smd roundrect
			(at 0.48 0 270)
			(size 0.59 0.64)
			(layers "F.Cu" "F.Mask" "F.Paste")
			(roundrect_rratio 0.25)
			(net 378 "Net-(U905-REF)")
			(pintype "passive")
		)
	)
	(footprint "antmicro-footprints:TP_SMD_0.75mm"
		(layer "F.Cu")
		(at 96.917962 137.6665)
		(property "Reference" "TP905"
			(at 0.3 0.4 180)
			(layer "F.SilkS")
			(effects
				(font
					(size 0.7 0.7)
					(thickness 0.15)
				)
				(justify left bottom)
			)
		)
		(property "Value" "TP_0.75mm_SMD"
			(at 0 1.2 0)
			(layer "F.Fab")
			(effects
				(font
					(size 0.7 0.7)
					(thickness 0.15)
				)
				(justify left bottom)
			)
		)
		(property "MPN" ""
			(at 0 0 0)
			(unlocked yes)
			(layer "F.Fab")
			(hide yes)
			(effects
				(font
					(size 1 1)
					(thickness 0.15)
				)
			)
		)
		(property "Manufacturer" ""
			(at 0 0 0)
			(unlocked yes)
			(layer "F.Fab")
			(hide yes)
			(effects
				(font
					(size 1 1)
					(thickness 0.15)
				)
			)
		)
		(property "Author" "Antmicro"
			(at 0 0 0)
			(unlocked yes)
			(layer "F.Fab")
			(hide yes)
			(effects
				(font
					(size 1 1)
					(thickness 0.15)
				)
			)
		)
		(property "License" "Apache-2.0"
			(at 0 0 0)
			(unlocked yes)
			(layer "F.Fab")
			(hide yes)
			(effects
				(font
					(size 1 1)
					(thickness 0.15)
				)
			)
		)
		(sheetname "/USB/")
		(sheetfile "usb.kicad_sch")
		(attr exclude_from_pos_files exclude_from_bom)
		(fp_circle
			(center 0 0)
			(end 0.475 0)
			(stroke
				(width 0.05)
				(type default)
			)
			(fill no)
			(layer "F.CrtYd")
		)
		(fp_text user "Author: Antmicro"
			(at -0.4 3.901 0)
			(layer "F.Fab")
			(effects
				(font
					(size 0.7 0.7)
					(thickness 0.15)
				)
				(justify left bottom)
			)
		)
		(fp_text user "License: Apache-2.0"
			(at -0.4 5.101 0)
			(layer "F.Fab")
			(effects
				(font
					(size 0.7 0.7)
					(thickness 0.15)
				)
				(justify left bottom)
			)
		)
		(fp_text user "${REFERENCE}"
			(at -0.4 2.7 0)
			(layer "F.Fab")
			(effects
				(font
					(size 0.7 0.7)
					(thickness 0.15)
				)
				(justify left bottom)
			)
		)
		(pad "1" smd circle
			(at 0 0)
			(size 0.75 0.75)
			(layers "F.Cu" "F.Mask")
			(net 30 "/USB/USB_1V2")
			(pinfunction "1")
			(pintype "passive")
		)
	)
	(footprint "antmicro-footprints:TP_SMD_0.75mm"
		(layer "F.Cu")
		(at 88.117962 132.9165 180)
		(property "Reference" "TP914"
			(at -0.152038 4.1365 0)
			(layer "F.SilkS")
			(effects
				(font
					(size 0.7 0.7)
					(thickness 0.15)
				)
				(justify right bottom)
			)
		)
		(property "Value" "TP_0.75mm_SMD"
			(at 0 1.2 0)
			(layer "F.Fab")
			(effects
				(font
					(size 0.7 0.7)
					(thickness 0.15)
				)
				(justify right bottom)
			)
		)
		(property "MPN" ""
			(at 0 0 180)
			(unlocked yes)
			(layer "F.Fab")
			(hide yes)
			(effects
				(font
					(size 1 1)
					(thickness 0.15)
				)
			)
		)
		(property "Manufacturer" ""
			(at 0 0 180)
			(unlocked yes)
			(layer "F.Fab")
			(hide yes)
			(effects
				(font
					(size 1 1)
					(thickness 0.15)
				)
			)
		)
		(property "Author" "Antmicro"
			(at 0 0 180)
			(unlocked yes)
			(layer "F.Fab")
			(hide yes)
			(effects
				(font
					(size 1 1)
					(thickness 0.15)
				)
			)
		)
		(property "License" "Apache-2.0"
			(at 0 0 180)
			(unlocked yes)
			(layer "F.Fab")
			(hide yes)
			(effects
				(font
					(size 1 1)
					(thickness 0.15)
				)
			)
		)
		(sheetname "/USB/")
		(sheetfile "usb.kicad_sch")
		(attr exclude_from_pos_files exclude_from_bom)
		(fp_circle
			(center 0 0)
			(end 0.475 0)
			(stroke
				(width 0.05)
				(type default)
			)
			(fill no)
			(layer "F.CrtYd")
		)
		(fp_text user "License: Apache-2.0"
			(at -0.4 5.101 180)
			(layer "F.Fab")
			(effects
				(font
					(size 0.7 0.7)
					(thickness 0.15)
				)
				(justify left bottom)
			)
		)
		(fp_text user "Author: Antmicro"
			(at -0.4 3.901 180)
			(layer "F.Fab")
			(effects
				(font
					(size 0.7 0.7)
					(thickness 0.15)
				)
				(justify left bottom)
			)
		)
		(fp_text user "${REFERENCE}"
			(at -0.4 2.7 180)
			(layer "F.Fab")
			(effects
				(font
					(size 0.7 0.7)
					(thickness 0.15)
				)
				(justify left bottom)
			)
		)
		(pad "1" smd circle
			(at 0 0 180)
			(size 0.75 0.75)
			(layers "F.Cu" "F.Mask")
			(net 439 "Net-(U905-PD2_CC1)")
			(pinfunction "1")
			(pintype "passive")
		)
	)
	(footprint "antmicro-footprints:R_0402_1005Metric"
		(layer "F.Cu")
		(at 58.992962 176.3255 180)
		(descr "Resistor SMD 0402")
		(tags "resistor SMD 0402")
		(property "Reference" "R810"
			(at -1.507038 1.3255 0)
			(layer "F.SilkS")
			(effects
				(font
					(size 0.7 0.7)
					(thickness 0.15)
				)
				(justify right top)
			)
		)
		(property "Value" "R_0R_0402"
			(at -1.011843 1.772046 0)
			(layer "F.Fab")
			(effects
				(font
					(size 0.7 0.7)
					(thickness 0.15)
				)
				(justify right top)
			)
		)
		(property "Datasheet" "https://industrial.panasonic.com/cdbs/www-data/pdf/RDA0000/AOA0000C301.pdf"
			(at 0 0 0)
			(layer "F.Fab")
			(hide yes)
			(effects
				(font
					(size 1.27 1.27)
					(thickness 0.15)
				)
			)
		)
		(property "Description" "SMD Chip Resistor, Jumper, 0 ohm, 100 mW, 0402 [1005 Metric], Thick Film, General Purpose"
			(at 0 0 0)
			(layer "F.Fab")
			(hide yes)
			(effects
				(font
					(size 1.27 1.27)
					(thickness 0.15)
				)
			)
		)
		(property "MPN" "ERJ2GE0R00X"
			(at 0 0 180)
			(unlocked yes)
			(layer "F.Fab")
			(hide yes)
			(effects
				(font
					(size 1 1)
					(thickness 0.15)
				)
			)
		)
		(property "Manufacturer" "Panasonic"
			(at 0 0 180)
			(unlocked yes)
			(layer "F.Fab")
			(hide yes)
			(effects
				(font
					(size 1 1)
					(thickness 0.15)
				)
			)
		)
		(property "License" "Apache-2.0"
			(at 0 0 180)
			(unlocked yes)
			(layer "F.Fab")
			(hide yes)
			(effects
				(font
					(size 1 1)
					(thickness 0.15)
				)
			)
		)
		(property "Author" "Antmicro"
			(at 0 0 180)
			(unlocked yes)
			(layer "F.Fab")
			(hide yes)
			(effects
				(font
					(size 1 1)
					(thickness 0.15)
				)
			)
		)
		(property "Val" "0R"
			(at 0 0 180)
			(unlocked yes)
			(layer "F.Fab")
			(hide yes)
			(effects
				(font
					(size 1 1)
					(thickness 0.15)
				)
			)
		)
		(property "Tolerance" "~"
			(at 0 0 180)
			(unlocked yes)
			(layer "F.Fab")
			(hide yes)
			(effects
				(font
					(size 1 1)
					(thickness 0.15)
				)
			)
		)
		(property "Current" "1A"
			(at 0 0 180)
			(unlocked yes)
			(layer "F.Fab")
			(hide yes)
			(effects
				(font
					(size 1 1)
					(thickness 0.15)
				)
			)
		)
		(sheetname "/Peripherals/")
		(sheetfile "peripherals.kicad_sch")
		(attr smd)
		(fp_poly
			(pts
				(xy -0.925 -0.47) (xy 0.925 -0.47) (xy 0.925 0.47) (xy -0.925 0.47)
			)
			(stroke
				(width 0.05)
				(type default)
			)
			(fill no)
			(layer "F.CrtYd")
		)
		(fp_poly
			(pts
				(xy -0.5 -0.25) (xy 0.5 -0.25) (xy 0.5 0.25) (xy -0.5 0.25)
			)
			(stroke
				(width 0.15)
				(type solid)
			)
			(fill no)
			(layer "F.Fab")
		)
		(fp_text user "${REFERENCE}"
			(at -0.95 3.168 0)
			(layer "F.Fab")
			(effects
				(font
					(size 0.7 0.7)
					(thickness 0.15)
				)
				(justify right top)
			)
		)
		(fp_text user "License: Apache-2.0"
			(at -0.949999 5.169 0)
			(layer "F.Fab")
			(effects
				(font
					(size 0.7 0.7)
					(thickness 0.15)
				)
				(justify right top)
			)
		)
		(fp_text user "Author: Antmicro"
			(at -0.95 4.169 0)
			(layer "F.Fab")
			(effects
				(font
					(size 0.7 0.7)
					(thickness 0.15)
				)
				(justify right top)
			)
		)
		(pad "1" smd roundrect
			(at -0.48 0 180)
			(size 0.59 0.64)
			(layers "F.Cu" "F.Mask" "F.Paste")
			(roundrect_rratio 0.25)
			(net 106 "Net-(C814-Pad2)")
			(pintype "passive")
		)
		(pad "2" smd roundrect
			(at 0.48 0 180)
			(size 0.59 0.64)
			(layers "F.Cu" "F.Mask" "F.Paste")
			(roundrect_rratio 0.25)
			(net 319 "Net-(J804-Pad1)")
			(pintype "passive")
		)
	)
	(footprint "antmicro-footprints:C_0402_1005Metric"
		(layer "F.Cu")
		(at 63.617962 175.2255 180)
		(descr "Capacitor SMD 0402")
		(tags "capacitor SMD 0402")
		(property "Reference" "C822"
			(at 13.367962 2.9755 0)
			(layer "F.SilkS")
			(effects
				(font
					(size 0.7 0.7)
					(thickness 0.15)
				)
				(justify right top)
			)
		)
		(property "Value" "C_36p_0402"
			(at -1.022927 2.155213 0)
			(layer "F.Fab")
			(effects
				(font
					(size 0.7 0.7)
					(thickness 0.15)
				)
				(justify right top)
			)
		)
		(property "Datasheet" "https://eu.mouser.com/datasheet/3/5926/1/C0GNP0_Dielectric.pdf"
			(at 0 0 0)
			(layer "F.Fab")
			(hide yes)
			(effects
				(font
					(size 1.27 1.27)
					(thickness 0.15)
				)
			)
		)
		(property "Description" "Multilayer Ceramic Capacitors MLCC, 36 pF, 25V, 0402, C0G, 5%"
			(at 0 0 0)
			(layer "F.Fab")
			(hide yes)
			(effects
				(font
					(size 1.27 1.27)
					(thickness 0.15)
				)
			)
		)
		(property "MPN" "04023A360JAT2A"
			(at 0 0 180)
			(unlocked yes)
			(layer "F.Fab")
			(hide yes)
			(effects
				(font
					(size 1 1)
					(thickness 0.15)
				)
			)
		)
		(property "Manufacturer" "KYOCERA AVX"
			(at 0 0 180)
			(unlocked yes)
			(layer "F.Fab")
			(hide yes)
			(effects
				(font
					(size 1 1)
					(thickness 0.15)
				)
			)
		)
		(property "License" "Apache-2.0"
			(at 0 0 180)
			(unlocked yes)
			(layer "F.Fab")
			(hide yes)
			(effects
				(font
					(size 1 1)
					(thickness 0.15)
				)
			)
		)
		(property "Author" "Antmicro"
			(at 0 0 180)
			(unlocked yes)
			(layer "F.Fab")
			(hide yes)
			(effects
				(font
					(size 1 1)
					(thickness 0.15)
				)
			)
		)
		(property "Val" "36pF"
			(at 0 0 180)
			(unlocked yes)
			(layer "F.Fab")
			(hide yes)
			(effects
				(font
					(size 1 1)
					(thickness 0.15)
				)
			)
		)
		(property "Voltage" "25 V"
			(at 0 0 180)
			(unlocked yes)
			(layer "F.Fab")
			(hide yes)
			(effects
				(font
					(size 1 1)
					(thickness 0.15)
				)
			)
		)
		(property "Dielectric" "C0G (NP0)"
			(at 0 0 180)
			(unlocked yes)
			(layer "F.Fab")
			(hide yes)
			(effects
				(font
					(size 1 1)
					(thickness 0.15)
				)
			)
		)
		(sheetname "/Peripherals/")
		(sheetfile "peripherals.kicad_sch")
		(attr smd)
		(fp_rect
			(start -0.925 -0.47)
			(end 0.925 0.47)
			(stroke
				(width 0.05)
				(type default)
			)
			(fill no)
			(layer "F.CrtYd")
		)
		(fp_line
			(start 0.504 0.248)
			(end -0.494 0.248)
			(stroke
				(width 0.15)
				(type solid)
			)
			(layer "F.Fab")
		)
		(fp_line
			(start 0.504 -0.25)
			(end 0.504 0.248)
			(stroke
				(width 0.15)
				(type solid)
			)
			(layer "F.Fab")
		)
		(fp_line
			(start -0.494 0.248)
			(end -0.494 -0.25)
			(stroke
				(width 0.15)
				(type solid)
			)
			(layer "F.Fab")
		)
		(fp_line
			(start -0.494 -0.25)
			(end 0.504 -0.25)
			(stroke
				(width 0.15)
				(type solid)
			)
			(layer "F.Fab")
		)
		(fp_text user "${REFERENCE}"
			(at -0.939 4.599 0)
			(layer "F.Fab")
			(effects
				(font
					(size 0.7 0.7)
					(thickness 0.15)
				)
				(justify right top)
			)
		)
		(fp_text user "Author: Antmicro"
			(at -0.939 3.399 0)
			(layer "F.Fab")
			(effects
				(font
					(size 0.7 0.7)
					(thickness 0.15)
				)
				(justify right top)
			)
		)
		(fp_text user "License: Apache-2.0"
			(at -0.939 5.799 0)
			(layer "F.Fab")
			(effects
				(font
					(size 0.7 0.7)
					(thickness 0.15)
				)
				(justify right top)
			)
		)
		(pad "1" smd roundrect
			(at -0.48 0 180)
			(size 0.59 0.64)
			(layers "F.Cu" "F.Mask" "F.Paste")
			(roundrect_rratio 0.25)
			(net 110 "Net-(C817-Pad1)")
			(pintype "passive")
		)
		(pad "2" smd roundrect
			(at 0.48 0 180)
			(size 0.59 0.64)
			(layers "F.Cu" "F.Mask" "F.Paste")
			(roundrect_rratio 0.25)
			(net 106 "Net-(C814-Pad2)")
			(pintype "passive")
		)
	)
	(footprint "antmicro-footprints:C_0402_1005Metric"
		(layer "F.Cu")
		(at 76.242962 174.3665)
		(descr "Capacitor SMD 0402")
		(tags "capacitor SMD 0402")
		(property "Reference" "C806"
			(at 5.155 -0.98 0)
			(layer "F.SilkS")
			(effects
				(font
					(size 0.7 0.7)
					(thickness 0.15)
				)
				(justify left bottom)
			)
		)
		(property "Value" "C_2u2_0402"
			(at -1.022927 2.155213 0)
			(layer "F.Fab")
			(effects
				(font
					(size 0.7 0.7)
					(thickness 0.15)
				)
				(justify left bottom)
			)
		)
		(property "Datasheet" "https://product.tdk.com/en/search/capacitor/ceramic/mlcc/info?part_no=C1005X5R1A225K050BC"
			(at 0 0 0)
			(layer "F.Fab")
			(hide yes)
			(effects
				(font
					(size 1.27 1.27)
					(thickness 0.15)
				)
			)
		)
		(property "MPN" "C1005X5R1A225K050BC"
			(at 0 0 0)
			(unlocked yes)
			(layer "F.Fab")
			(hide yes)
			(effects
				(font
					(size 1 1)
					(thickness 0.15)
				)
			)
		)
		(property "Manufacturer" "TDK"
			(at 0 0 0)
			(unlocked yes)
			(layer "F.Fab")
			(hide yes)
			(effects
				(font
					(size 1 1)
					(thickness 0.15)
				)
			)
		)
		(property "License" "Apache-2.0"
			(at 0 0 0)
			(unlocked yes)
			(layer "F.Fab")
			(hide yes)
			(effects
				(font
					(size 1 1)
					(thickness 0.15)
				)
			)
		)
		(property "Author" "Antmicro"
			(at 0 0 0)
			(unlocked yes)
			(layer "F.Fab")
			(hide yes)
			(effects
				(font
					(size 1 1)
					(thickness 0.15)
				)
			)
		)
		(property "Val" "2u2"
			(at 0 0 0)
			(unlocked yes)
			(layer "F.Fab")
			(hide yes)
			(effects
				(font
					(size 1 1)
					(thickness 0.15)
				)
			)
		)
		(property "Voltage" ""
			(at 0 0 0)
			(unlocked yes)
			(layer "F.Fab")
			(hide yes)
			(effects
				(font
					(size 1 1)
					(thickness 0.15)
				)
			)
		)
		(property "Dielectric" ""
			(at 0 0 0)
			(unlocked yes)
			(layer "F.Fab")
			(hide yes)
			(effects
				(font
					(size 1 1)
					(thickness 0.15)
				)
			)
		)
		(sheetname "/Peripherals/")
		(sheetfile "peripherals.kicad_sch")
		(attr smd)
		(fp_rect
			(start -0.925 -0.47)
			(end 0.925 0.47)
			(stroke
				(width 0.05)
				(type default)
			)
			(fill no)
			(layer "F.CrtYd")
		)
		(fp_line
			(start -0.494 -0.25)
			(end 0.504 -0.25)
			(stroke
				(width 0.15)
				(type solid)
			)
			(layer "F.Fab")
		)
		(fp_line
			(start -0.494 0.248)
			(end -0.494 -0.25)
			(stroke
				(width 0.15)
				(type solid)
			)
			(layer "F.Fab")
		)
		(fp_line
			(start 0.504 -0.25)
			(end 0.504 0.248)
			(stroke
				(width 0.15)
				(type solid)
			)
			(layer "F.Fab")
		)
		(fp_line
			(start 0.504 0.248)
			(end -0.494 0.248)
			(stroke
				(width 0.15)
				(type solid)
			)
			(layer "F.Fab")
		)
		(fp_text user "${REFERENCE}"
			(at -0.939 4.599 0)
			(layer "F.Fab")
			(effects
				(font
					(size 0.7 0.7)
					(thickness 0.15)
				)
				(justify left bottom)
			)
		)
		(fp_text user "Author: Antmicro"
			(at -0.939 3.399 0)
			(layer "F.Fab")
			(effects
				(font
					(size 0.7 0.7)
					(thickness 0.15)
				)
				(justify left bottom)
			)
		)
		(fp_text user "License: Apache-2.0"
			(at -0.939 5.799 0)
			(layer "F.Fab")
			(effects
				(font
					(size 0.7 0.7)
					(thickness 0.15)
				)
				(justify left bottom)
			)
		)
		(pad "1" smd roundrect
			(at -0.48 0)
			(size 0.59 0.64)
			(layers "F.Cu" "F.Mask" "F.Paste")
			(roundrect_rratio 0.25)
			(net 93 "Net-(U801-V_{DD(A)})")
			(pintype "passive")
		)
		(pad "2" smd roundrect
			(at 0.48 0)
			(size 0.59 0.64)
			(layers "F.Cu" "F.Mask" "F.Paste")
			(roundrect_rratio 0.25)
			(net 3 "GND")
			(pintype "passive")
		)
	)
	(footprint "antmicro-footprints:R_0402_1005Metric"
		(layer "F.Cu")
		(at 46.542962 129.7915)
		(descr "Resistor SMD 0402")
		(tags "resistor SMD 0402")
		(property "Reference" "R405"
			(at -3.975 0.35 0)
			(layer "F.SilkS")
			(effects
				(font
					(size 0.7 0.7)
					(thickness 0.15)
				)
				(justify left bottom)
			)
		)
		(property "Value" "R_1k2_0402"
			(at -1.011843 1.772047 0)
			(layer "F.Fab")
			(effects
				(font
					(size 0.7 0.7)
					(thickness 0.15)
				)
				(justify left bottom)
			)
		)
		(property "Datasheet" "https://www.bourns.com/docs/product-datasheets/cr.pdf"
			(at 0 0 0)
			(layer "F.Fab")
			(hide yes)
			(effects
				(font
					(size 1.27 1.27)
					(thickness 0.15)
				)
			)
		)
		(property "Manufacturer" "Bourns"
			(at 0 0 0)
			(unlocked yes)
			(layer "F.Fab")
			(hide yes)
			(effects
				(font
					(size 1 1)
					(thickness 0.15)
				)
			)
		)
		(property "MPN" "CR0402-FX-1201GLF"
			(at 0 0 0)
			(unlocked yes)
			(layer "F.Fab")
			(hide yes)
			(effects
				(font
					(size 1 1)
					(thickness 0.15)
				)
			)
		)
		(property "Val" "1k2"
			(at 0 0 0)
			(unlocked yes)
			(layer "F.Fab")
			(hide yes)
			(effects
				(font
					(size 1 1)
					(thickness 0.15)
				)
			)
		)
		(property "License" "Apache-2.0"
			(at 0 0 0)
			(unlocked yes)
			(layer "F.Fab")
			(hide yes)
			(effects
				(font
					(size 1 1)
					(thickness 0.15)
				)
			)
		)
		(property "Author" "Antmicro"
			(at 0 0 0)
			(unlocked yes)
			(layer "F.Fab")
			(hide yes)
			(effects
				(font
					(size 1 1)
					(thickness 0.15)
				)
			)
		)
		(property "Tolerance" "1%"
			(at 0 0 0)
			(unlocked yes)
			(layer "F.Fab")
			(hide yes)
			(effects
				(font
					(size 1 1)
					(thickness 0.15)
				)
			)
		)
		(sheetname "/Ethernet/")
		(sheetfile "ethernet.kicad_sch")
		(attr smd)
		(fp_rect
			(start -0.925 -0.47)
			(end 0.925 0.47)
			(stroke
				(width 0.05)
				(type default)
			)
			(fill no)
			(layer "F.CrtYd")
		)
		(fp_rect
			(start -0.5 -0.25)
			(end 0.5 0.25)
			(stroke
				(width 0.15)
				(type solid)
			)
			(fill no)
			(layer "F.Fab")
		)
		(fp_text user "Author: Antmicro"
			(at -0.95 4.169 0)
			(layer "F.Fab")
			(effects
				(font
					(size 0.7 0.7)
					(thickness 0.15)
				)
				(justify left bottom)
			)
		)
		(fp_text user "License: Apache-2.0"
			(at -0.95 5.169 0)
			(layer "F.Fab")
			(effects
				(font
					(size 0.7 0.7)
					(thickness 0.15)
				)
				(justify left bottom)
			)
		)
		(fp_text user "${REFERENCE}"
			(at -0.95 3.168 0)
			(layer "F.Fab")
			(effects
				(font
					(size 0.7 0.7)
					(thickness 0.15)
				)
				(justify left bottom)
			)
		)
		(pad "1" smd roundrect
			(at -0.48 0)
			(size 0.59 0.64)
			(layers "F.Cu" "F.Mask" "F.Paste")
			(roundrect_rratio 0.25)
			(net 90 "/Ethernet/VSS")
			(pintype "passive")
		)
		(pad "2" smd roundrect
			(at 0.48 0)
			(size 0.59 0.64)
			(layers "F.Cu" "F.Mask" "F.Paste")
			(roundrect_rratio 0.25)
			(net 360 "/Ethernet/CLSB")
			(pintype "passive")
		)
	)
	(footprint "antmicro-footprints:TP_SMD_0.75mm"
		(layer "F.Cu")
		(at 117.652962 137.7915 -90)
		(property "Reference" "TP307"
			(at 0.425 -3.845 180)
			(layer "F.SilkS")
			(effects
				(font
					(size 0.7 0.7)
					(thickness 0.15)
				)
				(justify right bottom)
			)
		)
		(property "Value" "TP_0.75mm_SMD"
			(at 0 1.2 90)
			(layer "F.Fab")
			(effects
				(font
					(size 0.7 0.7)
					(thickness 0.15)
				)
				(justify right bottom)
			)
		)
		(property "MPN" ""
			(at 0 0 270)
			(unlocked yes)
			(layer "F.Fab")
			(hide yes)
			(effects
				(font
					(size 1 1)
					(thickness 0.15)
				)
			)
		)
		(property "Manufacturer" ""
			(at 0 0 270)
			(unlocked yes)
			(layer "F.Fab")
			(hide yes)
			(effects
				(font
					(size 1 1)
					(thickness 0.15)
				)
			)
		)
		(property "Author" "Antmicro"
			(at 0 0 270)
			(unlocked yes)
			(layer "F.Fab")
			(hide yes)
			(effects
				(font
					(size 1 1)
					(thickness 0.15)
				)
			)
		)
		(property "License" "Apache-2.0"
			(at 0 0 270)
			(unlocked yes)
			(layer "F.Fab")
			(hide yes)
			(effects
				(font
					(size 1 1)
					(thickness 0.15)
				)
			)
		)
		(sheetname "/Supply/")
		(sheetfile "supply.kicad_sch")
		(attr exclude_from_pos_files exclude_from_bom)
		(fp_circle
			(center 0 0)
			(end 0.475 0)
			(stroke
				(width 0.05)
				(type default)
			)
			(fill no)
			(layer "F.CrtYd")
		)
		(fp_text user "License: Apache-2.0"
			(at -0.4 5.101 270)
			(layer "F.Fab")
			(effects
				(font
					(size 0.7 0.7)
					(thickness 0.15)
				)
				(justify left bottom)
			)
		)
		(fp_text user "${REFERENCE}"
			(at -0.4 2.7 270)
			(layer "F.Fab")
			(effects
				(font
					(size 0.7 0.7)
					(thickness 0.15)
				)
				(justify left bottom)
			)
		)
		(fp_text user "Author: Antmicro"
			(at -0.4 3.901 270)
			(layer "F.Fab")
			(effects
				(font
					(size 0.7 0.7)
					(thickness 0.15)
				)
				(justify left bottom)
			)
		)
		(pad "1" smd circle
			(at 0 0 270)
			(size 0.75 0.75)
			(layers "F.Cu" "F.Mask")
			(net 65 "3V3_SSD")
			(pinfunction "1")
			(pintype "passive")
		)
	)
	(footprint "antmicro-footprints:TP_SMD_0.75mm"
		(layer "F.Cu")
		(at 74.767962 159.6665 -90)
		(property "Reference" "TP305"
			(at -1.65 -1.25 270)
			(layer "F.SilkS")
			(effects
				(font
					(size 0.7 0.7)
					(thickness 0.15)
				)
				(justify right bottom)
			)
		)
		(property "Value" "TP_0.75mm_SMD"
			(at 0 1.2 90)
			(layer "F.Fab")
			(effects
				(font
					(size 0.7 0.7)
					(thickness 0.15)
				)
				(justify right bottom)
			)
		)
		(property "MPN" ""
			(at 0 0 270)
			(unlocked yes)
			(layer "F.Fab")
			(hide yes)
			(effects
				(font
					(size 1 1)
					(thickness 0.15)
				)
			)
		)
		(property "Manufacturer" ""
			(at 0 0 270)
			(unlocked yes)
			(layer "F.Fab")
			(hide yes)
			(effects
				(font
					(size 1 1)
					(thickness 0.15)
				)
			)
		)
		(property "Author" "Antmicro"
			(at 0 0 270)
			(unlocked yes)
			(layer "F.Fab")
			(hide yes)
			(effects
				(font
					(size 1 1)
					(thickness 0.15)
				)
			)
		)
		(property "License" "Apache-2.0"
			(at 0 0 270)
			(unlocked yes)
			(layer "F.Fab")
			(hide yes)
			(effects
				(font
					(size 1 1)
					(thickness 0.15)
				)
			)
		)
		(sheetname "/Supply/")
		(sheetfile "supply.kicad_sch")
		(attr exclude_from_pos_files exclude_from_bom)
		(fp_circle
			(center 0 0)
			(end 0.475 0)
			(stroke
				(width 0.05)
				(type default)
			)
			(fill no)
			(layer "F.CrtYd")
		)
		(fp_text user "Author: Antmicro"
			(at -0.4 3.901 270)
			(layer "F.Fab")
			(effects
				(font
					(size 0.7 0.7)
					(thickness 0.15)
				)
				(justify left bottom)
			)
		)
		(fp_text user "${REFERENCE}"
			(at -0.4 2.7 270)
			(layer "F.Fab")
			(effects
				(font
					(size 0.7 0.7)
					(thickness 0.15)
				)
				(justify left bottom)
			)
		)
		(fp_text user "License: Apache-2.0"
			(at -0.4 5.101 270)
			(layer "F.Fab")
			(effects
				(font
					(size 0.7 0.7)
					(thickness 0.15)
				)
				(justify left bottom)
			)
		)
		(pad "1" smd circle
			(at 0 0 270)
			(size 0.75 0.75)
			(layers "F.Cu" "F.Mask")
			(net 10 "+5V")
			(pinfunction "1")
			(pintype "passive")
		)
	)
	(footprint "antmicro-footprints:C_0402_1005Metric"
		(layer "F.Cu")
		(at 74.617962 178.2415 180)
		(descr "Capacitor SMD 0402")
		(tags "capacitor SMD 0402")
		(property "Reference" "C810"
			(at -2.42 -1.375 0)
			(layer "F.SilkS")
			(effects
				(font
					(size 0.7 0.7)
					(thickness 0.15)
				)
				(justify right bottom)
			)
		)
		(property "Value" "C_10p_0402"
			(at -1.022927 2.155213 0)
			(layer "F.Fab")
			(effects
				(font
					(size 0.7 0.7)
					(thickness 0.15)
				)
				(justify right bottom)
			)
		)
		(property "Datasheet" "https://www.murata.com/products/productdetail?partno=GCM1555C1H100GA16%23"
			(at 0 0 180)
			(layer "F.Fab")
			(hide yes)
			(effects
				(font
					(size 1.27 1.27)
					(thickness 0.15)
				)
			)
		)
		(property "MPN" "GCM1555C1H100GA16D"
			(at 0 0 180)
			(unlocked yes)
			(layer "F.Fab")
			(hide yes)
			(effects
				(font
					(size 1 1)
					(thickness 0.15)
				)
			)
		)
		(property "Manufacturer" "Murata"
			(at 0 0 180)
			(unlocked yes)
			(layer "F.Fab")
			(hide yes)
			(effects
				(font
					(size 1 1)
					(thickness 0.15)
				)
			)
		)
		(property "License" "Apache-2.0"
			(at 0 0 180)
			(unlocked yes)
			(layer "F.Fab")
			(hide yes)
			(effects
				(font
					(size 1 1)
					(thickness 0.15)
				)
			)
		)
		(property "Author" "Antmicro"
			(at 0 0 180)
			(unlocked yes)
			(layer "F.Fab")
			(hide yes)
			(effects
				(font
					(size 1 1)
					(thickness 0.15)
				)
			)
		)
		(property "Val" "10p"
			(at 0 0 180)
			(unlocked yes)
			(layer "F.Fab")
			(hide yes)
			(effects
				(font
					(size 1 1)
					(thickness 0.15)
				)
			)
		)
		(property "Voltage" "50V"
			(at 0 0 180)
			(unlocked yes)
			(layer "F.Fab")
			(hide yes)
			(effects
				(font
					(size 1 1)
					(thickness 0.15)
				)
			)
		)
		(property "Dielectric" "C0G"
			(at 0 0 180)
			(unlocked yes)
			(layer "F.Fab")
			(hide yes)
			(effects
				(font
					(size 1 1)
					(thickness 0.15)
				)
			)
		)
		(sheetname "/Peripherals/")
		(sheetfile "peripherals.kicad_sch")
		(attr smd)
		(fp_rect
			(start -0.925 -0.47)
			(end 0.925 0.47)
			(stroke
				(width 0.05)
				(type default)
			)
			(fill no)
			(layer "F.CrtYd")
		)
		(fp_line
			(start 0.504 0.248)
			(end -0.494 0.248)
			(stroke
				(width 0.15)
				(type solid)
			)
			(layer "F.Fab")
		)
		(fp_line
			(start 0.504 -0.25)
			(end 0.504 0.248)
			(stroke
				(width 0.15)
				(type solid)
			)
			(layer "F.Fab")
		)
		(fp_line
			(start -0.494 0.248)
			(end -0.494 -0.25)
			(stroke
				(width 0.15)
				(type solid)
			)
			(layer "F.Fab")
		)
		(fp_line
			(start -0.494 -0.25)
			(end 0.504 -0.25)
			(stroke
				(width 0.15)
				(type solid)
			)
			(layer "F.Fab")
		)
		(fp_text user "Author: Antmicro"
			(at -0.939 3.399 180)
			(layer "F.Fab")
			(effects
				(font
					(size 0.7 0.7)
					(thickness 0.15)
				)
				(justify left bottom)
			)
		)
		(fp_text user "${REFERENCE}"
			(at -0.939 4.599 180)
			(layer "F.Fab")
			(effects
				(font
					(size 0.7 0.7)
					(thickness 0.15)
				)
				(justify left bottom)
			)
		)
		(fp_text user "License: Apache-2.0"
			(at -0.939 5.799 180)
			(layer "F.Fab")
			(effects
				(font
					(size 0.7 0.7)
					(thickness 0.15)
				)
				(justify left bottom)
			)
		)
		(pad "1" smd roundrect
			(at -0.48 0 180)
			(size 0.59 0.64)
			(layers "F.Cu" "F.Mask" "F.Paste")
			(roundrect_rratio 0.25)
			(net 3 "GND")
			(pintype "passive")
		)
		(pad "2" smd roundrect
			(at 0.48 0 180)
			(size 0.59 0.64)
			(layers "F.Cu" "F.Mask" "F.Paste")
			(roundrect_rratio 0.25)
			(net 99 "Net-(U801-XTAL2)")
			(pintype "passive")
		)
	)
	(footprint "antmicro-footprints:Conn_Socket_Hirose_DF40_2x50_DF40HC-3.0-100DS-0.4V"
		(layer "F.Cu")
		(at 80.020961 154.714 -90)
		(property "Reference" "J201"
			(at -10.2975 1.652999 90)
			(layer "F.SilkS")
			(effects
				(font
					(size 0.7 0.7)
					(thickness 0.15)
				)
				(justify left bottom)
			)
		)
		(property "Value" "Socket_Hirose_DF40_2x50_DF40HC-3.0-100DS-0.4V"
			(at 0 3.25 90)
			(layer "F.Fab")
			(effects
				(font
					(size 0.7 0.7)
					(thickness 0.15)
				)
				(justify left bottom)
			)
		)
		(property "Datasheet" "https://www.hirose.com/en/product/document?clcode=CL0684-4151-0-51&productname=DF40HC(3.0)-100DS-0.4V(51&series=DF40&documenttype=Catalog&lang=en&documentid=en_DF40_CAT"
			(at 0 0 270)
			(layer "F.Fab")
			(hide yes)
			(effects
				(font
					(size 1.27 1.27)
					(thickness 0.15)
				)
			)
		)
		(property "Manufacturer" "Hirose Electric"
			(at 0 0 270)
			(unlocked yes)
			(layer "F.Fab")
			(hide yes)
			(effects
				(font
					(size 1 1)
					(thickness 0.15)
				)
			)
		)
		(property "MPN" "DF40HC(3.0)-100DS-0.4V(51)"
			(at 0 0 270)
			(unlocked yes)
			(layer "F.Fab")
			(hide yes)
			(effects
				(font
					(size 1 1)
					(thickness 0.15)
				)
			)
		)
		(property "Author" "Antmicro"
			(at 0 0 270)
			(unlocked yes)
			(layer "F.Fab")
			(hide yes)
			(effects
				(font
					(size 1 1)
					(thickness 0.15)
				)
			)
		)
		(property "License" "Apache-2.0"
			(at 0 0 270)
			(unlocked yes)
			(layer "F.Fab")
			(hide yes)
			(effects
				(font
					(size 1 1)
					(thickness 0.15)
				)
			)
		)
		(property "Pitch" "0.4 mm"
			(at 0 0 270)
			(unlocked yes)
			(layer "F.Fab")
			(hide yes)
			(effects
				(font
					(size 1 1)
					(thickness 0.15)
				)
			)
		)
		(sheetname "/Compute module/")
		(sheetfile "compute-module.kicad_sch")
		(attr smd)
		(fp_line
			(start -11.298 1.446)
			(end -10.077 1.446)
			(stroke
				(width 0.15)
				(type solid)
			)
			(layer "F.SilkS")
		)
		(fp_line
			(start -11.298 1.446)
			(end -11.298 -1.433)
			(stroke
				(width 0.15)
				(type solid)
			)
			(layer "F.SilkS")
		)
		(fp_line
			(start 11.303 1.446)
			(end 10.082 1.446)
			(stroke
				(width 0.15)
				(type solid)
			)
			(layer "F.SilkS")
		)
		(fp_line
			(start -11.298 -1.433)
			(end -10.077 -1.433)
			(stroke
				(width 0.15)
				(type solid)
			)
			(layer "F.SilkS")
		)
		(fp_line
			(start 11.303 -1.433)
			(end 11.303 1.446)
			(stroke
				(width 0.15)
				(type solid)
			)
			(layer "F.SilkS")
		)
		(fp_line
			(start 11.303 -1.433)
			(end 10.082 -1.433)
			(stroke
				(width 0.15)
				(type solid)
			)
			(layer "F.SilkS")
		)
		(fp_circle
			(center -10.1 1.7)
			(end -10.05 1.7)
			(stroke
				(width 0.15)
				(type solid)
			)
			(fill yes)
			(layer "F.SilkS")
		)
		(fp_rect
			(start -11.55 -2.14)
			(end 11.54 2.13)
			(stroke
				(width 0.05)
				(type solid)
			)
			(fill no)
			(layer "F.CrtYd")
		)
		(fp_line
			(start -11.298 1.446)
			(end -11.298 -1.433)
			(stroke
				(width 0.15)
				(type solid)
			)
			(layer "F.Fab")
		)
		(fp_line
			(start -10.077 1.446)
			(end -11.298 1.446)
			(stroke
				(width 0.15)
				(type solid)
			)
			(layer "F.Fab")
		)
		(fp_line
			(start 10.082 1.446)
			(end -10.058 1.446)
			(stroke
				(width 0.15)
				(type solid)
			)
			(layer "F.Fab")
		)
		(fp_line
			(start 11.303 1.446)
			(end 10.082 1.446)
			(stroke
				(width 0.15)
				(type solid)
			)
			(layer "F.Fab")
		)
		(fp_line
			(start -11.298 -1.433)
			(end -10.077 -1.433)
			(stroke
				(width 0.15)
				(type solid)
			)
			(layer "F.Fab")
		)
		(fp_line
			(start -10.077 -1.433)
			(end 10.082 -1.433)
			(stroke
				(width 0.15)
				(type solid)
			)
			(layer "F.Fab")
		)
		(fp_line
			(start 10.082 -1.433)
			(end 11.303 -1.433)
			(stroke
				(width 0.15)
				(type solid)
			)
			(layer "F.Fab")
		)
		(fp_line
			(start 11.303 -1.433)
			(end 11.303 1.446)
			(stroke
				(width 0.15)
				(type solid)
			)
			(layer "F.Fab")
		)
		(fp_text user "License: Apache-2.0"
			(at -12.65 5.006 270)
			(layer "F.Fab")
			(effects
				(font
					(size 0.7 0.7)
					(thickness 0.15)
				)
				(justify left bottom)
			)
		)
		(fp_text user "Author: Antmicro"
			(at -12.65 6.206 270)
			(layer "F.Fab")
			(effects
				(font
					(size 0.7 0.7)
					(thickness 0.15)
				)
				(justify left bottom)
			)
		)
		(fp_text user "${REFERENCE}"
			(at -12.65 7.406 270)
			(layer "F.Fab")
			(effects
				(font
					(size 0.7 0.7)
					(thickness 0.15)
				)
				(justify left bottom)
			)
		)
		(pad "1" smd rect
			(at -9.798 1.547 270)
			(size 0.2 0.7)
			(layers "F.Cu" "F.Mask" "F.Paste")
			(net 3 "GND")
			(pintype "passive")
		)
		(pad "2" smd rect
			(at -9.798 -1.534 270)
			(size 0.2 0.7)
			(layers "F.Cu" "F.Mask" "F.Paste")
			(net 3 "GND")
			(pintype "passive")
		)
		(pad "3" smd rect
			(at -9.398 1.547 270)
			(size 0.2 0.7)
			(layers "F.Cu" "F.Mask" "F.Paste")
			(net 79 "/Compute module/ETHERNET.D3_P")
			(pintype "passive")
		)
		(pad "4" smd rect
			(at -9.398 -1.534 270)
			(size 0.2 0.7)
			(layers "F.Cu" "F.Mask" "F.Paste")
			(net 80 "/Compute module/ETHERNET.D1_P")
			(pintype "passive")
		)
		(pad "5" smd rect
			(at -8.997 1.547 270)
			(size 0.2 0.7)
			(layers "F.Cu" "F.Mask" "F.Paste")
			(net 81 "/Compute module/ETHERNET.D3_N")
			(pintype "passive")
		)
		(pad "6" smd rect
			(at -8.997 -1.534 270)
			(size 0.2 0.7)
			(layers "F.Cu" "F.Mask" "F.Paste")
			(net 82 "/Compute module/ETHERNET.D1_N")
			(pintype "passive")
		)
		(pad "7" smd rect
			(at -8.597 1.547 270)
			(size 0.2 0.7)
			(layers "F.Cu" "F.Mask" "F.Paste")
			(net 3 "GND")
			(pintype "passive")
		)
		(pad "8" smd rect
			(at -8.597 -1.534 270)
			(size 0.2 0.7)
			(layers "F.Cu" "F.Mask" "F.Paste")
			(net 3 "GND")
			(pintype "passive")
		)
		(pad "9" smd rect
			(at -8.196 1.547 270)
			(size 0.2 0.7)
			(layers "F.Cu" "F.Mask" "F.Paste")
			(net 83 "/Compute module/ETHERNET.D2_N")
			(pintype "passive")
		)
		(pad "10" smd rect
			(at -8.196 -1.534 270)
			(size 0.2 0.7)
			(layers "F.Cu" "F.Mask" "F.Paste")
			(net 84 "/Compute module/ETHERNET.D0_N")
			(pintype "passive")
		)
		(pad "11" smd rect
			(at -7.797 1.547 270)
			(size 0.2 0.7)
			(layers "F.Cu" "F.Mask" "F.Paste")
			(net 85 "/Compute module/ETHERNET.D2_P")
			(pintype "passive")
		)
		(pad "12" smd rect
			(at -7.797 -1.534 270)
			(size 0.2 0.7)
			(layers "F.Cu" "F.Mask" "F.Paste")
			(net 88 "/Compute module/ETHERNET.D0_P")
			(pintype "passive")
		)
		(pad "13" smd rect
			(at -7.397 1.547 270)
			(size 0.2 0.7)
			(layers "F.Cu" "F.Mask" "F.Paste")
			(net 3 "GND")
			(pintype "passive")
		)
		(pad "14" smd rect
			(at -7.397 -1.534 270)
			(size 0.2 0.7)
			(layers "F.Cu" "F.Mask" "F.Paste")
			(net 3 "GND")
			(pintype "passive")
		)
		(pad "15" smd rect
			(at -6.997 1.547 270)
			(size 0.2 0.7)
			(layers "F.Cu" "F.Mask" "F.Paste")
			(net 212 "/Compute module/ETHERNET.LED_ACT")
			(pintype "passive")
		)
		(pad "16" smd rect
			(at -6.997 -1.534 270)
			(size 0.2 0.7)
			(layers "F.Cu" "F.Mask" "F.Paste")
			(net 213 "/Compute module/SYNC_IN")
			(pintype "passive")
		)
		(pad "17" smd rect
			(at -6.596 1.547 270)
			(size 0.2 0.7)
			(layers "F.Cu" "F.Mask" "F.Paste")
			(net 214 "/Compute module/ETHERNET.LED_LINK")
			(pintype "passive")
		)
		(pad "18" smd rect
			(at -6.596 -1.534 270)
			(size 0.2 0.7)
			(layers "F.Cu" "F.Mask" "F.Paste")
			(net 215 "/Compute module/SYNC_OUT")
			(pintype "passive")
		)
		(pad "19" smd rect
			(at -6.197 1.547 270)
			(size 0.2 0.7)
			(layers "F.Cu" "F.Mask" "F.Paste")
			(net 138 "unconnected-(J201-Pad19)")
			(pintype "passive+no_connect")
		)
		(pad "20" smd rect
			(at -6.197 -1.534 270)
			(size 0.2 0.7)
			(layers "F.Cu" "F.Mask" "F.Paste")
			(net 216 "/Compute module/~{EEPROM_WP}")
			(pintype "passive")
		)
		(pad "21" smd rect
			(at -5.797 1.547 270)
			(size 0.2 0.7)
			(layers "F.Cu" "F.Mask" "F.Paste")
			(net 137 "Net-(J201-Pad21)")
			(pintype "passive")
		)
		(pad "22" smd rect
			(at -5.797 -1.534 270)
			(size 0.2 0.7)
			(layers "F.Cu" "F.Mask" "F.Paste")
			(net 3 "GND")
			(pintype "passive")
		)
		(pad "23" smd rect
			(at -5.398 1.547 270)
			(size 0.2 0.7)
			(layers "F.Cu" "F.Mask" "F.Paste")
			(net 3 "GND")
			(pintype "passive")
		)
		(pad "24" smd rect
			(at -5.398 -1.534 270)
			(size 0.2 0.7)
			(layers "F.Cu" "F.Mask" "F.Paste")
			(net 217 "/Compute module/GPIO.26")
			(pintype "passive")
		)
		(pad "25" smd rect
			(at -4.997 1.547 270)
			(size 0.2 0.7)
			(layers "F.Cu" "F.Mask" "F.Paste")
			(net 218 "/Compute module/GPIO.21")
			(pintype "passive")
		)
		(pad "26" smd rect
			(at -4.997 -1.534 270)
			(size 0.2 0.7)
			(layers "F.Cu" "F.Mask" "F.Paste")
			(net 219 "/Compute module/GPIO.19")
			(pintype "passive")
		)
		(pad "27" smd rect
			(at -4.596 1.547 270)
			(size 0.2 0.7)
			(layers "F.Cu" "F.Mask" "F.Paste")
			(net 220 "/Compute module/GPIO.20")
			(pintype "passive")
		)
		(pad "28" smd rect
			(at -4.596 -1.534 270)
			(size 0.2 0.7)
			(layers "F.Cu" "F.Mask" "F.Paste")
			(net 221 "/Compute module/GPIO.13{slash}TXD5")
			(pintype "passive")
		)
		(pad "29" smd rect
			(at -4.197 1.547 270)
			(size 0.2 0.7)
			(layers "F.Cu" "F.Mask" "F.Paste")
			(net 222 "/Compute module/GPIO.16")
			(pintype "passive")
		)
		(pad "30" smd rect
			(at -4.197 -1.534 270)
			(size 0.2 0.7)
			(layers "F.Cu" "F.Mask" "F.Paste")
			(net 223 "/Compute module/GPIO.6")
			(pintype "passive")
		)
		(pad "31" smd rect
			(at -3.795 1.547 270)
			(size 0.2 0.7)
			(layers "F.Cu" "F.Mask" "F.Paste")
			(net 224 "/Compute module/GPIO.12{slash}RXD5")
			(pintype "passive")
		)
		(pad "32" smd rect
			(at -3.795 -1.534 270)
			(size 0.2 0.7)
			(layers "F.Cu" "F.Mask" "F.Paste")
			(net 3 "GND")
			(pintype "passive")
		)
		(pad "33" smd rect
			(at -3.396 1.547 270)
			(size 0.2 0.7)
			(layers "F.Cu" "F.Mask" "F.Paste")
			(net 3 "GND")
			(pintype "passive")
		)
		(pad "34" smd rect
			(at -3.396 -1.534 270)
			(size 0.2 0.7)
			(layers "F.Cu" "F.Mask" "F.Paste")
			(net 225 "/Compute module/GPIO.5{slash}RXD3")
			(pintype "passive")
		)
		(pad "35" smd rect
			(at -2.997 1.547 270)
			(size 0.2 0.7)
			(layers "F.Cu" "F.Mask" "F.Paste")
			(net 446 "/Compute module/GPIO.1{slash}SCL0")
			(pintype "passive")
		)
		(pad "36" smd rect
			(at -2.997 -1.534 270)
			(size 0.2 0.7)
			(layers "F.Cu" "F.Mask" "F.Paste")
			(net 447 "/Compute module/GPIO.0{slash}SDA0")
			(pintype "passive")
		)
		(pad "37" smd rect
			(at -2.598 1.547 270)
			(size 0.2 0.7)
			(layers "F.Cu" "F.Mask" "F.Paste")
			(net 226 "/Compute module/GPIO.7")
			(pintype "passive")
		)
		(pad "38" smd rect
			(at -2.598 -1.534 270)
			(size 0.2 0.7)
			(layers "F.Cu" "F.Mask" "F.Paste")
			(net 227 "/Compute module/GPIO.11")
			(pintype "passive")
		)
		(pad "39" smd rect
			(at -2.198 1.547 270)
			(size 0.2 0.7)
			(layers "F.Cu" "F.Mask" "F.Paste")
			(net 228 "/Compute module/GPIO.8{slash}TXD4")
			(pintype "passive")
		)
		(pad "40" smd rect
			(at -2.198 -1.534 270)
			(size 0.2 0.7)
			(layers "F.Cu" "F.Mask" "F.Paste")
			(net 229 "/Compute module/GPIO.9{slash}RXD4")
			(pintype "passive")
		)
		(pad "41" smd rect
			(at -1.798 1.547 270)
			(size 0.2 0.7)
			(layers "F.Cu" "F.Mask" "F.Paste")
			(net 230 "/Compute module/GPIO.25")
			(pintype "passive")
		)
		(pad "42" smd rect
			(at -1.798 -1.534 270)
			(size 0.2 0.7)
			(layers "F.Cu" "F.Mask" "F.Paste")
			(net 3 "GND")
			(pintype "passive")
		)
		(pad "43" smd rect
			(at -1.396 1.547 270)
			(size 0.2 0.7)
			(layers "F.Cu" "F.Mask" "F.Paste")
			(net 231 "/Compute module/PolarfireID")
			(pintype "passive")
		)
		(pad "44" smd rect
			(at -1.396 -1.534 270)
			(size 0.2 0.7)
			(layers "F.Cu" "F.Mask" "F.Paste")
			(net 232 "/Compute module/GPIO.10")
			(pintype "passive")
		)
		(pad "45" smd rect
			(at -0.997 1.547 270)
			(size 0.2 0.7)
			(layers "F.Cu" "F.Mask" "F.Paste")
			(net 233 "/Compute module/GPIO.24")
			(pintype "passive")
		)
		(pad "46" smd rect
			(at -0.997 -1.534 270)
			(size 0.2 0.7)
			(layers "F.Cu" "F.Mask" "F.Paste")
			(net 234 "/Compute module/GPIO.22")
			(pintype "passive")
		)
		(pad "47" smd rect
			(at -0.597 1.547 270)
			(size 0.2 0.7)
			(layers "F.Cu" "F.Mask" "F.Paste")
			(net 235 "/Compute module/GPIO.23")
			(pintype "passive")
		)
		(pad "48" smd rect
			(at -0.597 -1.534 270)
			(size 0.2 0.7)
			(layers "F.Cu" "F.Mask" "F.Paste")
			(net 236 "/Compute module/GPIO.27")
			(pintype "passive")
		)
		(pad "49" smd rect
			(at -0.198 1.547 270)
			(size 0.2 0.7)
			(layers "F.Cu" "F.Mask" "F.Paste")
			(net 237 "/Compute module/GPIO.18")
			(pintype "passive")
		)
		(pad "50" smd rect
			(at -0.198 -1.534 270)
			(size 0.2 0.7)
			(layers "F.Cu" "F.Mask" "F.Paste")
			(net 238 "/Compute module/GPIO.17")
			(pintype "passive")
		)
		(pad "51" smd rect
			(at 0.203 1.547 270)
			(size 0.2 0.7)
			(layers "F.Cu" "F.Mask" "F.Paste")
			(net 239 "/Compute module/GPIO.14{slash}RXD0")
			(pintype "passive")
		)
		(pad "52" smd rect
			(at 0.203 -1.534 270)
			(size 0.2 0.7)
			(layers "F.Cu" "F.Mask" "F.Paste")
			(net 3 "GND")
			(pintype "passive")
		)
		(pad "53" smd rect
			(at 0.602 1.547 270)
			(size 0.2 0.7)
			(layers "F.Cu" "F.Mask" "F.Paste")
			(net 3 "GND")
			(pintype "passive")
		)
		(pad "54" smd rect
			(at 0.602 -1.534 270)
			(size 0.2 0.7)
			(layers "F.Cu" "F.Mask" "F.Paste")
			(net 240 "/Compute module/GPIO.4{slash}TXD3")
			(pintype "passive")
		)
		(pad "55" smd rect
			(at 1.002 1.547 270)
			(size 0.2 0.7)
			(layers "F.Cu" "F.Mask" "F.Paste")
			(net 241 "/Compute module/GPIO.15{slash}TXD0")
			(pintype "passive")
		)
		(pad "56" smd rect
			(at 1.002 -1.534 270)
			(size 0.2 0.7)
			(layers "F.Cu" "F.Mask" "F.Paste")
			(net 242 "/Compute module/GPIO.3")
			(pintype "passive")
		)
		(pad "57" smd rect
			(at 1.401 1.547 270)
			(size 0.2 0.7)
			(layers "F.Cu" "F.Mask" "F.Paste")
			(net 7 "/Compute module/SDIO.CLK")
			(pintype "passive")
		)
		(pad "58" smd rect
			(at 1.401 -1.534 270)
			(size 0.2 0.7)
			(layers "F.Cu" "F.Mask" "F.Paste")
			(net 243 "/Compute module/GPIO.2")
			(pintype "passive")
		)
		(pad "59" smd rect
			(at 1.803 1.547 270)
			(size 0.2 0.7)
			(layers "F.Cu" "F.Mask" "F.Paste")
			(net 3 "GND")
			(pintype "passive")
		)
		(pad "60" smd rect
			(at 1.803 -1.534 270)
			(size 0.2 0.7)
			(layers "F.Cu" "F.Mask" "F.Paste")
			(net 3 "GND")
			(pintype "passive")
		)
		(pad "61" smd rect
			(at 2.203 1.547 270)
			(size 0.2 0.7)
			(layers "F.Cu" "F.Mask" "F.Paste")
			(net 11 "/Compute module/SDIO.D3")
			(pintype "passive")
		)
		(pad "62" smd rect
			(at 2.203 -1.534 270)
			(size 0.2 0.7)
			(layers "F.Cu" "F.Mask" "F.Paste")
			(net 8 "/Compute module/SDIO.CMD")
			(pintype "passive")
		)
		(pad "63" smd rect
			(at 2.603 1.547 270)
			(size 0.2 0.7)
			(layers "F.Cu" "F.Mask" "F.Paste")
			(net 6 "/Compute module/SDIO.D0")
			(pintype "passive")
		)
		(pad "64" smd rect
			(at 2.603 -1.534 270)
			(size 0.2 0.7)
			(layers "F.Cu" "F.Mask" "F.Paste")
			(net 136 "unconnected-(J201-Pad64)")
			(pintype "passive+no_connect")
		)
		(pad "65" smd rect
			(at 3.002 1.547 270)
			(size 0.2 0.7)
			(layers "F.Cu" "F.Mask" "F.Paste")
			(net 3 "GND")
			(pintype "passive")
		)
		(pad "66" smd rect
			(at 3.002 -1.534 270)
			(size 0.2 0.7)
			(layers "F.Cu" "F.Mask" "F.Paste")
			(net 3 "GND")
			(pintype "passive")
		)
		(pad "67" smd rect
			(at 3.402 1.547 270)
			(size 0.2 0.7)
			(layers "F.Cu" "F.Mask" "F.Paste")
			(net 5 "/Compute module/SDIO.D1")
			(pintype "passive")
		)
		(pad "68" smd rect
			(at 3.402 -1.534 270)
			(size 0.2 0.7)
			(layers "F.Cu" "F.Mask" "F.Paste")
			(net 135 "unconnected-(J201-Pad68)")
			(pintype "passive+no_connect")
		)
		(pad "69" smd rect
			(at 3.802 1.547 270)
			(size 0.2 0.7)
			(layers "F.Cu" "F.Mask" "F.Paste")
			(net 12 "/Compute module/SDIO.D2")
			(pintype "passive")
		)
		(pad "70" smd rect
			(at 3.802 -1.534 270)
			(size 0.2 0.7)
			(layers "F.Cu" "F.Mask" "F.Paste")
			(net 134 "unconnected-(J201-Pad70)")
			(pintype "passive+no_connect")
		)
		(pad "71" smd rect
			(at 4.203 1.547 270)
			(size 0.2 0.7)
			(layers "F.Cu" "F.Mask" "F.Paste")
			(net 3 "GND")
			(pintype "passive")
		)
		(pad "72" smd rect
			(at 4.203 -1.534 270)
			(size 0.2 0.7)
			(layers "F.Cu" "F.Mask" "F.Paste")
			(net 133 "unconnected-(J201-Pad72)")
			(pintype "passive+no_connect")
		)
		(pad "73" smd rect
			(at 4.602 1.547 270)
			(size 0.2 0.7)
			(layers "F.Cu" "F.Mask" "F.Paste")
			(net 129 "Net-(J201-Pad73)")
			(pintype "passive")
		)
		(pad "74" smd rect
			(at 4.602 -1.534 270)
			(size 0.2 0.7)
			(layers "F.Cu" "F.Mask" "F.Paste")
			(net 3 "GND")
			(pintype "passive")
		)
		(pad "75" smd rect
			(at 5.002 1.547 270)
			(size 0.2 0.7)
			(layers "F.Cu" "F.Mask" "F.Paste")
			(net 131 "unconnected-(J201-Pad75)")
			(pintype "passive+no_connect")
		)
		(pad "76" smd rect
			(at 5.002 -1.534 270)
			(size 0.2 0.7)
			(layers "F.Cu" "F.Mask" "F.Paste")
			(net 130 "Net-(J201-Pad76)")
			(pintype "passive")
		)
		(pad "77" smd rect
			(at 5.403 1.547 270)
			(size 0.2 0.7)
			(layers "F.Cu" "F.Mask" "F.Paste")
			(net 10 "+5V")
			(pintype "passive")
		)
		(pad "78" smd rect
			(at 5.403 -1.534 270)
			(size 0.2 0.7)
			(layers "F.Cu" "F.Mask" "F.Paste")
			(net 18 "V_{IO}")
			(pintype "passive")
		)
		(pad "79" smd rect
			(at 5.802 1.547 270)
			(size 0.2 0.7)
			(layers "F.Cu" "F.Mask" "F.Paste")
			(net 10 "+5V")
			(pintype "passive")
		)
		(pad "80" smd rect
			(at 5.802 -1.534 270)
			(size 0.2 0.7)
			(layers "F.Cu" "F.Mask" "F.Paste")
			(net 142 "/CSI/I_{2}C1.SCL")
			(pintype "passive")
		)
		(pad "81" smd rect
			(at 6.203 1.547 270)
			(size 0.2 0.7)
			(layers "F.Cu" "F.Mask" "F.Paste")
			(net 10 "+5V")
			(pintype "passive")
		)
		(pad "82" smd rect
			(at 6.203 -1.534 270)
			(size 0.2 0.7)
			(layers "F.Cu" "F.Mask" "F.Paste")
			(net 143 "/CSI/I_{2}C1.SDA")
			(pintype "passive")
		)
		(pad "83" smd rect
			(at 6.602 1.547 270)
			(size 0.2 0.7)
			(layers "F.Cu" "F.Mask" "F.Paste")
			(net 10 "+5V")
			(pintype "passive")
		)
		(pad "84" smd rect
			(at 6.602 -1.534 270)
			(size 0.2 0.7)
			(layers "F.Cu" "F.Mask" "F.Paste")
			(net 132 "/Compute module/CM4_3V3")
			(pintype "passive")
		)
		(pad "85" smd rect
			(at 7.001 1.547 270)
			(size 0.2 0.7)
			(layers "F.Cu" "F.Mask" "F.Paste")
			(net 10 "+5V")
			(pintype "passive")
		)
		(pad "86" smd rect
			(at 7.001 -1.534 270)
			(size 0.2 0.7)
			(layers "F.Cu" "F.Mask" "F.Paste")
			(net 132 "/Compute module/CM4_3V3")
			(pintype "passive")
		)
		(pad "87" smd rect
			(at 7.403 1.547 270)
			(size 0.2 0.7)
			(layers "F.Cu" "F.Mask" "F.Paste")
			(net 10 "+5V")
			(pintype "passive")
		)
		(pad "88" smd rect
			(at 7.403 -1.534 270)
			(size 0.2 0.7)
			(layers "F.Cu" "F.Mask" "F.Paste")
			(net 22 "+1V8")
			(pintype "passive")
		)
		(pad "89" smd rect
			(at 7.802 1.547 270)
			(size 0.2 0.7)
			(layers "F.Cu" "F.Mask" "F.Paste")
			(net 247 "/Compute module/WL_nDis")
			(pintype "passive")
		)
		(pad "90" smd rect
			(at 7.802 -1.534 270)
			(size 0.2 0.7)
			(layers "F.Cu" "F.Mask" "F.Paste")
			(net 22 "+1V8")
			(pintype "passive")
		)
		(pad "91" smd rect
			(at 8.202 1.547 270)
			(size 0.2 0.7)
			(layers "F.Cu" "F.Mask" "F.Paste")
			(net 248 "/Compute module/BT_nDis")
			(pintype "passive")
		)
		(pad "92" smd rect
			(at 8.202 -1.534 270)
			(size 0.2 0.7)
			(layers "F.Cu" "F.Mask" "F.Paste")
			(net 249 "/Compute module/RUN_PG")
			(pintype "passive")
		)
		(pad "93" smd rect
			(at 8.602 1.547 270)
			(size 0.2 0.7)
			(layers "F.Cu" "F.Mask" "F.Paste")
			(net 250 "/Compute module/~{RPi_BOOT}")
			(pintype "passive")
		)
		(pad "94" smd rect
			(at 8.602 -1.534 270)
			(size 0.2 0.7)
			(layers "F.Cu" "F.Mask" "F.Paste")
			(net 251 "/Compute module/GPIO.AIN1")
			(pintype "passive")
		)
		(pad "95" smd rect
			(at 9.002 1.547 270)
			(size 0.2 0.7)
			(layers "F.Cu" "F.Mask" "F.Paste")
			(net 252 "/Compute module/~{PWR_LED}")
			(pintype "passive")
		)
		(pad "96" smd rect
			(at 9.002 -1.534 270)
			(size 0.2 0.7)
			(layers "F.Cu" "F.Mask" "F.Paste")
			(net 253 "/Compute module/GPIO.AIN0")
			(pintype "passive")
		)
		(pad "97" smd rect
			(at 9.403 1.547 270)
			(size 0.2 0.7)
			(layers "F.Cu" "F.Mask" "F.Paste")
			(net 254 "/Compute module/CAM_GPIO")
			(pintype "passive")
		)
		(pad "98" smd rect
			(at 9.403 -1.534 270)
			(size 0.2 0.7)
			(layers "F.Cu" "F.Mask" "F.Paste")
			(net 3 "GND")
			(pintype "passive")
		)
		(pad "99" smd rect
			(at 9.803 1.547 270)
			(size 0.2 0.7)
			(layers "F.Cu" "F.Mask" "F.Paste")
			(net 255 "/Compute module/~{RPi_RST}")
			(pintype "passive")
		)
		(pad "100" smd rect
			(at 9.803 -1.534 270)
			(size 0.2 0.7)
			(layers "F.Cu" "F.Mask" "F.Paste")
			(net 128 "/Compute module/nEXTRST")
			(pintype "passive")
		)
	)
	(footprint "antmicro-footprints:C_0402_1005Metric"
		(layer "F.Cu")
		(at 86.467962 148.2165)
		(descr "Capacitor SMD 0402")
		(tags "capacitor SMD 0402")
		(property "Reference" "C936"
			(at -0.667962 1.6085 0)
			(layer "F.SilkS")
			(effects
				(font
					(size 0.7 0.7)
					(thickness 0.15)
				)
				(justify right bottom)
			)
		)
		(property "Value" "C_100n_0402"
			(at -1.022927 2.155213 0)
			(layer "F.Fab")
			(effects
				(font
					(size 0.7 0.7)
					(thickness 0.15)
				)
				(justify left bottom)
			)
		)
		(property "Datasheet" "https://www.murata.com/products/productdetail?partno=GRM155R61H104KE14%23"
			(at 0 0 0)
			(layer "F.Fab")
			(hide yes)
			(effects
				(font
					(size 1.27 1.27)
					(thickness 0.15)
				)
			)
		)
		(property "MPN" "GRM155R61H104KE14D"
			(at 0 0 0)
			(unlocked yes)
			(layer "F.Fab")
			(hide yes)
			(effects
				(font
					(size 1 1)
					(thickness 0.15)
				)
			)
		)
		(property "Manufacturer" "Murata"
			(at 0 0 0)
			(unlocked yes)
			(layer "F.Fab")
			(hide yes)
			(effects
				(font
					(size 1 1)
					(thickness 0.15)
				)
			)
		)
		(property "License" "Apache-2.0"
			(at 0 0 0)
			(unlocked yes)
			(layer "F.Fab")
			(hide yes)
			(effects
				(font
					(size 1 1)
					(thickness 0.15)
				)
			)
		)
		(property "Author" "Antmicro"
			(at 0 0 0)
			(unlocked yes)
			(layer "F.Fab")
			(hide yes)
			(effects
				(font
					(size 1 1)
					(thickness 0.15)
				)
			)
		)
		(property "Val" "100n"
			(at 0 0 0)
			(unlocked yes)
			(layer "F.Fab")
			(hide yes)
			(effects
				(font
					(size 1 1)
					(thickness 0.15)
				)
			)
		)
		(property "Voltage" "50V"
			(at 0 0 0)
			(unlocked yes)
			(layer "F.Fab")
			(hide yes)
			(effects
				(font
					(size 1 1)
					(thickness 0.15)
				)
			)
		)
		(property "Dielectric" "X5R"
			(at 0 0 0)
			(unlocked yes)
			(layer "F.Fab")
			(hide yes)
			(effects
				(font
					(size 1 1)
					(thickness 0.15)
				)
			)
		)
		(sheetname "/USB/")
		(sheetfile "usb.kicad_sch")
		(attr smd)
		(fp_rect
			(start -0.925 -0.47)
			(end 0.925 0.47)
			(stroke
				(width 0.05)
				(type default)
			)
			(fill no)
			(layer "F.CrtYd")
		)
		(fp_line
			(start -0.494 -0.25)
			(end 0.504 -0.25)
			(stroke
				(width 0.15)
				(type solid)
			)
			(layer "F.Fab")
		)
		(fp_line
			(start -0.494 0.248)
			(end -0.494 -0.25)
			(stroke
				(width 0.15)
				(type solid)
			)
			(layer "F.Fab")
		)
		(fp_line
			(start 0.504 -0.25)
			(end 0.504 0.248)
			(stroke
				(width 0.15)
				(type solid)
			)
			(layer "F.Fab")
		)
		(fp_line
			(start 0.504 0.248)
			(end -0.494 0.248)
			(stroke
				(width 0.15)
				(type solid)
			)
			(layer "F.Fab")
		)
		(fp_text user "License: Apache-2.0"
			(at -0.939 5.799 0)
			(layer "F.Fab")
			(effects
				(font
					(size 0.7 0.7)
					(thickness 0.15)
				)
				(justify left bottom)
			)
		)
		(fp_text user "${REFERENCE}"
			(at -0.939 4.599 0)
			(layer "F.Fab")
			(effects
				(font
					(size 0.7 0.7)
					(thickness 0.15)
				)
				(justify left bottom)
			)
		)
		(fp_text user "Author: Antmicro"
			(at -0.939 3.399 0)
			(layer "F.Fab")
			(effects
				(font
					(size 0.7 0.7)
					(thickness 0.15)
				)
				(justify left bottom)
			)
		)
		(pad "1" smd roundrect
			(at -0.48 0)
			(size 0.59 0.64)
			(layers "F.Cu" "F.Mask" "F.Paste")
			(roundrect_rratio 0.25)
			(net 3 "GND")
			(pintype "passive")
		)
		(pad "2" smd roundrect
			(at 0.48 0)
			(size 0.59 0.64)
			(layers "F.Cu" "F.Mask" "F.Paste")
			(roundrect_rratio 0.25)
			(net 9 "+3V3")
			(pintype "passive")
		)
	)
	(footprint "antmicro-footprints:C_0402_1005Metric"
		(layer "F.Cu")
		(at 139.017962 163.4165 180)
		(descr "Capacitor SMD 0402")
		(tags "capacitor SMD 0402")
		(property "Reference" "C507"
			(at -1.05 -2.57 0)
			(layer "F.SilkS")
			(effects
				(font
					(size 0.7 0.7)
					(thickness 0.15)
				)
				(justify right bottom)
			)
		)
		(property "Value" "C_1u_0402"
			(at -1.022927 2.155213 0)
			(layer "F.Fab")
			(effects
				(font
					(size 0.7 0.7)
					(thickness 0.15)
				)
				(justify right bottom)
			)
		)
		(property "Datasheet" "https://product.tdk.com/en/search/capacitor/ceramic/mlcc/info?part_no=C1005X6S1A105K050BC"
			(at 0 0 180)
			(layer "F.Fab")
			(hide yes)
			(effects
				(font
					(size 1.27 1.27)
					(thickness 0.15)
				)
			)
		)
		(property "Manufacturer" "TDK"
			(at 0 0 180)
			(unlocked yes)
			(layer "F.Fab")
			(hide yes)
			(effects
				(font
					(size 1 1)
					(thickness 0.15)
				)
			)
		)
		(property "MPN" "C1005X6S1A105K050BC"
			(at 0 0 180)
			(unlocked yes)
			(layer "F.Fab")
			(hide yes)
			(effects
				(font
					(size 1 1)
					(thickness 0.15)
				)
			)
		)
		(property "Val" "1u"
			(at 0 0 180)
			(unlocked yes)
			(layer "F.Fab")
			(hide yes)
			(effects
				(font
					(size 1 1)
					(thickness 0.15)
				)
			)
		)
		(property "License" "Apache-2.0"
			(at 0 0 180)
			(unlocked yes)
			(layer "F.Fab")
			(hide yes)
			(effects
				(font
					(size 1 1)
					(thickness 0.15)
				)
			)
		)
		(property "Author" "Antmicro"
			(at 0 0 180)
			(unlocked yes)
			(layer "F.Fab")
			(hide yes)
			(effects
				(font
					(size 1 1)
					(thickness 0.15)
				)
			)
		)
		(property "Voltage" ""
			(at 0 0 180)
			(unlocked yes)
			(layer "F.Fab")
			(hide yes)
			(effects
				(font
					(size 1 1)
					(thickness 0.15)
				)
			)
		)
		(property "Dielectric" ""
			(at 0 0 180)
			(unlocked yes)
			(layer "F.Fab")
			(hide yes)
			(effects
				(font
					(size 1 1)
					(thickness 0.15)
				)
			)
		)
		(sheetname "/NVMe & microSD/")
		(sheetfile "nvme-micro-sd.kicad_sch")
		(attr smd)
		(fp_rect
			(start -0.925 -0.47)
			(end 0.925 0.47)
			(stroke
				(width 0.05)
				(type default)
			)
			(fill no)
			(layer "F.CrtYd")
		)
		(fp_line
			(start 0.504 0.248)
			(end -0.494 0.248)
			(stroke
				(width 0.15)
				(type solid)
			)
			(layer "F.Fab")
		)
		(fp_line
			(start 0.504 -0.25)
			(end 0.504 0.248)
			(stroke
				(width 0.15)
				(type solid)
			)
			(layer "F.Fab")
		)
		(fp_line
			(start -0.494 0.248)
			(end -0.494 -0.25)
			(stroke
				(width 0.15)
				(type solid)
			)
			(layer "F.Fab")
		)
		(fp_line
			(start -0.494 -0.25)
			(end 0.504 -0.25)
			(stroke
				(width 0.15)
				(type solid)
			)
			(layer "F.Fab")
		)
		(fp_text user "License: Apache-2.0"
			(at -0.939 5.799 180)
			(layer "F.Fab")
			(effects
				(font
					(size 0.7 0.7)
					(thickness 0.15)
				)
				(justify left bottom)
			)
		)
		(fp_text user "${REFERENCE}"
			(at -0.939 4.599 180)
			(layer "F.Fab")
			(effects
				(font
					(size 0.7 0.7)
					(thickness 0.15)
				)
				(justify left bottom)
			)
		)
		(fp_text user "Author: Antmicro"
			(at -0.939 3.399 180)
			(layer "F.Fab")
			(effects
				(font
					(size 0.7 0.7)
					(thickness 0.15)
				)
				(justify left bottom)
			)
		)
		(pad "1" smd roundrect
			(at -0.48 0 180)
			(size 0.59 0.64)
			(layers "F.Cu" "F.Mask" "F.Paste")
			(roundrect_rratio 0.25)
			(net 3 "GND")
			(pintype "passive")
		)
		(pad "2" smd roundrect
			(at 0.48 0 180)
			(size 0.59 0.64)
			(layers "F.Cu" "F.Mask" "F.Paste")
			(roundrect_rratio 0.25)
			(net 9 "+3V3")
			(pintype "passive")
		)
	)
	(footprint "antmicro-footprints:FB_0402_1005Metric"
		(layer "F.Cu")
		(at 92.142962 146.2415 90)
		(descr "Ferrite Bead SMD 0402")
		(tags "ferrite bead SMD 0402")
		(property "Reference" "FB901"
			(at -3.23 1.175 90)
			(layer "F.SilkS")
			(effects
				(font
					(size 0.7 0.7)
					(thickness 0.15)
				)
				(justify left bottom)
			)
		)
		(property "Value" "FB_120Z_1.3A_Murata-BLM15PD_0402"
			(at 0 1.4 90)
			(layer "F.Fab")
			(effects
				(font
					(size 0.7 0.7)
					(thickness 0.15)
				)
				(justify left bottom)
			)
		)
		(property "Datasheet" "https://www.murata.com/en-us/products/productdata/8796740059166/ENFA0018.pdf"
			(at 0 0 90)
			(layer "F.Fab")
			(hide yes)
			(effects
				(font
					(size 1.27 1.27)
					(thickness 0.15)
				)
			)
		)
		(property "MPN" "BLM15PD121SN1D"
			(at 0 0 90)
			(unlocked yes)
			(layer "F.Fab")
			(hide yes)
			(effects
				(font
					(size 1 1)
					(thickness 0.15)
				)
			)
		)
		(property "Manufacturer" "Murata"
			(at 0 0 90)
			(unlocked yes)
			(layer "F.Fab")
			(hide yes)
			(effects
				(font
					(size 1 1)
					(thickness 0.15)
				)
			)
		)
		(property "Author" "Antmicro"
			(at 0 0 90)
			(unlocked yes)
			(layer "F.Fab")
			(hide yes)
			(effects
				(font
					(size 1 1)
					(thickness 0.15)
				)
			)
		)
		(property "License" "Apache-2.0"
			(at 0 0 90)
			(unlocked yes)
			(layer "F.Fab")
			(hide yes)
			(effects
				(font
					(size 1 1)
					(thickness 0.15)
				)
			)
		)
		(property "Val" "120Z/1.3A"
			(at 0 0 90)
			(unlocked yes)
			(layer "F.Fab")
			(hide yes)
			(effects
				(font
					(size 1 1)
					(thickness 0.15)
				)
			)
		)
		(property "Current" ""
			(at 0 0 90)
			(unlocked yes)
			(layer "F.Fab")
			(hide yes)
			(effects
				(font
					(size 1 1)
					(thickness 0.15)
				)
			)
		)
		(sheetname "/USB/")
		(sheetfile "usb.kicad_sch")
		(attr smd)
		(fp_rect
			(start -0.925 -0.47)
			(end 0.925 0.47)
			(stroke
				(width 0.05)
				(type default)
			)
			(fill no)
			(layer "F.CrtYd")
		)
		(fp_rect
			(start -0.5 -0.25)
			(end 0.5 0.25)
			(stroke
				(width 0.15)
				(type solid)
			)
			(fill no)
			(layer "F.Fab")
		)
		(fp_text user "${REFERENCE}"
			(at -0.95 3.168 90)
			(layer "F.Fab")
			(effects
				(font
					(size 0.7 0.7)
					(thickness 0.15)
				)
				(justify left bottom)
			)
		)
		(fp_text user "License: Apache-2.0"
			(at -0.95 5.169 90)
			(layer "F.Fab")
			(effects
				(font
					(size 0.7 0.7)
					(thickness 0.15)
				)
				(justify left bottom)
			)
		)
		(fp_text user "Author: Antmicro"
			(at -0.95 4.169 90)
			(layer "F.Fab")
			(effects
				(font
					(size 0.7 0.7)
					(thickness 0.15)
				)
				(justify left bottom)
			)
		)
		(pad "1" smd roundrect
			(at -0.48 0 90)
			(size 0.59 0.64)
			(layers "F.Cu" "F.Mask" "F.Paste")
			(roundrect_rratio 0.25)
			(net 27 "/USB/USB_3V3")
			(pintype "passive")
		)
		(pad "2" smd roundrect
			(at 0.48 0 90)
			(size 0.59 0.64)
			(layers "F.Cu" "F.Mask" "F.Paste")
			(roundrect_rratio 0.25)
			(net 31 "/USB/VREGIN")
			(pintype "passive")
		)
	)
	(footprint "antmicro-footprints:C_0402_1005Metric"
		(layer "F.Cu")
		(at 62.117962 177.6915 -90)
		(descr "Capacitor SMD 0402")
		(tags "capacitor SMD 0402")
		(property "Reference" "C824"
			(at -2.805 14.88 90)
			(layer "F.SilkS")
			(effects
				(font
					(size 0.7 0.7)
					(thickness 0.15)
				)
				(justify right bottom)
			)
		)
		(property "Value" "C_39p_0402"
			(at -1.022927 2.155213 90)
			(layer "F.Fab")
			(effects
				(font
					(size 0.7 0.7)
					(thickness 0.15)
				)
				(justify right bottom)
			)
		)
		(property "Datasheet" "https://spicat.kyocera-avx.com/product/mlcc/chartview/04025A390JAT2A/"
			(at 0 0 270)
			(layer "F.Fab")
			(hide yes)
			(effects
				(font
					(size 1.27 1.27)
					(thickness 0.15)
				)
			)
		)
		(property "Description" "SMD Multilayer Ceramic Capacitor, 39 pF, 50 V, 0402 [1005 Metric], ± 5%, C0G / NP0, AVX 0402 MLCC"
			(at 0 0 270)
			(layer "F.Fab")
			(hide yes)
			(effects
				(font
					(size 1.27 1.27)
					(thickness 0.15)
				)
			)
		)
		(property "MPN" "04025A390JAT2A"
			(at 0 0 270)
			(unlocked yes)
			(layer "F.Fab")
			(hide yes)
			(effects
				(font
					(size 1 1)
					(thickness 0.15)
				)
			)
		)
		(property "Manufacturer" "KYOCERA AVX"
			(at 0 0 270)
			(unlocked yes)
			(layer "F.Fab")
			(hide yes)
			(effects
				(font
					(size 1 1)
					(thickness 0.15)
				)
			)
		)
		(property "License" "Apache-2.0"
			(at 0 0 270)
			(unlocked yes)
			(layer "F.Fab")
			(hide yes)
			(effects
				(font
					(size 1 1)
					(thickness 0.15)
				)
			)
		)
		(property "Author" "Antmicro"
			(at 0 0 270)
			(unlocked yes)
			(layer "F.Fab")
			(hide yes)
			(effects
				(font
					(size 1 1)
					(thickness 0.15)
				)
			)
		)
		(property "Val" "39p"
			(at 0 0 270)
			(unlocked yes)
			(layer "F.Fab")
			(hide yes)
			(effects
				(font
					(size 1 1)
					(thickness 0.15)
				)
			)
		)
		(property "Voltage" ""
			(at 0 0 270)
			(unlocked yes)
			(layer "F.Fab")
			(hide yes)
			(effects
				(font
					(size 1 1)
					(thickness 0.15)
				)
			)
		)
		(property "Dielectric" ""
			(at 0 0 270)
			(unlocked yes)
			(layer "F.Fab")
			(hide yes)
			(effects
				(font
					(size 1 1)
					(thickness 0.15)
				)
			)
		)
		(sheetname "/Peripherals/")
		(sheetfile "peripherals.kicad_sch")
		(attr smd)
		(fp_rect
			(start -0.925 -0.47)
			(end 0.925 0.47)
			(stroke
				(width 0.05)
				(type default)
			)
			(fill no)
			(layer "F.CrtYd")
		)
		(fp_line
			(start -0.494 0.248)
			(end -0.494 -0.25)
			(stroke
				(width 0.15)
				(type solid)
			)
			(layer "F.Fab")
		)
		(fp_line
			(start 0.504 0.248)
			(end -0.494 0.248)
			(stroke
				(width 0.15)
				(type solid)
			)
			(layer "F.Fab")
		)
		(fp_line
			(start -0.494 -0.25)
			(end 0.504 -0.25)
			(stroke
				(width 0.15)
				(type solid)
			)
			(layer "F.Fab")
		)
		(fp_line
			(start 0.504 -0.25)
			(end 0.504 0.248)
			(stroke
				(width 0.15)
				(type solid)
			)
			(layer "F.Fab")
		)
		(fp_text user "${REFERENCE}"
			(at -0.939 4.599 270)
			(layer "F.Fab")
			(effects
				(font
					(size 0.7 0.7)
					(thickness 0.15)
				)
				(justify left bottom)
			)
		)
		(fp_text user "Author: Antmicro"
			(at -0.939 3.399 270)
			(layer "F.Fab")
			(effects
				(font
					(size 0.7 0.7)
					(thickness 0.15)
				)
				(justify left bottom)
			)
		)
		(fp_text user "License: Apache-2.0"
			(at -0.939 5.799 270)
			(layer "F.Fab")
			(effects
				(font
					(size 0.7 0.7)
					(thickness 0.15)
				)
				(justify left bottom)
			)
		)
		(pad "1" smd roundrect
			(at -0.48 0 270)
			(size 0.59 0.64)
			(layers "F.Cu" "F.Mask" "F.Paste")
			(roundrect_rratio 0.25)
			(net 3 "GND")
			(pintype "passive")
		)
		(pad "2" smd roundrect
			(at 0.48 0 270)
			(size 0.59 0.64)
			(layers "F.Cu" "F.Mask" "F.Paste")
			(roundrect_rratio 0.25)
			(net 100 "Net-(C811-Pad2)")
			(pintype "passive")
		)
	)
	(footprint "antmicro-footprints:Spacer_Drill3.7mm_H3mm_9774030151R"
		(layer "F.Cu")
		(at 80.520961 176.314 -90)
		(descr "Spacer M=3 h=3mm fi=5.1mm")
		(property "Reference" "H202"
			(at -0.1575 -4.087001 90)
			(layer "F.SilkS")
			(hide yes)
			(effects
				(font
					(size 0.7 0.7)
					(thickness 0.15)
				)
				(justify right bottom)
			)
		)
		(property "Value" "Spacer_Drill3.7mm_H3mm_9774030151R"
			(at 0 4 90)
			(layer "F.Fab")
			(effects
				(font
					(size 0.7 0.7)
					(thickness 0.15)
				)
				(justify right bottom)
			)
		)
		(property "Datasheet" "https://www.we-online.com/catalog/datasheet/9774030151.pdf"
			(at 0 0 270)
			(layer "F.Fab")
			(hide yes)
			(effects
				(font
					(size 1.27 1.27)
					(thickness 0.15)
				)
			)
		)
		(property "Manufacturer" "Würth Elektronik"
			(at 0 0 270)
			(unlocked yes)
			(layer "F.Fab")
			(hide yes)
			(effects
				(font
					(size 1 1)
					(thickness 0.15)
				)
			)
		)
		(property "MPN" "9774030151R"
			(at 0 0 270)
			(unlocked yes)
			(layer "F.Fab")
			(hide yes)
			(effects
				(font
					(size 1 1)
					(thickness 0.15)
				)
			)
		)
		(property "Author" "Antmicro"
			(at 0 0 270)
			(unlocked yes)
			(layer "F.Fab")
			(hide yes)
			(effects
				(font
					(size 1 1)
					(thickness 0.15)
				)
			)
		)
		(property "License" "Apache-2.0"
			(at 0 0 270)
			(unlocked yes)
			(layer "F.Fab")
			(hide yes)
			(effects
				(font
					(size 1 1)
					(thickness 0.15)
				)
			)
		)
		(sheetname "/Compute module/")
		(sheetfile "compute-module.kicad_sch")
		(solder_paste_margin_ratio -1)
		(attr smd)
		(fp_circle
			(center 0 0)
			(end 3.05 0)
			(stroke
				(width 0.05)
				(type solid)
			)
			(fill no)
			(layer "F.CrtYd")
		)
		(fp_circle
			(center 0 0)
			(end 2.6 0)
			(stroke
				(width 0.15)
				(type solid)
			)
			(fill no)
			(layer "F.Fab")
		)
		(fp_text user "${REFERENCE}"
			(at -9.6 6.5 270)
			(layer "F.Fab")
			(effects
				(font
					(size 0.7 0.7)
					(thickness 0.15)
				)
				(justify left bottom)
			)
		)
		(fp_text user "Author: Antmicro"
			(at -9.6 7.7 270)
			(layer "F.Fab")
			(effects
				(font
					(size 0.7 0.7)
					(thickness 0.15)
				)
				(justify left bottom)
			)
		)
		(fp_text user "License: Apache-2.0"
			(at -9.6 8.9 270)
			(layer "F.Fab")
			(effects
				(font
					(size 0.7 0.7)
					(thickness 0.15)
				)
				(justify left bottom)
			)
		)
		(pad "" smd custom
			(at -1.7 -1.7 270)
			(size 0.62 0.62)
			(layers "F.Paste")
			(thermal_bridge_angle 90)
			(options
				(clearance outline)
				(anchor circle)
			)
			(primitives
				(gr_arc
					(start -0.250195 1.279127)
					(mid 0.285453 0.294389)
					(end 1.266786 -0.24747)
					(width 0.2)
				)
				(gr_arc
					(start -0.34334 1.279127)
					(mid 0.218448 0.232561)
					(end 1.259603 -0.339191)
					(width 0.2)
				)
				(gr_arc
					(start -0.436309 1.279127)
					(mid 0.152481 0.169693)
					(end 1.255279 -0.431435)
					(width 0.2)
				)
				(gr_arc
					(start -0.529126 1.279127)
					(mid 0.087542 0.105784)
					(end 1.253811 -0.524161)
					(width 0.2)
				)
				(gr_arc
					(start -0.621807 1.279127)
					(mid 0.0309 0.033527)
					(end 1.275473 -0.621136)
					(width 0.2)
				)
				(gr_arc
					(start -0.71437 1.279127)
					(mid -0.037758 -0.026651)
					(end 1.263664 -0.711602)
					(width 0.2)
				)
				(gr_arc
					(start -0.806826 1.279127)
					(mid -0.105837 -0.087395)
					(end 1.253435 -0.802342)
					(width 0.2)
				)
				(gr_arc
					(start -0.899187 1.279127)
					(mid -0.165236 -0.156885)
					(end 1.267475 -0.897258)
					(width 0.2)
				)
				(gr_arc
					(start -0.991463 1.279127)
					(mid -0.228522 -0.222449)
					(end 1.270645 -0.990112)
					(width 0.2)
				)
				(gr_arc
					(start -1.083663 1.279127)
					(mid -0.294507 -0.285313)
					(end 1.266278 -1.081674)
					(width 0.2)
				)
				(gr_line
					(start 1.279127 -0.250195)
					(end 1.279127 -1.083663)
					(width 0.2)
				)
				(gr_line
					(start -0.250195 1.279127)
					(end -1.083663 1.279127)
					(width 0.2)
				)
			)
		)
		(pad "" smd custom
			(at -1.7 1.7)
			(size 0.62 0.62)
			(layers "F.Paste")
			(thermal_bridge_angle 90)
			(options
				(clearance outline)
				(anchor circle)
			)
			(primitives
				(gr_arc
					(start -0.250195 1.279127)
					(mid 0.285453 0.294389)
					(end 1.266786 -0.24747)
					(width 0.2)
				)
				(gr_arc
					(start -0.34334 1.279127)
					(mid 0.218448 0.232561)
					(end 1.259603 -0.339191)
					(width 0.2)
				)
				(gr_arc
					(start -0.436309 1.279127)
					(mid 0.152481 0.169693)
					(end 1.255279 -0.431435)
					(width 0.2)
				)
				(gr_arc
					(start -0.529126 1.279127)
					(mid 0.087542 0.105784)
					(end 1.253811 -0.524161)
					(width 0.2)
				)
				(gr_arc
					(start -0.621807 1.279127)
					(mid 0.0309 0.033527)
					(end 1.275473 -0.621136)
					(width 0.2)
				)
				(gr_arc
					(start -0.71437 1.279127)
					(mid -0.037758 -0.026651)
					(end 1.263664 -0.711602)
					(width 0.2)
				)
				(gr_arc
					(start -0.806826 1.279127)
					(mid -0.105837 -0.087395)
					(end 1.253435 -0.802342)
					(width 0.2)
				)
				(gr_arc
					(start -0.899187 1.279127)
					(mid -0.165236 -0.156885)
					(end 1.267475 -0.897258)
					(width 0.2)
				)
				(gr_arc
					(start -0.991463 1.279127)
					(mid -0.228522 -0.222449)
					(end 1.270645 -0.990112)
					(width 0.2)
				)
				(gr_arc
					(start -1.083663 1.279127)
					(mid -0.294507 -0.285313)
					(end 1.266278 -1.081674)
					(width 0.2)
				)
				(gr_line
					(start 1.279127 -0.250195)
					(end 1.279127 -1.083663)
					(width 0.2)
				)
				(gr_line
					(start -0.250195 1.279127)
					(end -1.083663 1.279127)
					(width 0.2)
				)
			)
		)
		(pad "" smd custom
			(at 1.7 -1.7 180)
			(size 0.62 0.62)
			(layers "F.Paste")
			(thermal_bridge_angle 90)
			(options
				(clearance outline)
				(anchor circle)
			)
			(primitives
				(gr_arc
					(start -0.250195 1.279127)
					(mid 0.285453 0.294389)
					(end 1.266786 -0.24747)
					(width 0.2)
				)
				(gr_arc
					(start -0.34334 1.279127)
					(mid 0.218448 0.232561)
					(end 1.259603 -0.339191)
					(width 0.2)
				)
				(gr_arc
					(start -0.436309 1.279127)
					(mid 0.152481 0.169693)
					(end 1.255279 -0.431435)
					(width 0.2)
				)
				(gr_arc
					(start -0.529126 1.279127)
					(mid 0.087542 0.105784)
					(end 1.253811 -0.524161)
					(width 0.2)
				)
				(gr_arc
					(start -0.621807 1.279127)
					(mid 0.0309 0.033527)
					(end 1.275473 -0.621136)
					(width 0.2)
				)
				(gr_arc
					(start -0.71437 1.279127)
					(mid -0.037758 -0.026651)
					(end 1.263664 -0.711602)
					(width 0.2)
				)
				(gr_arc
					(start -0.806826 1.279127)
					(mid -0.105837 -0.087395)
					(end 1.253435 -0.802342)
					(width 0.2)
				)
				(gr_arc
					(start -0.899187 1.279127)
					(mid -0.165236 -0.156885)
					(end 1.267475 -0.897258)
					(width 0.2)
				)
				(gr_arc
					(start -0.991463 1.279127)
					(mid -0.228522 -0.222449)
					(end 1.270645 -0.990112)
					(width 0.2)
				)
				(gr_arc
					(start -1.083663 1.279127)
					(mid -0.294507 -0.285313)
					(end 1.266278 -1.081674)
					(width 0.2)
				)
				(gr_line
					(start 1.279127 -0.250195)
					(end 1.279127 -1.083663)
					(width 0.2)
				)
				(gr_line
					(start -0.250195 1.279127)
					(end -1.083663 1.279127)
					(width 0.2)
				)
			)
		)
		(pad "" smd custom
			(at 1.7 1.7 90)
			(size 0.62 0.62)
			(layers "F.Paste")
			(thermal_bridge_angle 90)
			(options
				(clearance outline)
				(anchor circle)
			)
			(primitives
				(gr_arc
					(start -0.250195 1.279127)
					(mid 0.285453 0.294389)
					(end 1.266786 -0.24747)
					(width 0.2)
				)
				(gr_arc
					(start -0.34334 1.279127)
					(mid 0.218448 0.232561)
					(end 1.259603 -0.339191)
					(width 0.2)
				)
				(gr_arc
					(start -0.436309 1.279127)
					(mid 0.152481 0.169693)
					(end 1.255279 -0.431435)
					(width 0.2)
				)
				(gr_arc
					(start -0.529126 1.279127)
					(mid 0.087542 0.105784)
					(end 1.253811 -0.524161)
					(width 0.2)
				)
				(gr_arc
					(start -0.621807 1.279127)
					(mid 0.0309 0.033527)
					(end 1.275473 -0.621136)
					(width 0.2)
				)
				(gr_arc
					(start -0.71437 1.279127)
					(mid -0.037758 -0.026651)
					(end 1.263664 -0.711602)
					(width 0.2)
				)
				(gr_arc
					(start -0.806826 1.279127)
					(mid -0.105837 -0.087395)
					(end 1.253435 -0.802342)
					(width 0.2)
				)
				(gr_arc
					(start -0.899187 1.279127)
					(mid -0.165236 -0.156885)
					(end 1.267475 -0.897258)
					(width 0.2)
				)
				(gr_arc
					(start -0.991463 1.279127)
					(mid -0.228522 -0.222449)
					(end 1.270645 -0.990112)
					(width 0.2)
				)
				(gr_arc
					(start -1.083663 1.279127)
					(mid -0.294507 -0.285313)
					(end 1.266278 -1.081674)
					(width 0.2)
				)
				(gr_line
					(start 1.279127 -0.250195)
					(end 1.279127 -1.083663)
					(width 0.2)
				)
				(gr_line
					(start -0.250195 1.279127)
					(end -1.083663 1.279127)
					(width 0.2)
				)
			)
		)
		(pad "1" thru_hole circle
			(at 0 0 270)
			(size 6 6)
			(drill 3.7)
			(layers "*.Cu" "*.Mask")
			(remove_unused_layers no)
			(net 3 "GND")
			(pintype "passive")
		)
	)
	(footprint "antmicro-footprints:C_0402_1005Metric"
		(layer "F.Cu")
		(at 91.692962 148.2415 90)
		(descr "Capacitor SMD 0402")
		(tags "capacitor SMD 0402")
		(property "Reference" "C927"
			(at -3.755 0.135 90)
			(layer "F.SilkS")
			(effects
				(font
					(size 0.7 0.7)
					(thickness 0.15)
				)
				(justify left bottom)
			)
		)
		(property "Value" "C_18p_0402"
			(at -1.022927 2.155213 90)
			(layer "F.Fab")
			(effects
				(font
					(size 0.7 0.7)
					(thickness 0.15)
				)
				(justify left bottom)
			)
		)
		(property "Datasheet" "https://product.samsungsem.com/mlcc/CL05C180JB51PN.do"
			(at 0 0 90)
			(layer "F.Fab")
			(hide yes)
			(effects
				(font
					(size 1.27 1.27)
					(thickness 0.15)
				)
			)
		)
		(property "Manufacturer" "Samsung Electro-Mechanics"
			(at 0 0 90)
			(unlocked yes)
			(layer "F.Fab")
			(hide yes)
			(effects
				(font
					(size 1 1)
					(thickness 0.15)
				)
			)
		)
		(property "MPN" "CL05C180JB51PNC"
			(at 0 0 90)
			(unlocked yes)
			(layer "F.Fab")
			(hide yes)
			(effects
				(font
					(size 1 1)
					(thickness 0.15)
				)
			)
		)
		(property "Val" "18p"
			(at 0 0 90)
			(unlocked yes)
			(layer "F.Fab")
			(hide yes)
			(effects
				(font
					(size 1 1)
					(thickness 0.15)
				)
			)
		)
		(property "License" "Apache-2.0"
			(at 0 0 90)
			(unlocked yes)
			(layer "F.Fab")
			(hide yes)
			(effects
				(font
					(size 1 1)
					(thickness 0.15)
				)
			)
		)
		(property "Author" "Antmicro"
			(at 0 0 90)
			(unlocked yes)
			(layer "F.Fab")
			(hide yes)
			(effects
				(font
					(size 1 1)
					(thickness 0.15)
				)
			)
		)
		(property "Voltage" ""
			(at 0 0 90)
			(unlocked yes)
			(layer "F.Fab")
			(hide yes)
			(effects
				(font
					(size 1 1)
					(thickness 0.15)
				)
			)
		)
		(property "Dielectric" ""
			(at 0 0 90)
			(unlocked yes)
			(layer "F.Fab")
			(hide yes)
			(effects
				(font
					(size 1 1)
					(thickness 0.15)
				)
			)
		)
		(sheetname "/USB/")
		(sheetfile "usb.kicad_sch")
		(attr smd)
		(fp_rect
			(start -0.925 -0.47)
			(end 0.925 0.47)
			(stroke
				(width 0.05)
				(type default)
			)
			(fill no)
			(layer "F.CrtYd")
		)
		(fp_line
			(start 0.504 -0.25)
			(end 0.504 0.248)
			(stroke
				(width 0.15)
				(type solid)
			)
			(layer "F.Fab")
		)
		(fp_line
			(start -0.494 -0.25)
			(end 0.504 -0.25)
			(stroke
				(width 0.15)
				(type solid)
			)
			(layer "F.Fab")
		)
		(fp_line
			(start 0.504 0.248)
			(end -0.494 0.248)
			(stroke
				(width 0.15)
				(type solid)
			)
			(layer "F.Fab")
		)
		(fp_line
			(start -0.494 0.248)
			(end -0.494 -0.25)
			(stroke
				(width 0.15)
				(type solid)
			)
			(layer "F.Fab")
		)
		(fp_text user "Author: Antmicro"
			(at -0.939 3.399 90)
			(layer "F.Fab")
			(effects
				(font
					(size 0.7 0.7)
					(thickness 0.15)
				)
				(justify left bottom)
			)
		)
		(fp_text user "License: Apache-2.0"
			(at -0.939 5.799 90)
			(layer "F.Fab")
			(effects
				(font
					(size 0.7 0.7)
					(thickness 0.15)
				)
				(justify left bottom)
			)
		)
		(fp_text user "${REFERENCE}"
			(at -0.939 4.599 90)
			(layer "F.Fab")
			(effects
				(font
					(size 0.7 0.7)
					(thickness 0.15)
				)
				(justify left bottom)
			)
		)
		(pad "1" smd roundrect
			(at -0.48 0 90)
			(size 0.59 0.64)
			(layers "F.Cu" "F.Mask" "F.Paste")
			(roundrect_rratio 0.25)
			(net 115 "Net-(U905-OSCO)")
			(pintype "passive")
		)
		(pad "2" smd roundrect
			(at 0.48 0 90)
			(size 0.59 0.64)
			(layers "F.Cu" "F.Mask" "F.Paste")
			(roundrect_rratio 0.25)
			(net 3 "GND")
			(pintype "passive")
		)
	)
	(footprint "antmicro-footprints:SOIC-8_3.9x4.9x1.75mm_P1.27mm"
		(layer "F.Cu")
		(at 80.617962 134.457236)
		(property "Reference" "U902"
			(at -3.84 3.529264 0)
			(layer "F.SilkS")
			(effects
				(font
					(size 0.7 0.7)
					(thickness 0.15)
				)
				(justify left bottom)
			)
		)
		(property "Value" "93AA66C_SOIC"
			(at 0 3.65 0)
			(layer "F.Fab")
			(effects
				(font
					(size 0.7 0.7)
					(thickness 0.15)
				)
				(justify left bottom)
			)
		)
		(property "Datasheet" "https://ww1.microchip.com/downloads/aemDocuments/documents/MPD/ProductDocuments/DataSheets/93AA66X-93LC66X-93C66X-4-Kbit-Microwire-Compatible-Serial-EEPROM-Data-Sheet.pdf"
			(at 0 0 0)
			(layer "F.Fab")
			(hide yes)
			(effects
				(font
					(size 1.27 1.27)
					(thickness 0.15)
				)
			)
		)
		(property "MPN" "93AA66C-I/SN"
			(at 0 0 0)
			(unlocked yes)
			(layer "F.Fab")
			(hide yes)
			(effects
				(font
					(size 1 1)
					(thickness 0.15)
				)
			)
		)
		(property "Manufacturer" "Microchip Technology"
			(at 0 0 0)
			(unlocked yes)
			(layer "F.Fab")
			(hide yes)
			(effects
				(font
					(size 1 1)
					(thickness 0.15)
				)
			)
		)
		(property "Author" "Antmicro"
			(at 0 0 0)
			(unlocked yes)
			(layer "F.Fab")
			(hide yes)
			(effects
				(font
					(size 1 1)
					(thickness 0.15)
				)
			)
		)
		(property "License" "Apache-2.0"
			(at 0 0 0)
			(unlocked yes)
			(layer "F.Fab")
			(hide yes)
			(effects
				(font
					(size 1 1)
					(thickness 0.15)
				)
			)
		)
		(property ki_fp_filters "DIP*W7.62mm* SOIC*3.9x4.9mm*")
		(sheetname "/USB/")
		(sheetfile "usb.kicad_sch")
		(attr smd)
		(fp_line
			(start -1.95 -2.452)
			(end 1.95 -2.45)
			(stroke
				(width 0.15)
				(type solid)
			)
			(layer "F.SilkS")
		)
		(fp_line
			(start -1.95 2.45)
			(end 1.95 2.45)
			(stroke
				(width 0.15)
				(type solid)
			)
			(layer "F.SilkS")
		)
		(fp_circle
			(center -2.4 -2.45)
			(end -2.35 -2.4)
			(stroke
				(width 0.15)
				(type solid)
			)
			(fill yes)
			(layer "F.SilkS")
		)
		(fp_rect
			(start -3.625 -2.7)
			(end 3.625 2.7)
			(stroke
				(width 0.05)
				(type solid)
			)
			(fill no)
			(layer "F.CrtYd")
		)
		(fp_line
			(start -1.95 -1.18)
			(end -0.683 -2.452)
			(stroke
				(width 0.15)
				(type solid)
			)
			(layer "F.Fab")
		)
		(fp_line
			(start -1.95 2.45)
			(end -1.95 -1.18)
			(stroke
				(width 0.15)
				(type solid)
			)
			(layer "F.Fab")
		)
		(fp_line
			(start -0.683 -2.452)
			(end 1.949 -2.452)
			(stroke
				(width 0.15)
				(type solid)
			)
			(layer "F.Fab")
		)
		(fp_line
			(start 1.949 -2.452)
			(end 1.949 2.45)
			(stroke
				(width 0.15)
				(type solid)
			)
			(layer "F.Fab")
		)
		(fp_line
			(start 1.949 2.45)
			(end -1.95 2.45)
			(stroke
				(width 0.15)
				(type solid)
			)
			(layer "F.Fab")
		)
		(fp_text user "License: Apache-2.0"
			(at -3.476 5.099 0)
			(layer "F.Fab")
			(effects
				(font
					(size 0.7 0.7)
					(thickness 0.15)
				)
				(justify left bottom)
			)
		)
		(fp_text user "Author: Antmicro"
			(at -3.476 6.099 0)
			(layer "F.Fab")
			(effects
				(font
					(size 0.7 0.7)
					(thickness 0.15)
				)
				(justify left bottom)
			)
		)
		(fp_text user "${REFERENCE}"
			(at -3.476 7.099 0)
			(layer "F.Fab")
			(effects
				(font
					(size 0.7 0.7)
					(thickness 0.15)
				)
				(justify left bottom)
			)
		)
		(pad "1" smd roundrect
			(at -2.714 -1.905 90)
			(size 0.65 1.525)
			(layers "F.Cu" "F.Mask" "F.Paste")
			(roundrect_rratio 0.25)
			(net 283 "/USB/EECS")
			(pinfunction "CS")
			(pintype "input")
		)
		(pad "2" smd roundrect
			(at -2.714 -0.635 90)
			(size 0.65 1.525)
			(layers "F.Cu" "F.Mask" "F.Paste")
			(roundrect_rratio 0.25)
			(net 282 "/USB/EECLK")
			(pinfunction "CLK")
			(pintype "input")
		)
		(pad "3" smd roundrect
			(at -2.714 0.632 90)
			(size 0.65 1.525)
			(layers "F.Cu" "F.Mask" "F.Paste")
			(roundrect_rratio 0.25)
			(net 281 "/USB/EEDATA")
			(pinfunction "DI")
			(pintype "input")
		)
		(pad "4" smd roundrect
			(at -2.714 1.902 90)
			(size 0.65 1.525)
			(layers "F.Cu" "F.Mask" "F.Paste")
			(roundrect_rratio 0.25)
			(net 377 "Net-(U902-DO)")
			(pinfunction "DO")
			(pintype "tri_state")
		)
		(pad "5" smd roundrect
			(at 2.712 1.902 90)
			(size 0.65 1.525)
			(layers "F.Cu" "F.Mask" "F.Paste")
			(roundrect_rratio 0.25)
			(net 3 "GND")
			(pinfunction "GND")
			(pintype "power_in")
		)
		(pad "6" smd roundrect
			(at 2.712 0.632 90)
			(size 0.65 1.525)
			(layers "F.Cu" "F.Mask" "F.Paste")
			(roundrect_rratio 0.25)
			(net 27 "/USB/USB_3V3")
			(pinfunction "ORG")
			(pintype "input")
		)
		(pad "7" smd roundrect
			(at 2.712 -0.635 90)
			(size 0.65 1.525)
			(layers "F.Cu" "F.Mask" "F.Paste")
			(roundrect_rratio 0.25)
			(net 406 "unconnected-(U902-NC-Pad7)")
			(pinfunction "NC")
			(pintype "no_connect")
		)
		(pad "8" smd roundrect
			(at 2.712 -1.905 90)
			(size 0.65 1.525)
			(layers "F.Cu" "F.Mask" "F.Paste")
			(roundrect_rratio 0.25)
			(net 27 "/USB/USB_3V3")
			(pinfunction "VCC")
			(pintype "power_in")
		)
	)
	(footprint "antmicro-footprints:Spacer_Drill3.7mm_H3mm_9774030151R"
		(layer "F.Cu")
		(at 113.520961 128.314)
		(descr "Spacer M=3 h=3mm fi=5.1mm")
		(property "Reference" "H204"
			(at -0.087999 -3.0375 0)
			(layer "F.SilkS")
			(hide yes)
			(effects
				(font
					(size 0.7 0.7)
					(thickness 0.15)
				)
				(justify left bottom)
			)
		)
		(property "Value" "Spacer_Drill3.7mm_H3mm_9774030151R"
			(at 0 4 0)
			(layer "F.Fab")
			(effects
				(font
					(size 0.7 0.7)
					(thickness 0.15)
				)
				(justify left bottom)
			)
		)
		(property "Datasheet" "https://www.we-online.com/catalog/datasheet/9774030151.pdf"
			(at 0 0 0)
			(layer "F.Fab")
			(hide yes)
			(effects
				(font
					(size 1.27 1.27)
					(thickness 0.15)
				)
			)
		)
		(property "Manufacturer" "Würth Elektronik"
			(at 0 0 0)
			(unlocked yes)
			(layer "F.Fab")
			(hide yes)
			(effects
				(font
					(size 1 1)
					(thickness 0.15)
				)
			)
		)
		(property "MPN" "9774030151R"
			(at 0 0 0)
			(unlocked yes)
			(layer "F.Fab")
			(hide yes)
			(effects
				(font
					(size 1 1)
					(thickness 0.15)
				)
			)
		)
		(property "Author" "Antmicro"
			(at 0 0 0)
			(unlocked yes)
			(layer "F.Fab")
			(hide yes)
			(effects
				(font
					(size 1 1)
					(thickness 0.15)
				)
			)
		)
		(property "License" "Apache-2.0"
			(at 0 0 0)
			(unlocked yes)
			(layer "F.Fab")
			(hide yes)
			(effects
				(font
					(size 1 1)
					(thickness 0.15)
				)
			)
		)
		(sheetname "/Compute module/")
		(sheetfile "compute-module.kicad_sch")
		(solder_paste_margin_ratio -1)
		(attr smd)
		(fp_circle
			(center 0 0)
			(end 3.05 0)
			(stroke
				(width 0.05)
				(type solid)
			)
			(fill no)
			(layer "F.CrtYd")
		)
		(fp_circle
			(center 0 0)
			(end 2.6 0)
			(stroke
				(width 0.15)
				(type solid)
			)
			(fill no)
			(layer "F.Fab")
		)
		(fp_text user "License: Apache-2.0"
			(at -9.6 8.9 0)
			(layer "F.Fab")
			(effects
				(font
					(size 0.7 0.7)
					(thickness 0.15)
				)
				(justify left bottom)
			)
		)
		(fp_text user "Author: Antmicro"
			(at -9.6 7.7 0)
			(layer "F.Fab")
			(effects
				(font
					(size 0.7 0.7)
					(thickness 0.15)
				)
				(justify left bottom)
			)
		)
		(fp_text user "${REFERENCE}"
			(at -9.6 6.5 0)
			(layer "F.Fab")
			(effects
				(font
					(size 0.7 0.7)
					(thickness 0.15)
				)
				(justify left bottom)
			)
		)
		(pad "" smd custom
			(at -1.7 -1.7)
			(size 0.62 0.62)
			(layers "F.Paste")
			(thermal_bridge_angle 90)
			(options
				(clearance outline)
				(anchor circle)
			)
			(primitives
				(gr_arc
					(start -0.250195 1.279127)
					(mid 0.285453 0.294389)
					(end 1.266786 -0.24747)
					(width 0.2)
				)
				(gr_arc
					(start -0.34334 1.279127)
					(mid 0.218448 0.232561)
					(end 1.259603 -0.339191)
					(width 0.2)
				)
				(gr_arc
					(start -0.436309 1.279127)
					(mid 0.152481 0.169693)
					(end 1.255279 -0.431435)
					(width 0.2)
				)
				(gr_arc
					(start -0.529126 1.279127)
					(mid 0.087542 0.105784)
					(end 1.253811 -0.524161)
					(width 0.2)
				)
				(gr_arc
					(start -0.621807 1.279127)
					(mid 0.0309 0.033527)
					(end 1.275473 -0.621136)
					(width 0.2)
				)
				(gr_arc
					(start -0.71437 1.279127)
					(mid -0.037758 -0.026651)
					(end 1.263664 -0.711602)
					(width 0.2)
				)
				(gr_arc
					(start -0.806826 1.279127)
					(mid -0.105837 -0.087395)
					(end 1.253435 -0.802342)
					(width 0.2)
				)
				(gr_arc
					(start -0.899187 1.279127)
					(mid -0.165236 -0.156885)
					(end 1.267475 -0.897258)
					(width 0.2)
				)
				(gr_arc
					(start -0.991463 1.279127)
					(mid -0.228522 -0.222449)
					(end 1.270645 -0.990112)
					(width 0.2)
				)
				(gr_arc
					(start -1.083663 1.279127)
					(mid -0.294507 -0.285313)
					(end 1.266278 -1.081674)
					(width 0.2)
				)
				(gr_line
					(start 1.279127 -0.250195)
					(end 1.279127 -1.083663)
					(width 0.2)
				)
				(gr_line
					(start -0.250195 1.279127)
					(end -1.083663 1.279127)
					(width 0.2)
				)
			)
		)
		(pad "" smd custom
			(at -1.7 1.7 90)
			(size 0.62 0.62)
			(layers "F.Paste")
			(thermal_bridge_angle 90)
			(options
				(clearance outline)
				(anchor circle)
			)
			(primitives
				(gr_arc
					(start -0.250195 1.279127)
					(mid 0.285453 0.294389)
					(end 1.266786 -0.24747)
					(width 0.2)
				)
				(gr_arc
					(start -0.34334 1.279127)
					(mid 0.218448 0.232561)
					(end 1.259603 -0.339191)
					(width 0.2)
				)
				(gr_arc
					(start -0.436309 1.279127)
					(mid 0.152481 0.169693)
					(end 1.255279 -0.431435)
					(width 0.2)
				)
				(gr_arc
					(start -0.529126 1.279127)
					(mid 0.087542 0.105784)
					(end 1.253811 -0.524161)
					(width 0.2)
				)
				(gr_arc
					(start -0.621807 1.279127)
					(mid 0.0309 0.033527)
					(end 1.275473 -0.621136)
					(width 0.2)
				)
				(gr_arc
					(start -0.71437 1.279127)
					(mid -0.037758 -0.026651)
					(end 1.263664 -0.711602)
					(width 0.2)
				)
				(gr_arc
					(start -0.806826 1.279127)
					(mid -0.105837 -0.087395)
					(end 1.253435 -0.802342)
					(width 0.2)
				)
				(gr_arc
					(start -0.899187 1.279127)
					(mid -0.165236 -0.156885)
					(end 1.267475 -0.897258)
					(width 0.2)
				)
				(gr_arc
					(start -0.991463 1.279127)
					(mid -0.228522 -0.222449)
					(end 1.270645 -0.990112)
					(width 0.2)
				)
				(gr_arc
					(start -1.083663 1.279127)
					(mid -0.294507 -0.285313)
					(end 1.266278 -1.081674)
					(width 0.2)
				)
				(gr_line
					(start 1.279127 -0.250195)
					(end 1.279127 -1.083663)
					(width 0.2)
				)
				(gr_line
					(start -0.250195 1.279127)
					(end -1.083663 1.279127)
					(width 0.2)
				)
			)
		)
		(pad "" smd custom
			(at 1.7 -1.7 270)
			(size 0.62 0.62)
			(layers "F.Paste")
			(thermal_bridge_angle 90)
			(options
				(clearance outline)
				(anchor circle)
			)
			(primitives
				(gr_arc
					(start -0.250195 1.279127)
					(mid 0.285453 0.294389)
					(end 1.266786 -0.24747)
					(width 0.2)
				)
				(gr_arc
					(start -0.34334 1.279127)
					(mid 0.218448 0.232561)
					(end 1.259603 -0.339191)
					(width 0.2)
				)
				(gr_arc
					(start -0.436309 1.279127)
					(mid 0.152481 0.169693)
					(end 1.255279 -0.431435)
					(width 0.2)
				)
				(gr_arc
					(start -0.529126 1.279127)
					(mid 0.087542 0.105784)
					(end 1.253811 -0.524161)
					(width 0.2)
				)
				(gr_arc
					(start -0.621807 1.279127)
					(mid 0.0309 0.033527)
					(end 1.275473 -0.621136)
					(width 0.2)
				)
				(gr_arc
					(start -0.71437 1.279127)
					(mid -0.037758 -0.026651)
					(end 1.263664 -0.711602)
					(width 0.2)
				)
				(gr_arc
					(start -0.806826 1.279127)
					(mid -0.105837 -0.087395)
					(end 1.253435 -0.802342)
					(width 0.2)
				)
				(gr_arc
					(start -0.899187 1.279127)
					(mid -0.165236 -0.156885)
					(end 1.267475 -0.897258)
					(width 0.2)
				)
				(gr_arc
					(start -0.991463 1.279127)
					(mid -0.228522 -0.222449)
					(end 1.270645 -0.990112)
					(width 0.2)
				)
				(gr_arc
					(start -1.083663 1.279127)
					(mid -0.294507 -0.285313)
					(end 1.266278 -1.081674)
					(width 0.2)
				)
				(gr_line
					(start 1.279127 -0.250195)
					(end 1.279127 -1.083663)
					(width 0.2)
				)
				(gr_line
					(start -0.250195 1.279127)
					(end -1.083663 1.279127)
					(width 0.2)
				)
			)
		)
		(pad "" smd custom
			(at 1.7 1.7 180)
			(size 0.62 0.62)
			(layers "F.Paste")
			(thermal_bridge_angle 90)
			(options
				(clearance outline)
				(anchor circle)
			)
			(primitives
				(gr_arc
					(start -0.250195 1.279127)
					(mid 0.285453 0.294389)
					(end 1.266786 -0.24747)
					(width 0.2)
				)
				(gr_arc
					(start -0.34334 1.279127)
					(mid 0.218448 0.232561)
					(end 1.259603 -0.339191)
					(width 0.2)
				)
				(gr_arc
					(start -0.436309 1.279127)
					(mid 0.152481 0.169693)
					(end 1.255279 -0.431435)
					(width 0.2)
				)
				(gr_arc
					(start -0.529126 1.279127)
					(mid 0.087542 0.105784)
					(end 1.253811 -0.524161)
					(width 0.2)
				)
				(gr_arc
					(start -0.621807 1.279127)
					(mid 0.0309 0.033527)
					(end 1.275473 -0.621136)
					(width 0.2)
				)
				(gr_arc
					(start -0.71437 1.279127)
					(mid -0.037758 -0.026651)
					(end 1.263664 -0.711602)
					(width 0.2)
				)
				(gr_arc
					(start -0.806826 1.279127)
					(mid -0.105837 -0.087395)
					(end 1.253435 -0.802342)
					(width 0.2)
				)
				(gr_arc
					(start -0.899187 1.279127)
					(mid -0.165236 -0.156885)
					(end 1.267475 -0.897258)
					(width 0.2)
				)
				(gr_arc
					(start -0.991463 1.279127)
					(mid -0.228522 -0.222449)
					(end 1.270645 -0.990112)
					(width 0.2)
				)
				(gr_arc
					(start -1.083663 1.279127)
					(mid -0.294507 -0.285313)
					(end 1.266278 -1.081674)
					(width 0.2)
				)
				(gr_line
					(start 1.279127 -0.250195)
					(end 1.279127 -1.083663)
					(width 0.2)
				)
				(gr_line
					(start -0.250195 1.279127)
					(end -1.083663 1.279127)
					(width 0.2)
				)
			)
		)
		(pad "1" thru_hole circle
			(at 0 0)
			(size 6 6)
			(drill 3.7)
			(layers "*.Cu" "*.Mask")
			(remove_unused_layers no)
			(net 3 "GND")
			(pintype "passive")
		)
	)
	(footprint "antmicro-footprints:R_0402_1005Metric"
		(layer "F.Cu")
		(at 81.837962 124.4715)
		(descr "Resistor SMD 0402")
		(tags "resistor SMD 0402")
		(property "Reference" "R918"
			(at 0.045 1.265 0)
			(layer "F.SilkS")
			(effects
				(font
					(size 0.7 0.7)
					(thickness 0.15)
				)
				(justify left bottom)
			)
		)
		(property "Value" "R_470R_0402"
			(at -1.011843 1.772047 0)
			(layer "F.Fab")
			(effects
				(font
					(size 0.7 0.7)
					(thickness 0.15)
				)
				(justify left bottom)
			)
		)
		(property "Datasheet" "https://www.bourns.com/docs/product-datasheets/cr.pdf"
			(at 0 0 0)
			(layer "F.Fab")
			(hide yes)
			(effects
				(font
					(size 1.27 1.27)
					(thickness 0.15)
				)
			)
		)
		(property "Manufacturer" "Bourns"
			(at 0 0 0)
			(unlocked yes)
			(layer "F.Fab")
			(hide yes)
			(effects
				(font
					(size 1 1)
					(thickness 0.15)
				)
			)
		)
		(property "MPN" "CR0402-FX-4700GLF"
			(at 0 0 0)
			(unlocked yes)
			(layer "F.Fab")
			(hide yes)
			(effects
				(font
					(size 1 1)
					(thickness 0.15)
				)
			)
		)
		(property "Val" "470R"
			(at 0 0 0)
			(unlocked yes)
			(layer "F.Fab")
			(hide yes)
			(effects
				(font
					(size 1 1)
					(thickness 0.15)
				)
			)
		)
		(property "License" "Apache-2.0"
			(at 0 0 0)
			(unlocked yes)
			(layer "F.Fab")
			(hide yes)
			(effects
				(font
					(size 1 1)
					(thickness 0.15)
				)
			)
		)
		(property "Author" "Antmicro"
			(at 0 0 0)
			(unlocked yes)
			(layer "F.Fab")
			(hide yes)
			(effects
				(font
					(size 1 1)
					(thickness 0.15)
				)
			)
		)
		(property "Tolerance" "1%"
			(at 0 0 0)
			(unlocked yes)
			(layer "F.Fab")
			(hide yes)
			(effects
				(font
					(size 1 1)
					(thickness 0.15)
				)
			)
		)
		(sheetname "/USB/")
		(sheetfile "usb.kicad_sch")
		(attr smd)
		(fp_rect
			(start -0.925 -0.47)
			(end 0.925 0.47)
			(stroke
				(width 0.05)
				(type default)
			)
			(fill no)
			(layer "F.CrtYd")
		)
		(fp_rect
			(start -0.5 -0.25)
			(end 0.5 0.25)
			(stroke
				(width 0.15)
				(type solid)
			)
			(fill no)
			(layer "F.Fab")
		)
		(fp_text user "Author: Antmicro"
			(at -0.95 4.169 0)
			(layer "F.Fab")
			(effects
				(font
					(size 0.7 0.7)
					(thickness 0.15)
				)
				(justify left bottom)
			)
		)
		(fp_text user "${REFERENCE}"
			(at -0.95 3.168 0)
			(layer "F.Fab")
			(effects
				(font
					(size 0.7 0.7)
					(thickness 0.15)
				)
				(justify left bottom)
			)
		)
		(fp_text user "License: Apache-2.0"
			(at -0.95 5.169 0)
			(layer "F.Fab")
			(effects
				(font
					(size 0.7 0.7)
					(thickness 0.15)
				)
				(justify left bottom)
			)
		)
		(pad "1" smd roundrect
			(at -0.48 0)
			(size 0.59 0.64)
			(layers "F.Cu" "F.Mask" "F.Paste")
			(roundrect_rratio 0.25)
			(net 484 "Net-(D907-A)")
			(pintype "passive")
		)
		(pad "2" smd roundrect
			(at 0.48 0)
			(size 0.59 0.64)
			(layers "F.Cu" "F.Mask" "F.Paste")
			(roundrect_rratio 0.25)
			(net 113 "/USB/OUT_FTDI")
			(pintype "passive")
		)
	)
	(footprint "antmicro-footprints:C_0402_1005Metric"
		(layer "F.Cu")
		(at 63.617962 179.1505)
		(descr "Capacitor SMD 0402")
		(tags "capacitor SMD 0402")
		(property "Reference" "C820"
			(at -16.17 -0.624 0)
			(layer "F.SilkS")
			(effects
				(font
					(size 0.7 0.7)
					(thickness 0.15)
				)
				(justify left bottom)
			)
		)
		(property "Value" "C_template_name_0402"
			(at -1.022927 2.155213 0)
			(layer "F.Fab")
			(effects
				(font
					(size 0.7 0.7)
					(thickness 0.15)
				)
				(justify left bottom)
			)
		)
		(property "Datasheet" "template_datasheet"
			(at 0 0 0)
			(layer "F.Fab")
			(hide yes)
			(effects
				(font
					(size 1.27 1.27)
					(thickness 0.15)
				)
			)
		)
		(property "MPN" "template_MPN"
			(at 0 0 0)
			(unlocked yes)
			(layer "F.Fab")
			(hide yes)
			(effects
				(font
					(size 1 1)
					(thickness 0.15)
				)
			)
		)
		(property "Manufacturer" "template_manufacturer"
			(at 0 0 0)
			(unlocked yes)
			(layer "F.Fab")
			(hide yes)
			(effects
				(font
					(size 1 1)
					(thickness 0.15)
				)
			)
		)
		(property "License" "Apache-2.0"
			(at 0 0 0)
			(unlocked yes)
			(layer "F.Fab")
			(hide yes)
			(effects
				(font
					(size 1 1)
					(thickness 0.15)
				)
			)
		)
		(property "Author" "Antmicro"
			(at 0 0 0)
			(unlocked yes)
			(layer "F.Fab")
			(hide yes)
			(effects
				(font
					(size 1 1)
					(thickness 0.15)
				)
			)
		)
		(property "Val" "template_value"
			(at 0 0 0)
			(unlocked yes)
			(layer "F.Fab")
			(hide yes)
			(effects
				(font
					(size 1 1)
					(thickness 0.15)
				)
			)
		)
		(property "Voltage" "template_voltage"
			(at 0 0 0)
			(unlocked yes)
			(layer "F.Fab")
			(hide yes)
			(effects
				(font
					(size 1 1)
					(thickness 0.15)
				)
			)
		)
		(property "Dielectric" "template_dielectric"
			(at 0 0 0)
			(unlocked yes)
			(layer "F.Fab")
			(hide yes)
			(effects
				(font
					(size 1 1)
					(thickness 0.15)
				)
			)
		)
		(sheetname "/Peripherals/")
		(sheetfile "peripherals.kicad_sch")
		(attr smd exclude_from_pos_files exclude_from_bom dnp)
		(fp_rect
			(start -0.925 -0.47)
			(end 0.925 0.47)
			(stroke
				(width 0.05)
				(type default)
			)
			(fill no)
			(layer "F.CrtYd")
		)
		(fp_line
			(start -0.494 -0.25)
			(end 0.504 -0.25)
			(stroke
				(width 0.15)
				(type solid)
			)
			(layer "F.Fab")
		)
		(fp_line
			(start -0.494 0.248)
			(end -0.494 -0.25)
			(stroke
				(width 0.15)
				(type solid)
			)
			(layer "F.Fab")
		)
		(fp_line
			(start 0.504 -0.25)
			(end 0.504 0.248)
			(stroke
				(width 0.15)
				(type solid)
			)
			(layer "F.Fab")
		)
		(fp_line
			(start 0.504 0.248)
			(end -0.494 0.248)
			(stroke
				(width 0.15)
				(type solid)
			)
			(layer "F.Fab")
		)
		(fp_text user "License: Apache-2.0"
			(at -0.939 5.799 0)
			(layer "F.Fab")
			(effects
				(font
					(size 0.7 0.7)
					(thickness 0.15)
				)
				(justify left bottom)
			)
		)
		(fp_text user "${REFERENCE}"
			(at -0.939 4.599 0)
			(layer "F.Fab")
			(effects
				(font
					(size 0.7 0.7)
					(thickness 0.15)
				)
				(justify left bottom)
			)
		)
		(fp_text user "Author: Antmicro"
			(at -0.939 3.399 0)
			(layer "F.Fab")
			(effects
				(font
					(size 0.7 0.7)
					(thickness 0.15)
				)
				(justify left bottom)
			)
		)
		(pad "1" smd roundrect
			(at -0.48 0)
			(size 0.59 0.64)
			(layers "F.Cu" "F.Mask" "F.Paste")
			(roundrect_rratio 0.25)
			(net 100 "Net-(C811-Pad2)")
			(pintype "passive")
		)
		(pad "2" smd roundrect
			(at 0.48 0)
			(size 0.59 0.64)
			(layers "F.Cu" "F.Mask" "F.Paste")
			(roundrect_rratio 0.25)
			(net 109 "Net-(C816-Pad2)")
			(pintype "passive")
		)
	)
	(footprint "antmicro-footprints:C_0402_1005Metric"
		(layer "F.Cu")
		(at 61.442962 174.2665 180)
		(descr "Capacitor SMD 0402")
		(tags "capacitor SMD 0402")
		(property "Reference" "C814"
			(at 13.942962 3.0165 0)
			(layer "F.SilkS")
			(effects
				(font
					(size 0.7 0.7)
					(thickness 0.15)
				)
				(justify right top)
			)
		)
		(property "Value" "C_12p_0402"
			(at -1.022927 2.155213 0)
			(layer "F.Fab")
			(effects
				(font
					(size 0.7 0.7)
					(thickness 0.15)
				)
				(justify right top)
			)
		)
		(property "Datasheet" "https://product.tdk.com/en/search/capacitor/ceramic/mlcc/info?part_no=CGA2B2C0G1H120J050BA"
			(at 0 0 0)
			(layer "F.Fab")
			(hide yes)
			(effects
				(font
					(size 1.27 1.27)
					(thickness 0.15)
				)
			)
		)
		(property "Description" "SMD Multilayer Ceramic Capacitor, 12 pF, 50 V, 0402 [1005 Metric], ± 5%, C0G / NP0, CGA"
			(at 0 0 0)
			(layer "F.Fab")
			(hide yes)
			(effects
				(font
					(size 1.27 1.27)
					(thickness 0.15)
				)
			)
		)
		(property "MPN" "CGA2B2C0G1H120J050BA"
			(at 0 0 180)
			(unlocked yes)
			(layer "F.Fab")
			(hide yes)
			(effects
				(font
					(size 1 1)
					(thickness 0.15)
				)
			)
		)
		(property "Manufacturer" "TDK"
			(at 0 0 180)
			(unlocked yes)
			(layer "F.Fab")
			(hide yes)
			(effects
				(font
					(size 1 1)
					(thickness 0.15)
				)
			)
		)
		(property "License" "Apache-2.0"
			(at 0 0 180)
			(unlocked yes)
			(layer "F.Fab")
			(hide yes)
			(effects
				(font
					(size 1 1)
					(thickness 0.15)
				)
			)
		)
		(property "Author" "Antmicro"
			(at 0 0 180)
			(unlocked yes)
			(layer "F.Fab")
			(hide yes)
			(effects
				(font
					(size 1 1)
					(thickness 0.15)
				)
			)
		)
		(property "Val" "12p"
			(at 0 0 180)
			(unlocked yes)
			(layer "F.Fab")
			(hide yes)
			(effects
				(font
					(size 1 1)
					(thickness 0.15)
				)
			)
		)
		(property "Voltage" ""
			(at 0 0 180)
			(unlocked yes)
			(layer "F.Fab")
			(hide yes)
			(effects
				(font
					(size 1 1)
					(thickness 0.15)
				)
			)
		)
		(property "Dielectric" ""
			(at 0 0 180)
			(unlocked yes)
			(layer "F.Fab")
			(hide yes)
			(effects
				(font
					(size 1 1)
					(thickness 0.15)
				)
			)
		)
		(sheetname "/Peripherals/")
		(sheetfile "peripherals.kicad_sch")
		(attr smd)
		(fp_rect
			(start -0.925 -0.47)
			(end 0.925 0.47)
			(stroke
				(width 0.05)
				(type default)
			)
			(fill no)
			(layer "F.CrtYd")
		)
		(fp_line
			(start 0.504 0.248)
			(end -0.494 0.248)
			(stroke
				(width 0.15)
				(type solid)
			)
			(layer "F.Fab")
		)
		(fp_line
			(start 0.504 -0.25)
			(end 0.504 0.248)
			(stroke
				(width 0.15)
				(type solid)
			)
			(layer "F.Fab")
		)
		(fp_line
			(start -0.494 0.248)
			(end -0.494 -0.25)
			(stroke
				(width 0.15)
				(type solid)
			)
			(layer "F.Fab")
		)
		(fp_line
			(start -0.494 -0.25)
			(end 0.504 -0.25)
			(stroke
				(width 0.15)
				(type solid)
			)
			(layer "F.Fab")
		)
		(fp_text user "License: Apache-2.0"
			(at -0.939 5.799 0)
			(layer "F.Fab")
			(effects
				(font
					(size 0.7 0.7)
					(thickness 0.15)
				)
				(justify right top)
			)
		)
		(fp_text user "Author: Antmicro"
			(at -0.939 3.399 0)
			(layer "F.Fab")
			(effects
				(font
					(size 0.7 0.7)
					(thickness 0.15)
				)
				(justify right top)
			)
		)
		(fp_text user "${REFERENCE}"
			(at -0.939 4.599 0)
			(layer "F.Fab")
			(effects
				(font
					(size 0.7 0.7)
					(thickness 0.15)
				)
				(justify right top)
			)
		)
		(pad "1" smd roundrect
			(at -0.48 0 180)
			(size 0.59 0.64)
			(layers "F.Cu" "F.Mask" "F.Paste")
			(roundrect_rratio 0.25)
			(net 107 "Net-(U801-ANT2)")
			(pintype "passive")
		)
		(pad "2" smd roundrect
			(at 0.48 0 180)
			(size 0.59 0.64)
			(layers "F.Cu" "F.Mask" "F.Paste")
			(roundrect_rratio 0.25)
			(net 106 "Net-(C814-Pad2)")
			(pintype "passive")
		)
	)
	(footprint "antmicro-footprints:R_0402_1005Metric"
		(layer "F.Cu")
		(at 102.067962 143.6165 180)
		(descr "Resistor SMD 0402")
		(tags "resistor SMD 0402")
		(property "Reference" "R932"
			(at -3.575 -0.475 0)
			(layer "F.SilkS")
			(effects
				(font
					(size 0.7 0.7)
					(thickness 0.15)
				)
				(justify right bottom)
			)
		)
		(property "Value" "R_10k_0402"
			(at -1.011843 1.772047 0)
			(layer "F.Fab")
			(effects
				(font
					(size 0.7 0.7)
					(thickness 0.15)
				)
				(justify right bottom)
			)
		)
		(property "Datasheet" "https://www.bourns.com/docs/product-datasheets/cr.pdf"
			(at 0 0 180)
			(layer "F.Fab")
			(hide yes)
			(effects
				(font
					(size 1.27 1.27)
					(thickness 0.15)
				)
			)
		)
		(property "Manufacturer" "Bourns"
			(at 0 0 180)
			(unlocked yes)
			(layer "F.Fab")
			(hide yes)
			(effects
				(font
					(size 1 1)
					(thickness 0.15)
				)
			)
		)
		(property "MPN" "CR0402-FX-1002GLF"
			(at 0 0 180)
			(unlocked yes)
			(layer "F.Fab")
			(hide yes)
			(effects
				(font
					(size 1 1)
					(thickness 0.15)
				)
			)
		)
		(property "Val" "10k"
			(at 0 0 180)
			(unlocked yes)
			(layer "F.Fab")
			(hide yes)
			(effects
				(font
					(size 1 1)
					(thickness 0.15)
				)
			)
		)
		(property "License" "Apache-2.0"
			(at 0 0 180)
			(unlocked yes)
			(layer "F.Fab")
			(hide yes)
			(effects
				(font
					(size 1 1)
					(thickness 0.15)
				)
			)
		)
		(property "Author" "Antmicro"
			(at 0 0 180)
			(unlocked yes)
			(layer "F.Fab")
			(hide yes)
			(effects
				(font
					(size 1 1)
					(thickness 0.15)
				)
			)
		)
		(property "Tolerance" "1%"
			(at 0 0 180)
			(unlocked yes)
			(layer "F.Fab")
			(hide yes)
			(effects
				(font
					(size 1 1)
					(thickness 0.15)
				)
			)
		)
		(sheetname "/USB/")
		(sheetfile "usb.kicad_sch")
		(attr smd exclude_from_pos_files exclude_from_bom dnp)
		(fp_rect
			(start -0.925 -0.47)
			(end 0.925 0.47)
			(stroke
				(width 0.05)
				(type default)
			)
			(fill no)
			(layer "F.CrtYd")
		)
		(fp_rect
			(start -0.5 -0.25)
			(end 0.5 0.25)
			(stroke
				(width 0.15)
				(type solid)
			)
			(fill no)
			(layer "F.Fab")
		)
		(fp_text user "${REFERENCE}"
			(at -0.95 3.168 180)
			(layer "F.Fab")
			(effects
				(font
					(size 0.7 0.7)
					(thickness 0.15)
				)
				(justify left bottom)
			)
		)
		(fp_text user "Author: Antmicro"
			(at -0.95 4.169 180)
			(layer "F.Fab")
			(effects
				(font
					(size 0.7 0.7)
					(thickness 0.15)
				)
				(justify left bottom)
			)
		)
		(fp_text user "License: Apache-2.0"
			(at -0.95 5.169 180)
			(layer "F.Fab")
			(effects
				(font
					(size 0.7 0.7)
					(thickness 0.15)
				)
				(justify left bottom)
			)
		)
		(pad "1" smd roundrect
			(at -0.48 0 180)
			(size 0.59 0.64)
			(layers "F.Cu" "F.Mask" "F.Paste")
			(roundrect_rratio 0.25)
			(net 490 "Net-(Q905-G)")
			(pintype "passive")
		)
		(pad "2" smd roundrect
			(at 0.48 0 180)
			(size 0.59 0.64)
			(layers "F.Cu" "F.Mask" "F.Paste")
			(roundrect_rratio 0.25)
			(net 27 "/USB/USB_3V3")
			(pintype "passive")
		)
	)
	(footprint "antmicro-footprints:R_0402_1005Metric"
		(layer "F.Cu")
		(at 103.817962 129.7915 90)
		(descr "Resistor SMD 0402")
		(tags "resistor SMD 0402")
		(property "Reference" "R926"
			(at -1.825 1.54 90)
			(layer "F.SilkS")
			(effects
				(font
					(size 0.7 0.7)
					(thickness 0.15)
				)
				(justify left bottom)
			)
		)
		(property "Value" "R_200R_0402"
			(at -1.011843 1.772047 90)
			(layer "F.Fab")
			(effects
				(font
					(size 0.7 0.7)
					(thickness 0.15)
				)
				(justify left bottom)
			)
		)
		(property "Datasheet" "https://www.bourns.com/docs/product-datasheets/cr.pdf"
			(at 0 0 90)
			(layer "F.Fab")
			(hide yes)
			(effects
				(font
					(size 1.27 1.27)
					(thickness 0.15)
				)
			)
		)
		(property "MPN" "CR0402-FX-2000GLF"
			(at 0 0 90)
			(unlocked yes)
			(layer "F.Fab")
			(hide yes)
			(effects
				(font
					(size 1 1)
					(thickness 0.15)
				)
			)
		)
		(property "Manufacturer" "Bourns"
			(at 0 0 90)
			(unlocked yes)
			(layer "F.Fab")
			(hide yes)
			(effects
				(font
					(size 1 1)
					(thickness 0.15)
				)
			)
		)
		(property "License" "Apache-2.0"
			(at 0 0 90)
			(unlocked yes)
			(layer "F.Fab")
			(hide yes)
			(effects
				(font
					(size 1 1)
					(thickness 0.15)
				)
			)
		)
		(property "Author" "Antmicro"
			(at 0 0 90)
			(unlocked yes)
			(layer "F.Fab")
			(hide yes)
			(effects
				(font
					(size 1 1)
					(thickness 0.15)
				)
			)
		)
		(property "Val" "200R"
			(at 0 0 90)
			(unlocked yes)
			(layer "F.Fab")
			(hide yes)
			(effects
				(font
					(size 1 1)
					(thickness 0.15)
				)
			)
		)
		(property "Tolerance" "1%"
			(at 0 0 90)
			(unlocked yes)
			(layer "F.Fab")
			(hide yes)
			(effects
				(font
					(size 1 1)
					(thickness 0.15)
				)
			)
		)
		(sheetname "/USB/")
		(sheetfile "usb.kicad_sch")
		(attr smd)
		(fp_rect
			(start -0.925 -0.47)
			(end 0.925 0.47)
			(stroke
				(width 0.05)
				(type default)
			)
			(fill no)
			(layer "F.CrtYd")
		)
		(fp_rect
			(start -0.5 -0.25)
			(end 0.5 0.25)
			(stroke
				(width 0.15)
				(type solid)
			)
			(fill no)
			(layer "F.Fab")
		)
		(fp_text user "Author: Antmicro"
			(at -0.95 4.169 90)
			(layer "F.Fab")
			(effects
				(font
					(size 0.7 0.7)
					(thickness 0.15)
				)
				(justify left bottom)
			)
		)
		(fp_text user "${REFERENCE}"
			(at -0.95 3.168 90)
			(layer "F.Fab")
			(effects
				(font
					(size 0.7 0.7)
					(thickness 0.15)
				)
				(justify left bottom)
			)
		)
		(fp_text user "License: Apache-2.0"
			(at -0.95 5.169 90)
			(layer "F.Fab")
			(effects
				(font
					(size 0.7 0.7)
					(thickness 0.15)
				)
				(justify left bottom)
			)
		)
		(pad "1" smd roundrect
			(at -0.48 0 90)
			(size 0.59 0.64)
			(layers "F.Cu" "F.Mask" "F.Paste")
			(roundrect_rratio 0.25)
			(net 10 "+5V")
			(pintype "passive")
		)
		(pad "2" smd roundrect
			(at 0.48 0 90)
			(size 0.59 0.64)
			(layers "F.Cu" "F.Mask" "F.Paste")
			(roundrect_rratio 0.25)
			(net 28 "/USB/+5V_{CAP}")
			(pintype "passive")
		)
	)
	(footprint "antmicro-footprints:LED_0603_1608Metric_G"
		(layer "F.Cu")
		(at 117.617962 135.2415 90)
		(descr "LED SMD 0603 Green")
		(tags "LED SMD 0603 Green")
		(property "Reference" "D503"
			(at 1.175 0.75 90)
			(layer "F.SilkS")
			(effects
				(font
					(size 0.7 0.7)
					(thickness 0.15)
				)
				(justify left bottom)
			)
		)
		(property "Value" "LED_G_0603_KP-1608CGCK"
			(at -0.001 1.599 90)
			(layer "F.Fab")
			(effects
				(font
					(size 0.7 0.7)
					(thickness 0.15)
				)
				(justify left bottom)
			)
		)
		(property "Datasheet" "http://www.kingbright.com/attachments/file/psearch//000/00/00/KP-1608CGCK(Ver.23B).pdf"
			(at 0 0 90)
			(layer "F.Fab")
			(hide yes)
			(effects
				(font
					(size 1.27 1.27)
					(thickness 0.15)
				)
			)
		)
		(property "MPN" "KP-1608CGCK"
			(at 0 0 90)
			(unlocked yes)
			(layer "F.Fab")
			(hide yes)
			(effects
				(font
					(size 1 1)
					(thickness 0.15)
				)
			)
		)
		(property "Manufacturer" "Kingbright"
			(at 0 0 90)
			(unlocked yes)
			(layer "F.Fab")
			(hide yes)
			(effects
				(font
					(size 1 1)
					(thickness 0.15)
				)
			)
		)
		(property "Color" "Green"
			(at 0 0 90)
			(unlocked yes)
			(layer "F.Fab")
			(hide yes)
			(effects
				(font
					(size 1 1)
					(thickness 0.15)
				)
			)
		)
		(property "Author" "Antmicro"
			(at 0 0 90)
			(unlocked yes)
			(layer "F.Fab")
			(hide yes)
			(effects
				(font
					(size 1 1)
					(thickness 0.15)
				)
			)
		)
		(property "License" "Apache-2.0"
			(at 0 0 90)
			(unlocked yes)
			(layer "F.Fab")
			(hide yes)
			(effects
				(font
					(size 1 1)
					(thickness 0.15)
				)
			)
		)
		(sheetname "/NVMe & microSD/")
		(sheetfile "nvme-micro-sd.kicad_sch")
		(attr smd)
		(fp_line
			(start 0.22 -0.35)
			(end -0.22 -0.35)
			(stroke
				(width 0.15)
				(type solid)
			)
			(layer "F.SilkS")
		)
		(fp_line
			(start -1.18 -0.319)
			(end -1.18 0.321)
			(stroke
				(width 0.15)
				(type solid)
			)
			(layer "F.SilkS")
		)
		(fp_line
			(start 0.105328 0.001008)
			(end 0.24 0.001)
			(stroke
				(width 0.1)
				(type solid)
			)
			(layer "F.SilkS")
		)
		(fp_line
			(start -0.094672 0.001008)
			(end 0.105328 -0.198992)
			(stroke
				(width 0.1)
				(type solid)
			)
			(layer "F.SilkS")
		)
		(fp_line
			(start -0.094672 0.001008)
			(end -0.24 0.001008)
			(stroke
				(width 0.1)
				(type solid)
			)
			(layer "F.SilkS")
		)
		(fp_line
			(start 0.105328 0.201008)
			(end 0.105328 -0.198992)
			(stroke
				(width 0.1)
				(type solid)
			)
			(layer "F.SilkS")
		)
		(fp_line
			(start 0.105328 0.201008)
			(end -0.094672 0.001008)
			(stroke
				(width 0.1)
				(type solid)
			)
			(layer "F.SilkS")
		)
		(fp_line
			(start -0.094672 0.201008)
			(end -0.094672 -0.198992)
			(stroke
				(width 0.1)
				(type solid)
			)
			(layer "F.SilkS")
		)
		(fp_line
			(start 0.22 0.35)
			(end -0.22 0.35)
			(stroke
				(width 0.15)
				(type solid)
			)
			(layer "F.SilkS")
		)
		(fp_rect
			(start 1.25 0.65)
			(end -1.25 -0.65)
			(stroke
				(width 0.05)
				(type solid)
			)
			(fill no)
			(layer "F.CrtYd")
		)
		(fp_line
			(start 0.201 -0.202)
			(end -0.101 0)
			(stroke
				(width 0.15)
				(type solid)
			)
			(layer "F.Fab")
		)
		(fp_line
			(start -0.199 -0.202)
			(end -0.199 0.1)
			(stroke
				(width 0.15)
				(type solid)
			)
			(layer "F.Fab")
		)
		(fp_line
			(start 0.599 0)
			(end 0.201 0)
			(stroke
				(width 0.15)
				(type solid)
			)
			(layer "F.Fab")
		)
		(fp_line
			(start 0.201 0)
			(end 0.201 -0.202)
			(stroke
				(width 0.15)
				(type solid)
			)
			(layer "F.Fab")
		)
		(fp_line
			(start -0.101 0)
			(end 0.201 0.2)
			(stroke
				(width 0.15)
				(type solid)
			)
			(layer "F.Fab")
		)
		(fp_line
			(start -0.199 0)
			(end -0.597 0)
			(stroke
				(width 0.15)
				(type solid)
			)
			(layer "F.Fab")
		)
		(fp_line
			(start 0.201 0.2)
			(end 0.201 0)
			(stroke
				(width 0.15)
				(type solid)
			)
			(layer "F.Fab")
		)
		(fp_line
			(start -0.199 0.2)
			(end -0.199 0.1)
			(stroke
				(width 0.15)
				(type solid)
			)
			(layer "F.Fab")
		)
		(fp_rect
			(start 0.848 0.4)
			(end -0.85 -0.402)
			(stroke
				(width 0.15)
				(type solid)
			)
			(fill no)
			(layer "F.Fab")
		)
		(fp_text user "Author: Antmicro"
			(at -1.4224 4.799 90)
			(layer "F.Fab")
			(effects
				(font
					(size 0.7 0.7)
					(thickness 0.15)
				)
				(justify left bottom)
			)
		)
		(fp_text user "${REFERENCE}"
			(at -1.4224 5.999 90)
			(layer "F.Fab")
			(effects
				(font
					(size 0.7 0.7)
					(thickness 0.15)
				)
				(justify left bottom)
			)
		)
		(fp_text user "License: Apache-2.0"
			(at -1.4224 3.599 90)
			(layer "F.Fab")
			(effects
				(font
					(size 0.7 0.7)
					(thickness 0.15)
				)
				(justify left bottom)
			)
		)
		(pad "1" smd roundrect
			(at -0.7 0 270)
			(size 0.8 1)
			(layers "F.Cu" "F.Mask" "F.Paste")
			(roundrect_rratio 0.2)
			(net 470 "Net-(D503-C)")
			(pinfunction "C")
			(pintype "passive")
		)
		(pad "2" smd roundrect
			(at 0.7 0 270)
			(size 0.8 1)
			(layers "F.Cu" "F.Mask" "F.Paste")
			(roundrect_rratio 0.2)
			(net 478 "Net-(D503-A)")
			(pinfunction "A")
			(pintype "passive")
		)
	)
	(footprint "antmicro-footprints:C_0402_1005Metric"
		(layer "F.Cu")
		(at 61.442962 179.1415 180)
		(descr "Capacitor SMD 0402")
		(tags "capacitor SMD 0402")
		(property "Reference" "C811"
			(at 14.192962 1.3915 0)
			(layer "F.SilkS")
			(effects
				(font
					(size 0.7 0.7)
					(thickness 0.15)
				)
				(justify right top)
			)
		)
		(property "Value" "C_12p_0402"
			(at -1.022927 2.155213 0)
			(layer "F.Fab")
			(effects
				(font
					(size 0.7 0.7)
					(thickness 0.15)
				)
				(justify right top)
			)
		)
		(property "Datasheet" "https://product.tdk.com/en/search/capacitor/ceramic/mlcc/info?part_no=CGA2B2C0G1H120J050BA"
			(at 0 0 0)
			(layer "F.Fab")
			(hide yes)
			(effects
				(font
					(size 1.27 1.27)
					(thickness 0.15)
				)
			)
		)
		(property "Description" "SMD Multilayer Ceramic Capacitor, 12 pF, 50 V, 0402 [1005 Metric], ± 5%, C0G / NP0, CGA"
			(at 0 0 0)
			(layer "F.Fab")
			(hide yes)
			(effects
				(font
					(size 1.27 1.27)
					(thickness 0.15)
				)
			)
		)
		(property "MPN" "CGA2B2C0G1H120J050BA"
			(at 0 0 180)
			(unlocked yes)
			(layer "F.Fab")
			(hide yes)
			(effects
				(font
					(size 1 1)
					(thickness 0.15)
				)
			)
		)
		(property "Manufacturer" "TDK"
			(at 0 0 180)
			(unlocked yes)
			(layer "F.Fab")
			(hide yes)
			(effects
				(font
					(size 1 1)
					(thickness 0.15)
				)
			)
		)
		(property "License" "Apache-2.0"
			(at 0 0 180)
			(unlocked yes)
			(layer "F.Fab")
			(hide yes)
			(effects
				(font
					(size 1 1)
					(thickness 0.15)
				)
			)
		)
		(property "Author" "Antmicro"
			(at 0 0 180)
			(unlocked yes)
			(layer "F.Fab")
			(hide yes)
			(effects
				(font
					(size 1 1)
					(thickness 0.15)
				)
			)
		)
		(property "Val" "12p"
			(at 0 0 180)
			(unlocked yes)
			(layer "F.Fab")
			(hide yes)
			(effects
				(font
					(size 1 1)
					(thickness 0.15)
				)
			)
		)
		(property "Voltage" ""
			(at 0 0 180)
			(unlocked yes)
			(layer "F.Fab")
			(hide yes)
			(effects
				(font
					(size 1 1)
					(thickness 0.15)
				)
			)
		)
		(property "Dielectric" ""
			(at 0 0 180)
			(unlocked yes)
			(layer "F.Fab")
			(hide yes)
			(effects
				(font
					(size 1 1)
					(thickness 0.15)
				)
			)
		)
		(sheetname "/Peripherals/")
		(sheetfile "peripherals.kicad_sch")
		(attr smd)
		(fp_rect
			(start -0.925 -0.47)
			(end 0.925 0.47)
			(stroke
				(width 0.05)
				(type default)
			)
			(fill no)
			(layer "F.CrtYd")
		)
		(fp_line
			(start 0.504 0.248)
			(end -0.494 0.248)
			(stroke
				(width 0.15)
				(type solid)
			)
			(layer "F.Fab")
		)
		(fp_line
			(start 0.504 -0.25)
			(end 0.504 0.248)
			(stroke
				(width 0.15)
				(type solid)
			)
			(layer "F.Fab")
		)
		(fp_line
			(start -0.494 0.248)
			(end -0.494 -0.25)
			(stroke
				(width 0.15)
				(type solid)
			)
			(layer "F.Fab")
		)
		(fp_line
			(start -0.494 -0.25)
			(end 0.504 -0.25)
			(stroke
				(width 0.15)
				(type solid)
			)
			(layer "F.Fab")
		)
		(fp_text user "License: Apache-2.0"
			(at -0.939 5.799 0)
			(layer "F.Fab")
			(effects
				(font
					(size 0.7 0.7)
					(thickness 0.15)
				)
				(justify right top)
			)
		)
		(fp_text user "Author: Antmicro"
			(at -0.939 3.399 0)
			(layer "F.Fab")
			(effects
				(font
					(size 0.7 0.7)
					(thickness 0.15)
				)
				(justify right top)
			)
		)
		(fp_text user "${REFERENCE}"
			(at -0.939 4.599 0)
			(layer "F.Fab")
			(effects
				(font
					(size 0.7 0.7)
					(thickness 0.15)
				)
				(justify right top)
			)
		)
		(pad "1" smd roundrect
			(at -0.48 0 180)
			(size 0.59 0.64)
			(layers "F.Cu" "F.Mask" "F.Paste")
			(roundrect_rratio 0.25)
			(net 101 "Net-(U801-ANT1)")
			(pintype "passive")
		)
		(pad "2" smd roundrect
			(at 0.48 0 180)
			(size 0.59 0.64)
			(layers "F.Cu" "F.Mask" "F.Paste")
			(roundrect_rratio 0.25)
			(net 100 "Net-(C811-Pad2)")
			(pintype "passive")
		)
	)
	(footprint "antmicro-footprints:TP_SMD_0.75mm"
		(layer "F.Cu")
		(at 93.85 133.05)
		(property "Reference" "TP919"
			(at 3.05 3.41 0)
			(layer "F.SilkS")
			(effects
				(font
					(size 0.7 0.7)
					(thickness 0.15)
				)
				(justify left bottom)
			)
		)
		(property "Value" "TP_0.75mm_SMD"
			(at 0 1.2 0)
			(layer "F.Fab")
			(effects
				(font
					(size 0.7 0.7)
					(thickness 0.15)
				)
				(justify left bottom)
			)
		)
		(property "MPN" ""
			(at 0 0 0)
			(unlocked yes)
			(layer "F.Fab")
			(hide yes)
			(effects
				(font
					(size 1 1)
					(thickness 0.15)
				)
			)
		)
		(property "Manufacturer" ""
			(at 0 0 0)
			(unlocked yes)
			(layer "F.Fab")
			(hide yes)
			(effects
				(font
					(size 1 1)
					(thickness 0.15)
				)
			)
		)
		(property "Author" "Antmicro"
			(at 0 0 0)
			(unlocked yes)
			(layer "F.Fab")
			(hide yes)
			(effects
				(font
					(size 1 1)
					(thickness 0.15)
				)
			)
		)
		(property "License" "Apache-2.0"
			(at 0 0 0)
			(unlocked yes)
			(layer "F.Fab")
			(hide yes)
			(effects
				(font
					(size 1 1)
					(thickness 0.15)
				)
			)
		)
		(sheetname "/USB/")
		(sheetfile "usb.kicad_sch")
		(attr exclude_from_pos_files exclude_from_bom)
		(fp_circle
			(center 0 0)
			(end 0.475 0)
			(stroke
				(width 0.05)
				(type default)
			)
			(fill no)
			(layer "F.CrtYd")
		)
		(fp_text user "License: Apache-2.0"
			(at -0.4 5.101 0)
			(layer "F.Fab")
			(effects
				(font
					(size 0.7 0.7)
					(thickness 0.15)
				)
				(justify left bottom)
			)
		)
		(fp_text user "${REFERENCE}"
			(at -0.4 2.7 0)
			(layer "F.Fab")
			(effects
				(font
					(size 0.7 0.7)
					(thickness 0.15)
				)
				(justify left bottom)
			)
		)
		(fp_text user "Author: Antmicro"
			(at -0.4 3.901 0)
			(layer "F.Fab")
			(effects
				(font
					(size 0.7 0.7)
					(thickness 0.15)
				)
				(justify left bottom)
			)
		)
		(pad "1" smd circle
			(at 0 0)
			(size 0.75 0.75)
			(layers "F.Cu" "F.Mask")
			(net 450 "Net-(U905-GPIO2)")
			(pinfunction "1")
			(pintype "passive")
		)
	)
	(footprint "antmicro-footprints:LED_0603_1608Metric_G"
		(layer "F.Cu")
		(at 73.767962 160.8765 180)
		(descr "LED SMD 0603 Green")
		(tags "LED SMD 0603 Green")
		(property "Reference" "D306"
			(at 6.15 0.91 0)
			(layer "F.SilkS")
			(effects
				(font
					(size 0.7 0.7)
					(thickness 0.15)
				)
				(justify right bottom)
			)
		)
		(property "Value" "LED_G_0603_KP-1608CGCK"
			(at -0.001 1.599 0)
			(layer "F.Fab")
			(effects
				(font
					(size 0.7 0.7)
					(thickness 0.15)
				)
				(justify right bottom)
			)
		)
		(property "Datasheet" "http://www.kingbright.com/attachments/file/psearch//000/00/00/KP-1608CGCK(Ver.23B).pdf"
			(at 0 0 180)
			(layer "F.Fab")
			(hide yes)
			(effects
				(font
					(size 1.27 1.27)
					(thickness 0.15)
				)
			)
		)
		(property "MPN" "KP-1608CGCK"
			(at 0 0 180)
			(unlocked yes)
			(layer "F.Fab")
			(hide yes)
			(effects
				(font
					(size 1 1)
					(thickness 0.15)
				)
			)
		)
		(property "Manufacturer" "Kingbright"
			(at 0 0 180)
			(unlocked yes)
			(layer "F.Fab")
			(hide yes)
			(effects
				(font
					(size 1 1)
					(thickness 0.15)
				)
			)
		)
		(property "Color" "Green"
			(at 0 0 180)
			(unlocked yes)
			(layer "F.Fab")
			(hide yes)
			(effects
				(font
					(size 1 1)
					(thickness 0.15)
				)
			)
		)
		(property "Author" "Antmicro"
			(at 0 0 180)
			(unlocked yes)
			(layer "F.Fab")
			(hide yes)
			(effects
				(font
					(size 1 1)
					(thickness 0.15)
				)
			)
		)
		(property "License" "Apache-2.0"
			(at 0 0 180)
			(unlocked yes)
			(layer "F.Fab")
			(hide yes)
			(effects
				(font
					(size 1 1)
					(thickness 0.15)
				)
			)
		)
		(sheetname "/Supply/")
		(sheetfile "supply.kicad_sch")
		(attr smd)
		(fp_line
			(start 0.22 0.35)
			(end -0.22 0.35)
			(stroke
				(width 0.15)
				(type solid)
			)
			(layer "F.SilkS")
		)
		(fp_line
			(start 0.22 -0.35)
			(end -0.22 -0.35)
			(stroke
				(width 0.15)
				(type solid)
			)
			(layer "F.SilkS")
		)
		(fp_line
			(start 0.105328 0.201008)
			(end 0.105328 -0.198992)
			(stroke
				(width 0.1)
				(type solid)
			)
			(layer "F.SilkS")
		)
		(fp_line
			(start 0.105328 0.201008)
			(end -0.094672 0.001008)
			(stroke
				(width 0.1)
				(type solid)
			)
			(layer "F.SilkS")
		)
		(fp_line
			(start 0.105328 0.001008)
			(end 0.24 0.001)
			(stroke
				(width 0.1)
				(type solid)
			)
			(layer "F.SilkS")
		)
		(fp_line
			(start -0.094672 0.201008)
			(end -0.094672 -0.198992)
			(stroke
				(width 0.1)
				(type solid)
			)
			(layer "F.SilkS")
		)
		(fp_line
			(start -0.094672 0.001008)
			(end 0.105328 -0.198992)
			(stroke
				(width 0.1)
				(type solid)
			)
			(layer "F.SilkS")
		)
		(fp_line
			(start -0.094672 0.001008)
			(end -0.24 0.001008)
			(stroke
				(width 0.1)
				(type solid)
			)
			(layer "F.SilkS")
		)
		(fp_line
			(start -1.18 -0.319)
			(end -1.18 0.321)
			(stroke
				(width 0.15)
				(type solid)
			)
			(layer "F.SilkS")
		)
		(fp_rect
			(start 1.25 0.65)
			(end -1.25 -0.65)
			(stroke
				(width 0.05)
				(type solid)
			)
			(fill no)
			(layer "F.CrtYd")
		)
		(fp_line
			(start 0.599 0)
			(end 0.201 0)
			(stroke
				(width 0.15)
				(type solid)
			)
			(layer "F.Fab")
		)
		(fp_line
			(start 0.201 0.2)
			(end 0.201 0)
			(stroke
				(width 0.15)
				(type solid)
			)
			(layer "F.Fab")
		)
		(fp_line
			(start 0.201 0)
			(end 0.201 -0.202)
			(stroke
				(width 0.15)
				(type solid)
			)
			(layer "F.Fab")
		)
		(fp_line
			(start 0.201 -0.202)
			(end -0.101 0)
			(stroke
				(width 0.15)
				(type solid)
			)
			(layer "F.Fab")
		)
		(fp_line
			(start -0.101 0)
			(end 0.201 0.2)
			(stroke
				(width 0.15)
				(type solid)
			)
			(layer "F.Fab")
		)
		(fp_line
			(start -0.199 0.2)
			(end -0.199 0.1)
			(stroke
				(width 0.15)
				(type solid)
			)
			(layer "F.Fab")
		)
		(fp_line
			(start -0.199 0)
			(end -0.597 0)
			(stroke
				(width 0.15)
				(type solid)
			)
			(layer "F.Fab")
		)
		(fp_line
			(start -0.199 -0.202)
			(end -0.199 0.1)
			(stroke
				(width 0.15)
				(type solid)
			)
			(layer "F.Fab")
		)
		(fp_rect
			(start 0.848 0.4)
			(end -0.85 -0.402)
			(stroke
				(width 0.15)
				(type solid)
			)
			(fill no)
			(layer "F.Fab")
		)
		(fp_text user "License: Apache-2.0"
			(at -1.4224 3.599 180)
			(layer "F.Fab")
			(effects
				(font
					(size 0.7 0.7)
					(thickness 0.15)
				)
				(justify left bottom)
			)
		)
		(fp_text user "${REFERENCE}"
			(at -1.4224 5.999 180)
			(layer "F.Fab")
			(effects
				(font
					(size 0.7 0.7)
					(thickness 0.15)
				)
				(justify left bottom)
			)
		)
		(fp_text user "Author: Antmicro"
			(at -1.4224 4.799 180)
			(layer "F.Fab")
			(effects
				(font
					(size 0.7 0.7)
					(thickness 0.15)
				)
				(justify left bottom)
			)
		)
		(pad "1" smd roundrect
			(at -0.7 0)
			(size 0.8 1)
			(layers "F.Cu" "F.Mask" "F.Paste")
			(roundrect_rratio 0.2)
			(net 3 "GND")
			(pinfunction "C")
			(pintype "passive")
		)
		(pad "2" smd roundrect
			(at 0.7 0)
			(size 0.8 1)
			(layers "F.Cu" "F.Mask" "F.Paste")
			(roundrect_rratio 0.2)
			(net 476 "Net-(D306-A)")
			(pinfunction "A")
			(pintype "passive")
		)
	)
	(footprint "antmicro-footprints:R_0402_1005Metric"
		(layer "F.Cu")
		(at 54.827962 129.9265)
		(descr "Resistor SMD 0402")
		(tags "resistor SMD 0402")
		(property "Reference" "R410"
			(at -1.49 -5.38 0)
			(layer "F.SilkS")
			(effects
				(font
					(size 0.7 0.7)
					(thickness 0.15)
				)
				(justify left bottom)
			)
		)
		(property "Value" "R_10k_0402"
			(at -1.011843 1.772047 0)
			(layer "F.Fab")
			(effects
				(font
					(size 0.7 0.7)
					(thickness 0.15)
				)
				(justify left bottom)
			)
		)
		(property "Datasheet" "https://www.bourns.com/docs/product-datasheets/cr.pdf"
			(at 0 0 0)
			(layer "F.Fab")
			(hide yes)
			(effects
				(font
					(size 1.27 1.27)
					(thickness 0.15)
				)
			)
		)
		(property "Manufacturer" "Bourns"
			(at 0 0 0)
			(unlocked yes)
			(layer "F.Fab")
			(hide yes)
			(effects
				(font
					(size 1 1)
					(thickness 0.15)
				)
			)
		)
		(property "MPN" "CR0402-FX-1002GLF"
			(at 0 0 0)
			(unlocked yes)
			(layer "F.Fab")
			(hide yes)
			(effects
				(font
					(size 1 1)
					(thickness 0.15)
				)
			)
		)
		(property "Val" "10k"
			(at 0 0 0)
			(unlocked yes)
			(layer "F.Fab")
			(hide yes)
			(effects
				(font
					(size 1 1)
					(thickness 0.15)
				)
			)
		)
		(property "License" "Apache-2.0"
			(at 0 0 0)
			(unlocked yes)
			(layer "F.Fab")
			(hide yes)
			(effects
				(font
					(size 1 1)
					(thickness 0.15)
				)
			)
		)
		(property "Author" "Antmicro"
			(at 0 0 0)
			(unlocked yes)
			(layer "F.Fab")
			(hide yes)
			(effects
				(font
					(size 1 1)
					(thickness 0.15)
				)
			)
		)
		(property "Tolerance" "1%"
			(at 0 0 0)
			(unlocked yes)
			(layer "F.Fab")
			(hide yes)
			(effects
				(font
					(size 1 1)
					(thickness 0.15)
				)
			)
		)
		(sheetname "/Ethernet/")
		(sheetfile "ethernet.kicad_sch")
		(attr smd exclude_from_pos_files exclude_from_bom dnp)
		(fp_rect
			(start -0.925 -0.47)
			(end 0.925 0.47)
			(stroke
				(width 0.05)
				(type default)
			)
			(fill no)
			(layer "F.CrtYd")
		)
		(fp_rect
			(start -0.5 -0.25)
			(end 0.5 0.25)
			(stroke
				(width 0.15)
				(type solid)
			)
			(fill no)
			(layer "F.Fab")
		)
		(fp_text user "License: Apache-2.0"
			(at -0.95 5.169 0)
			(layer "F.Fab")
			(effects
				(font
					(size 0.7 0.7)
					(thickness 0.15)
				)
				(justify left bottom)
			)
		)
		(fp_text user "${REFERENCE}"
			(at -0.95 3.168 0)
			(layer "F.Fab")
			(effects
				(font
					(size 0.7 0.7)
					(thickness 0.15)
				)
				(justify left bottom)
			)
		)
		(fp_text user "Author: Antmicro"
			(at -0.95 4.169 0)
			(layer "F.Fab")
			(effects
				(font
					(size 0.7 0.7)
					(thickness 0.15)
				)
				(justify left bottom)
			)
		)
		(pad "1" smd roundrect
			(at -0.48 0)
			(size 0.59 0.64)
			(layers "F.Cu" "F.Mask" "F.Paste")
			(roundrect_rratio 0.25)
			(net 365 "/Ethernet/~{BT}")
			(pintype "passive")
		)
		(pad "2" smd roundrect
			(at 0.48 0)
			(size 0.59 0.64)
			(layers "F.Cu" "F.Mask" "F.Paste")
			(roundrect_rratio 0.25)
			(net 33 "/Ethernet/VDD")
			(pintype "passive")
		)
	)
	(footprint "antmicro-footprints:C_0402_1005Metric"
		(layer "F.Cu")
		(at 91.042962 144.282236 -90)
		(descr "Capacitor SMD 0402")
		(tags "capacitor SMD 0402")
		(property "Reference" "C917"
			(at -1.482236 0.422962 90)
			(layer "F.SilkS")
			(effects
				(font
					(size 0.7 0.7)
					(thickness 0.15)
				)
				(justify right bottom)
			)
		)
		(property "Value" "C_100n_0402"
			(at -1.022927 2.155213 90)
			(layer "F.Fab")
			(effects
				(font
					(size 0.7 0.7)
					(thickness 0.15)
				)
				(justify right bottom)
			)
		)
		(property "Datasheet" "https://www.murata.com/products/productdetail?partno=GRM155R61H104KE14%23"
			(at 0 0 270)
			(layer "F.Fab")
			(hide yes)
			(effects
				(font
					(size 1.27 1.27)
					(thickness 0.15)
				)
			)
		)
		(property "Manufacturer" "Murata"
			(at 0 0 270)
			(unlocked yes)
			(layer "F.Fab")
			(hide yes)
			(effects
				(font
					(size 1 1)
					(thickness 0.15)
				)
			)
		)
		(property "MPN" "GRM155R61H104KE14D"
			(at 0 0 270)
			(unlocked yes)
			(layer "F.Fab")
			(hide yes)
			(effects
				(font
					(size 1 1)
					(thickness 0.15)
				)
			)
		)
		(property "Val" "100n"
			(at 0 0 270)
			(unlocked yes)
			(layer "F.Fab")
			(hide yes)
			(effects
				(font
					(size 1 1)
					(thickness 0.15)
				)
			)
		)
		(property "License" "Apache-2.0"
			(at 0 0 270)
			(unlocked yes)
			(layer "F.Fab")
			(hide yes)
			(effects
				(font
					(size 1 1)
					(thickness 0.15)
				)
			)
		)
		(property "Author" "Antmicro"
			(at 0 0 270)
			(unlocked yes)
			(layer "F.Fab")
			(hide yes)
			(effects
				(font
					(size 1 1)
					(thickness 0.15)
				)
			)
		)
		(property "Voltage" "50V"
			(at 0 0 270)
			(unlocked yes)
			(layer "F.Fab")
			(hide yes)
			(effects
				(font
					(size 1 1)
					(thickness 0.15)
				)
			)
		)
		(property "Dielectric" "X5R"
			(at 0 0 270)
			(unlocked yes)
			(layer "F.Fab")
			(hide yes)
			(effects
				(font
					(size 1 1)
					(thickness 0.15)
				)
			)
		)
		(sheetname "/USB/")
		(sheetfile "usb.kicad_sch")
		(attr smd)
		(fp_rect
			(start -0.925 -0.47)
			(end 0.925 0.47)
			(stroke
				(width 0.05)
				(type default)
			)
			(fill no)
			(layer "F.CrtYd")
		)
		(fp_line
			(start -0.494 0.248)
			(end -0.494 -0.25)
			(stroke
				(width 0.15)
				(type solid)
			)
			(layer "F.Fab")
		)
		(fp_line
			(start 0.504 0.248)
			(end -0.494 0.248)
			(stroke
				(width 0.15)
				(type solid)
			)
			(layer "F.Fab")
		)
		(fp_line
			(start -0.494 -0.25)
			(end 0.504 -0.25)
			(stroke
				(width 0.15)
				(type solid)
			)
			(layer "F.Fab")
		)
		(fp_line
			(start 0.504 -0.25)
			(end 0.504 0.248)
			(stroke
				(width 0.15)
				(type solid)
			)
			(layer "F.Fab")
		)
		(fp_text user "${REFERENCE}"
			(at -0.939 4.599 270)
			(layer "F.Fab")
			(effects
				(font
					(size 0.7 0.7)
					(thickness 0.15)
				)
				(justify left bottom)
			)
		)
		(fp_text user "License: Apache-2.0"
			(at -0.939 5.799 270)
			(layer "F.Fab")
			(effects
				(font
					(size 0.7 0.7)
					(thickness 0.15)
				)
				(justify left bottom)
			)
		)
		(fp_text user "Author: Antmicro"
			(at -0.939 3.399 270)
			(layer "F.Fab")
			(effects
				(font
					(size 0.7 0.7)
					(thickness 0.15)
				)
				(justify left bottom)
			)
		)
		(pad "1" smd roundrect
			(at -0.48 0 270)
			(size 0.59 0.64)
			(layers "F.Cu" "F.Mask" "F.Paste")
			(roundrect_rratio 0.25)
			(net 31 "/USB/VREGIN")
			(pintype "passive")
		)
		(pad "2" smd roundrect
			(at 0.48 0 270)
			(size 0.59 0.64)
			(layers "F.Cu" "F.Mask" "F.Paste")
			(roundrect_rratio 0.25)
			(net 3 "GND")
			(pintype "passive")
		)
	)
	(footprint "antmicro-footprints:TP_SMD_0.75mm"
		(layer "F.Cu")
		(at 74.817962 162.0165 -90)
		(property "Reference" "TP309"
			(at 1.36 -0.39 0)
			(layer "F.SilkS")
			(effects
				(font
					(size 0.7 0.7)
					(thickness 0.15)
				)
				(justify right bottom)
			)
		)
		(property "Value" "TP_0.75mm_SMD"
			(at 0 1.2 90)
			(layer "F.Fab")
			(effects
				(font
					(size 0.7 0.7)
					(thickness 0.15)
				)
				(justify right bottom)
			)
		)
		(property "MPN" ""
			(at 0 0 270)
			(unlocked yes)
			(layer "F.Fab")
			(hide yes)
			(effects
				(font
					(size 1 1)
					(thickness 0.15)
				)
			)
		)
		(property "Manufacturer" ""
			(at 0 0 270)
			(unlocked yes)
			(layer "F.Fab")
			(hide yes)
			(effects
				(font
					(size 1 1)
					(thickness 0.15)
				)
			)
		)
		(property "Author" "Antmicro"
			(at 0 0 270)
			(unlocked yes)
			(layer "F.Fab")
			(hide yes)
			(effects
				(font
					(size 1 1)
					(thickness 0.15)
				)
			)
		)
		(property "License" "Apache-2.0"
			(at 0 0 270)
			(unlocked yes)
			(layer "F.Fab")
			(hide yes)
			(effects
				(font
					(size 1 1)
					(thickness 0.15)
				)
			)
		)
		(sheetname "/Supply/")
		(sheetfile "supply.kicad_sch")
		(attr exclude_from_pos_files exclude_from_bom)
		(fp_circle
			(center 0 0)
			(end 0.475 0)
			(stroke
				(width 0.05)
				(type default)
			)
			(fill no)
			(layer "F.CrtYd")
		)
		(fp_text user "Author: Antmicro"
			(at -0.4 3.901 270)
			(layer "F.Fab")
			(effects
				(font
					(size 0.7 0.7)
					(thickness 0.15)
				)
				(justify left bottom)
			)
		)
		(fp_text user "License: Apache-2.0"
			(at -0.4 5.101 270)
			(layer "F.Fab")
			(effects
				(font
					(size 0.7 0.7)
					(thickness 0.15)
				)
				(justify left bottom)
			)
		)
		(fp_text user "${REFERENCE}"
			(at -0.4 2.7 270)
			(layer "F.Fab")
			(effects
				(font
					(size 0.7 0.7)
					(thickness 0.15)
				)
				(justify left bottom)
			)
		)
		(pad "1" smd circle
			(at 0 0 270)
			(size 0.75 0.75)
			(layers "F.Cu" "F.Mask")
			(net 9 "+3V3")
			(pinfunction "1")
			(pintype "passive")
		)
	)
	(footprint "antmicro-footprints:C_0402_1005Metric"
		(layer "F.Cu")
		(at 62.117962 175.7255 -90)
		(descr "Capacitor SMD 0402")
		(tags "capacitor SMD 0402")
		(property "Reference" "C825"
			(at -3.579 14.88 90)
			(layer "F.SilkS")
			(effects
				(font
					(size 0.7 0.7)
					(thickness 0.15)
				)
				(justify right bottom)
			)
		)
		(property "Value" "C_39p_0402"
			(at -1.022927 2.155213 90)
			(layer "F.Fab")
			(effects
				(font
					(size 0.7 0.7)
					(thickness 0.15)
				)
				(justify right bottom)
			)
		)
		(property "Datasheet" "https://spicat.kyocera-avx.com/product/mlcc/chartview/04025A390JAT2A/"
			(at 0 0 270)
			(layer "F.Fab")
			(hide yes)
			(effects
				(font
					(size 1.27 1.27)
					(thickness 0.15)
				)
			)
		)
		(property "Description" "SMD Multilayer Ceramic Capacitor, 39 pF, 50 V, 0402 [1005 Metric], ± 5%, C0G / NP0, AVX 0402 MLCC"
			(at 0 0 270)
			(layer "F.Fab")
			(hide yes)
			(effects
				(font
					(size 1.27 1.27)
					(thickness 0.15)
				)
			)
		)
		(property "MPN" "04025A390JAT2A"
			(at 0 0 270)
			(unlocked yes)
			(layer "F.Fab")
			(hide yes)
			(effects
				(font
					(size 1 1)
					(thickness 0.15)
				)
			)
		)
		(property "Manufacturer" "KYOCERA AVX"
			(at 0 0 270)
			(unlocked yes)
			(layer "F.Fab")
			(hide yes)
			(effects
				(font
					(size 1 1)
					(thickness 0.15)
				)
			)
		)
		(property "License" "Apache-2.0"
			(at 0 0 270)
			(unlocked yes)
			(layer "F.Fab")
			(hide yes)
			(effects
				(font
					(size 1 1)
					(thickness 0.15)
				)
			)
		)
		(property "Author" "Antmicro"
			(at 0 0 270)
			(unlocked yes)
			(layer "F.Fab")
			(hide yes)
			(effects
				(font
					(size 1 1)
					(thickness 0.15)
				)
			)
		)
		(property "Val" "39p"
			(at 0 0 270)
			(unlocked yes)
			(layer "F.Fab")
			(hide yes)
			(effects
				(font
					(size 1 1)
					(thickness 0.15)
				)
			)
		)
		(property "Voltage" ""
			(at 0 0 270)
			(unlocked yes)
			(layer "F.Fab")
			(hide yes)
			(effects
				(font
					(size 1 1)
					(thickness 0.15)
				)
			)
		)
		(property "Dielectric" ""
			(at 0 0 270)
			(unlocked yes)
			(layer "F.Fab")
			(hide yes)
			(effects
				(font
					(size 1 1)
					(thickness 0.15)
				)
			)
		)
		(sheetname "/Peripherals/")
		(sheetfile "peripherals.kicad_sch")
		(attr smd)
		(fp_rect
			(start -0.925 -0.47)
			(end 0.925 0.47)
			(stroke
				(width 0.05)
				(type default)
			)
			(fill no)
			(layer "F.CrtYd")
		)
		(fp_line
			(start -0.494 0.248)
			(end -0.494 -0.25)
			(stroke
				(width 0.15)
				(type solid)
			)
			(layer "F.Fab")
		)
		(fp_line
			(start 0.504 0.248)
			(end -0.494 0.248)
			(stroke
				(width 0.15)
				(type solid)
			)
			(layer "F.Fab")
		)
		(fp_line
			(start -0.494 -0.25)
			(end 0.504 -0.25)
			(stroke
				(width 0.15)
				(type solid)
			)
			(layer "F.Fab")
		)
		(fp_line
			(start 0.504 -0.25)
			(end 0.504 0.248)
			(stroke
				(width 0.15)
				(type solid)
			)
			(layer "F.Fab")
		)
		(fp_text user "License: Apache-2.0"
			(at -0.939 5.799 270)
			(layer "F.Fab")
			(effects
				(font
					(size 0.7 0.7)
					(thickness 0.15)
				)
				(justify left bottom)
			)
		)
		(fp_text user "${REFERENCE}"
			(at -0.939 4.599 270)
			(layer "F.Fab")
			(effects
				(font
					(size 0.7 0.7)
					(thickness 0.15)
				)
				(justify left bottom)
			)
		)
		(fp_text user "Author: Antmicro"
			(at -0.939 3.399 270)
			(layer "F.Fab")
			(effects
				(font
					(size 0.7 0.7)
					(thickness 0.15)
				)
				(justify left bottom)
			)
		)
		(pad "1" smd roundrect
			(at -0.48 0 270)
			(size 0.59 0.64)
			(layers "F.Cu" "F.Mask" "F.Paste")
			(roundrect_rratio 0.25)
			(net 106 "Net-(C814-Pad2)")
			(pintype "passive")
		)
		(pad "2" smd roundrect
			(at 0.48 0 270)
			(size 0.59 0.64)
			(layers "F.Cu" "F.Mask" "F.Paste")
			(roundrect_rratio 0.25)
			(net 3 "GND")
			(pintype "passive")
		)
	)
	(footprint "antmicro-footprints:R_0402_1005Metric"
		(layer "F.Cu")
		(at 99.037962 131.8365 180)
		(descr "Resistor SMD 0402")
		(tags "resistor SMD 0402")
		(property "Reference" "R914"
			(at 0.66 -0.34 0)
			(layer "F.SilkS")
			(effects
				(font
					(size 0.7 0.7)
					(thickness 0.15)
				)
				(justify right bottom)
			)
		)
		(property "Value" "R_100k_0402"
			(at -1.011843 1.772047 0)
			(layer "F.Fab")
			(effects
				(font
					(size 0.7 0.7)
					(thickness 0.15)
				)
				(justify right bottom)
			)
		)
		(property "Datasheet" "https://www.bourns.com/docs/product-datasheets/cr.pdf"
			(at 0 0 180)
			(layer "F.Fab")
			(hide yes)
			(effects
				(font
					(size 1.27 1.27)
					(thickness 0.15)
				)
			)
		)
		(property "Manufacturer" "Bourns"
			(at 0 0 180)
			(unlocked yes)
			(layer "F.Fab")
			(hide yes)
			(effects
				(font
					(size 1 1)
					(thickness 0.15)
				)
			)
		)
		(property "MPN" "CR0402-FX-1003GLF"
			(at 0 0 180)
			(unlocked yes)
			(layer "F.Fab")
			(hide yes)
			(effects
				(font
					(size 1 1)
					(thickness 0.15)
				)
			)
		)
		(property "Val" "100k"
			(at 0 0 180)
			(unlocked yes)
			(layer "F.Fab")
			(hide yes)
			(effects
				(font
					(size 1 1)
					(thickness 0.15)
				)
			)
		)
		(property "License" "Apache-2.0"
			(at 0 0 180)
			(unlocked yes)
			(layer "F.Fab")
			(hide yes)
			(effects
				(font
					(size 1 1)
					(thickness 0.15)
				)
			)
		)
		(property "Author" "Antmicro"
			(at 0 0 180)
			(unlocked yes)
			(layer "F.Fab")
			(hide yes)
			(effects
				(font
					(size 1 1)
					(thickness 0.15)
				)
			)
		)
		(property "Tolerance" "1%"
			(at 0 0 180)
			(unlocked yes)
			(layer "F.Fab")
			(hide yes)
			(effects
				(font
					(size 1 1)
					(thickness 0.15)
				)
			)
		)
		(sheetname "/USB/")
		(sheetfile "usb.kicad_sch")
		(attr smd)
		(fp_rect
			(start -0.925 -0.47)
			(end 0.925 0.47)
			(stroke
				(width 0.05)
				(type default)
			)
			(fill no)
			(layer "F.CrtYd")
		)
		(fp_rect
			(start -0.5 -0.25)
			(end 0.5 0.25)
			(stroke
				(width 0.15)
				(type solid)
			)
			(fill no)
			(layer "F.Fab")
		)
		(fp_text user "Author: Antmicro"
			(at -0.95 4.169 180)
			(layer "F.Fab")
			(effects
				(font
					(size 0.7 0.7)
					(thickness 0.15)
				)
				(justify left bottom)
			)
		)
		(fp_text user "${REFERENCE}"
			(at -0.95 3.168 180)
			(layer "F.Fab")
			(effects
				(font
					(size 0.7 0.7)
					(thickness 0.15)
				)
				(justify left bottom)
			)
		)
		(fp_text user "License: Apache-2.0"
			(at -0.95 5.169 180)
			(layer "F.Fab")
			(effects
				(font
					(size 0.7 0.7)
					(thickness 0.15)
				)
				(justify left bottom)
			)
		)
		(pad "1" smd roundrect
			(at -0.48 0 180)
			(size 0.59 0.64)
			(layers "F.Cu" "F.Mask" "F.Paste")
			(roundrect_rratio 0.25)
			(net 28 "/USB/+5V_{CAP}")
			(pintype "passive")
		)
		(pad "2" smd roundrect
			(at 0.48 0 180)
			(size 0.59 0.64)
			(layers "F.Cu" "F.Mask" "F.Paste")
			(roundrect_rratio 0.25)
			(net 288 "/USB/USBA_OUT_EN")
			(pintype "passive")
		)
	)
	(footprint "antmicro-footprints:XDFN-2_1x0.60mm"
		(layer "F.Cu")
		(at 134.337962 125.9465 180)
		(property "Reference" "D203"
			(at 0.46 -1.495 180)
			(layer "F.SilkS")
			(effects
				(font
					(size 0.7 0.7)
					(thickness 0.15)
				)
				(justify left bottom)
			)
		)
		(property "Value" "TPD1E0B04_XDFN-2"
			(at 0 1.5 0)
			(layer "F.Fab")
			(effects
				(font
					(size 0.7 0.7)
					(thickness 0.15)
				)
				(justify right bottom)
			)
		)
		(property "Datasheet" "https://www.ti.com/general/docs/suppproductinfo.tsp?distId=26&gotoUrl=https://www.ti.com/lit/gpn/tpd1e0b04"
			(at 0 0 180)
			(layer "F.Fab")
			(hide yes)
			(effects
				(font
					(size 1.27 1.27)
					(thickness 0.15)
				)
			)
		)
		(property "MPN" "TPD1E0B04DPYR"
			(at 268.675924 251.893 0)
			(layer "F.Fab")
			(hide yes)
			(effects
				(font
					(size 1 1)
					(thickness 0.15)
				)
			)
		)
		(property "Manufacturer" "Texas Instruments"
			(at 268.675924 251.893 0)
			(layer "F.Fab")
			(hide yes)
			(effects
				(font
					(size 1 1)
					(thickness 0.15)
				)
			)
		)
		(property "Author" "Antmicro"
			(at 0 0 180)
			(unlocked yes)
			(layer "F.Fab")
			(hide yes)
			(effects
				(font
					(size 1 1)
					(thickness 0.15)
				)
			)
		)
		(property "License" "Apache-2.0"
			(at 0 0 180)
			(unlocked yes)
			(layer "F.Fab")
			(hide yes)
			(effects
				(font
					(size 1 1)
					(thickness 0.15)
				)
			)
		)
		(sheetname "/Compute module/")
		(sheetfile "compute-module.kicad_sch")
		(attr smd)
		(fp_rect
			(start -0.725 -0.475)
			(end 0.725 0.475)
			(stroke
				(width 0.05)
				(type solid)
			)
			(fill no)
			(layer "F.CrtYd")
		)
		(fp_rect
			(start -0.55 -0.35)
			(end 0.55 0.35)
			(stroke
				(width 0.15)
				(type solid)
			)
			(fill no)
			(layer "F.Fab")
		)
		(fp_text user "${REFERENCE}"
			(at -0.8 3.2 180)
			(layer "F.Fab")
			(effects
				(font
					(size 0.7 0.7)
					(thickness 0.15)
				)
				(justify left bottom)
			)
		)
		(fp_text user "Author: Antmicro"
			(at -0.8 4.4 180)
			(layer "F.Fab")
			(effects
				(font
					(size 0.7 0.7)
					(thickness 0.15)
				)
				(justify left bottom)
			)
		)
		(fp_text user "License: Apache-2.0"
			(at -0.8 5.6 180)
			(layer "F.Fab")
			(effects
				(font
					(size 0.7 0.7)
					(thickness 0.15)
				)
				(justify left bottom)
			)
		)
		(pad "1" smd roundrect
			(at -0.351 0 180)
			(size 0.3 0.5)
			(layers "F.Cu" "F.Mask" "F.Paste")
			(roundrect_rratio 0.25)
			(net 3 "GND")
			(pinfunction "C")
			(pintype "passive")
		)
		(pad "2" smd roundrect
			(at 0.349 0 180)
			(size 0.3 0.5)
			(layers "F.Cu" "F.Mask" "F.Paste")
			(roundrect_rratio 0.25)
			(net 2 "Net-(D203-A)")
			(pinfunction "A")
			(pintype "passive")
		)
	)
	(footprint "antmicro-footprints:SOT-23-3"
		(layer "F.Cu")
		(at 104.842962 150.592)
		(property "Reference" "Q204"
			(at -1.475 -1.6255 0)
			(layer "F.SilkS")
			(effects
				(font
					(size 0.7 0.7)
					(thickness 0.15)
				)
				(justify left bottom)
			)
		)
		(property "Value" "SSM3J332R"
			(at -1.9 2.7 0)
			(layer "F.Fab")
			(effects
				(font
					(size 0.7 0.7)
					(thickness 0.15)
				)
				(justify left bottom)
			)
		)
		(property "Datasheet" "https://www.mouser.com/datasheet/2/408/SSM3J332R_datasheet_en_20181015-1150575.pdf"
			(at 0 0 0)
			(layer "F.Fab")
			(hide yes)
			(effects
				(font
					(size 1.27 1.27)
					(thickness 0.15)
				)
			)
		)
		(property "MPN" "SSM3J332R,LF"
			(at 0 0 0)
			(unlocked yes)
			(layer "F.Fab")
			(hide yes)
			(effects
				(font
					(size 1 1)
					(thickness 0.15)
				)
			)
		)
		(property "Manufacturer" "Toshiba"
			(at 0 0 0)
			(unlocked yes)
			(layer "F.Fab")
			(hide yes)
			(effects
				(font
					(size 1 1)
					(thickness 0.15)
				)
			)
		)
		(property "Author" "Antmicro"
			(at 0 0 0)
			(unlocked yes)
			(layer "F.Fab")
			(hide yes)
			(effects
				(font
					(size 1 1)
					(thickness 0.15)
				)
			)
		)
		(property "License" "Apache-2.0"
			(at 0 0 0)
			(unlocked yes)
			(layer "F.Fab")
			(hide yes)
			(effects
				(font
					(size 1 1)
					(thickness 0.15)
				)
			)
		)
		(sheetname "/Compute module/")
		(sheetfile "compute-module.kicad_sch")
		(attr smd)
		(fp_line
			(start -1.45 -1.35)
			(end -0.85 -1.35)
			(stroke
				(width 0.15)
				(type solid)
			)
			(layer "F.SilkS")
		)
		(fp_line
			(start -0.85 -1.35)
			(end -0.7 -1.5)
			(stroke
				(width 0.15)
				(type solid)
			)
			(layer "F.SilkS")
		)
		(fp_line
			(start -0.7 1.5)
			(end -0.7 1.35)
			(stroke
				(width 0.15)
				(type solid)
			)
			(layer "F.SilkS")
		)
		(fp_line
			(start 0.7 -1.5)
			(end -0.7 -1.5)
			(stroke
				(width 0.15)
				(type solid)
			)
			(layer "F.SilkS")
		)
		(fp_line
			(start 0.7 -0.4)
			(end 0.7 -1.5)
			(stroke
				(width 0.15)
				(type solid)
			)
			(layer "F.SilkS")
		)
		(fp_line
			(start 0.7 0.4)
			(end 0.7 1.5)
			(stroke
				(width 0.15)
				(type solid)
			)
			(layer "F.SilkS")
		)
		(fp_line
			(start 0.7 1.5)
			(end -0.7 1.5)
			(stroke
				(width 0.15)
				(type solid)
			)
			(layer "F.SilkS")
		)
		(fp_line
			(start -1.75 -0.5)
			(end -1.75 -1.4)
			(stroke
				(width 0.05)
				(type solid)
			)
			(layer "F.CrtYd")
		)
		(fp_line
			(start -1.75 0.5)
			(end -0.85 0.5)
			(stroke
				(width 0.05)
				(type solid)
			)
			(layer "F.CrtYd")
		)
		(fp_line
			(start -1.75 1.4)
			(end -1.75 0.5)
			(stroke
				(width 0.05)
				(type solid)
			)
			(layer "F.CrtYd")
		)
		(fp_line
			(start -0.9 -1.6)
			(end -0.9 -1.4)
			(stroke
				(width 0.05)
				(type solid)
			)
			(layer "F.CrtYd")
		)
		(fp_line
			(start -0.9 -1.6)
			(end 0.825 -1.6)
			(stroke
				(width 0.05)
				(type solid)
			)
			(layer "F.CrtYd")
		)
		(fp_line
			(start -0.9 -1.4)
			(end -1.75 -1.4)
			(stroke
				(width 0.05)
				(type solid)
			)
			(layer "F.CrtYd")
		)
		(fp_line
			(start -0.85 -0.5)
			(end -1.75 -0.5)
			(stroke
				(width 0.05)
				(type solid)
			)
			(layer "F.CrtYd")
		)
		(fp_line
			(start -0.85 0.5)
			(end -0.85 -0.5)
			(stroke
				(width 0.05)
				(type solid)
			)
			(layer "F.CrtYd")
		)
		(fp_line
			(start -0.85 1.4)
			(end -1.75 1.4)
			(stroke
				(width 0.05)
				(type solid)
			)
			(layer "F.CrtYd")
		)
		(fp_line
			(start -0.85 1.65)
			(end -0.85 1.4)
			(stroke
				(width 0.05)
				(type solid)
			)
			(layer "F.CrtYd")
		)
		(fp_line
			(start 0.825 -1.6)
			(end 0.825 -0.45)
			(stroke
				(width 0.05)
				(type solid)
			)
			(layer "F.CrtYd")
		)
		(fp_line
			(start 0.825 -0.45)
			(end 1.75 -0.45)
			(stroke
				(width 0.05)
				(type solid)
			)
			(layer "F.CrtYd")
		)
		(fp_line
			(start 0.85 0.45)
			(end 0.85 1.65)
			(stroke
				(width 0.05)
				(type solid)
			)
			(layer "F.CrtYd")
		)
		(fp_line
			(start 0.85 1.65)
			(end -0.85 1.65)
			(stroke
				(width 0.05)
				(type solid)
			)
			(layer "F.CrtYd")
		)
		(fp_line
			(start 1.75 -0.45)
			(end 1.75 0.45)
			(stroke
				(width 0.05)
				(type solid)
			)
			(layer "F.CrtYd")
		)
		(fp_line
			(start 1.75 0.45)
			(end 0.85 0.45)
			(stroke
				(width 0.05)
				(type solid)
			)
			(layer "F.CrtYd")
		)
		(fp_line
			(start -0.712 -1.325)
			(end -0.712 1.523)
			(stroke
				(width 0.15)
				(type solid)
			)
			(layer "F.Fab")
		)
		(fp_line
			(start -0.712 1.519)
			(end 0.688 1.519)
			(stroke
				(width 0.15)
				(type solid)
			)
			(layer "F.Fab")
		)
		(fp_line
			(start -0.437 -1.526)
			(end -0.712 -1.325)
			(stroke
				(width 0.15)
				(type solid)
			)
			(layer "F.Fab")
		)
		(fp_line
			(start -0.437 -1.526)
			(end 0.688 -1.526)
			(stroke
				(width 0.15)
				(type solid)
			)
			(layer "F.Fab")
		)
		(fp_line
			(start 0.688 1.519)
			(end 0.688 -1.52)
			(stroke
				(width 0.15)
				(type solid)
			)
			(layer "F.Fab")
		)
		(fp_text user "Author: Antmicro"
			(at -1.837 5.3 0)
			(layer "F.Fab")
			(effects
				(font
					(size 0.7 0.7)
					(thickness 0.15)
				)
				(justify left bottom)
			)
		)
		(fp_text user "${REFERENCE}"
			(at -1.837 4 0)
			(layer "F.Fab")
			(effects
				(font
					(size 0.7 0.7)
					(thickness 0.15)
				)
				(justify left bottom)
			)
		)
		(fp_text user "License: Apache-2.0"
			(at -1.8 6.8 0)
			(layer "F.Fab")
			(effects
				(font
					(size 0.7 0.7)
					(thickness 0.15)
				)
				(justify left bottom)
			)
		)
		(pad "1" smd roundrect
			(at -1.1 -0.951)
			(size 1 0.6)
			(layers "F.Cu" "F.Mask" "F.Paste")
			(roundrect_rratio 0.15)
			(net 327 "Net-(Q201-D)")
			(pinfunction "G")
			(pintype "input")
		)
		(pad "2" smd roundrect
			(at -1.1 0.949)
			(size 1 0.6)
			(layers "F.Cu" "F.Mask" "F.Paste")
			(roundrect_rratio 0.15)
			(net 10 "+5V")
			(pinfunction "S")
			(pintype "passive")
		)
		(pad "3" smd roundrect
			(at 1.1 -0.0005)
			(size 1 0.6)
			(layers "F.Cu" "F.Mask" "F.Paste")
			(roundrect_rratio 0.15)
			(net 259 "/Compute module/Pf_5V.SCL")
			(pinfunction "D")
			(pintype "passive")
		)
	)
	(footprint "antmicro-footprints:Spacer_Drill3.7mm_H3mm_9774030151R"
		(layer "F.Cu")
		(at 80.520961 128.314 90)
		(descr "Spacer M=3 h=3mm fi=5.1mm")
		(property "Reference" "H203"
			(at -1.511 4.004039 270)
			(layer "F.SilkS")
			(effects
				(font
					(size 0.7 0.7)
					(thickness 0.15)
				)
				(justify left bottom)
			)
		)
		(property "Value" "Spacer_Drill3.7mm_H3mm_9774030151R"
			(at 0 4 90)
			(layer "F.Fab")
			(effects
				(font
					(size 0.7 0.7)
					(thickness 0.15)
				)
				(justify left bottom)
			)
		)
		(property "Datasheet" "https://www.we-online.com/catalog/datasheet/9774030151.pdf"
			(at 0 0 90)
			(layer "F.Fab")
			(hide yes)
			(effects
				(font
					(size 1.27 1.27)
					(thickness 0.15)
				)
			)
		)
		(property "Manufacturer" "Würth Elektronik"
			(at 0 0 90)
			(unlocked yes)
			(layer "F.Fab")
			(hide yes)
			(effects
				(font
					(size 1 1)
					(thickness 0.15)
				)
			)
		)
		(property "MPN" "9774030151R"
			(at 0 0 90)
			(unlocked yes)
			(layer "F.Fab")
			(hide yes)
			(effects
				(font
					(size 1 1)
					(thickness 0.15)
				)
			)
		)
		(property "Author" "Antmicro"
			(at 0 0 90)
			(unlocked yes)
			(layer "F.Fab")
			(hide yes)
			(effects
				(font
					(size 1 1)
					(thickness 0.15)
				)
			)
		)
		(property "License" "Apache-2.0"
			(at 0 0 90)
			(unlocked yes)
			(layer "F.Fab")
			(hide yes)
			(effects
				(font
					(size 1 1)
					(thickness 0.15)
				)
			)
		)
		(sheetname "/Compute module/")
		(sheetfile "compute-module.kicad_sch")
		(solder_paste_margin_ratio -1)
		(attr smd)
		(fp_circle
			(center 0 0)
			(end 3.05 0)
			(stroke
				(width 0.05)
				(type solid)
			)
			(fill no)
			(layer "F.CrtYd")
		)
		(fp_circle
			(center 0 0)
			(end 2.6 0)
			(stroke
				(width 0.15)
				(type solid)
			)
			(fill no)
			(layer "F.Fab")
		)
		(fp_text user "${REFERENCE}"
			(at -9.6 6.5 90)
			(layer "F.Fab")
			(effects
				(font
					(size 0.7 0.7)
					(thickness 0.15)
				)
				(justify left bottom)
			)
		)
		(fp_text user "License: Apache-2.0"
			(at -9.6 8.9 90)
			(layer "F.Fab")
			(effects
				(font
					(size 0.7 0.7)
					(thickness 0.15)
				)
				(justify left bottom)
			)
		)
		(fp_text user "Author: Antmicro"
			(at -9.6 7.7 90)
			(layer "F.Fab")
			(effects
				(font
					(size 0.7 0.7)
					(thickness 0.15)
				)
				(justify left bottom)
			)
		)
		(pad "" smd custom
			(at -1.7 -1.7 90)
			(size 0.62 0.62)
			(layers "F.Paste")
			(thermal_bridge_angle 90)
			(options
				(clearance outline)
				(anchor circle)
			)
			(primitives
				(gr_arc
					(start -0.250195 1.279127)
					(mid 0.285453 0.294389)
					(end 1.266786 -0.24747)
					(width 0.2)
				)
				(gr_arc
					(start -0.34334 1.279127)
					(mid 0.218448 0.232561)
					(end 1.259603 -0.339191)
					(width 0.2)
				)
				(gr_arc
					(start -0.436309 1.279127)
					(mid 0.152481 0.169693)
					(end 1.255279 -0.431435)
					(width 0.2)
				)
				(gr_arc
					(start -0.529126 1.279127)
					(mid 0.087542 0.105784)
					(end 1.253811 -0.524161)
					(width 0.2)
				)
				(gr_arc
					(start -0.621807 1.279127)
					(mid 0.0309 0.033527)
					(end 1.275473 -0.621136)
					(width 0.2)
				)
				(gr_arc
					(start -0.71437 1.279127)
					(mid -0.037758 -0.026651)
					(end 1.263664 -0.711602)
					(width 0.2)
				)
				(gr_arc
					(start -0.806826 1.279127)
					(mid -0.105837 -0.087395)
					(end 1.253435 -0.802342)
					(width 0.2)
				)
				(gr_arc
					(start -0.899187 1.279127)
					(mid -0.165236 -0.156885)
					(end 1.267475 -0.897258)
					(width 0.2)
				)
				(gr_arc
					(start -0.991463 1.279127)
					(mid -0.228522 -0.222449)
					(end 1.270645 -0.990112)
					(width 0.2)
				)
				(gr_arc
					(start -1.083663 1.279127)
					(mid -0.294507 -0.285313)
					(end 1.266278 -1.081674)
					(width 0.2)
				)
				(gr_line
					(start 1.279127 -0.250195)
					(end 1.279127 -1.083663)
					(width 0.2)
				)
				(gr_line
					(start -0.250195 1.279127)
					(end -1.083663 1.279127)
					(width 0.2)
				)
			)
		)
		(pad "" smd custom
			(at -1.7 1.7 180)
			(size 0.62 0.62)
			(layers "F.Paste")
			(thermal_bridge_angle 90)
			(options
				(clearance outline)
				(anchor circle)
			)
			(primitives
				(gr_arc
					(start -0.250195 1.279127)
					(mid 0.285453 0.294389)
					(end 1.266786 -0.24747)
					(width 0.2)
				)
				(gr_arc
					(start -0.34334 1.279127)
					(mid 0.218448 0.232561)
					(end 1.259603 -0.339191)
					(width 0.2)
				)
				(gr_arc
					(start -0.436309 1.279127)
					(mid 0.152481 0.169693)
					(end 1.255279 -0.431435)
					(width 0.2)
				)
				(gr_arc
					(start -0.529126 1.279127)
					(mid 0.087542 0.105784)
					(end 1.253811 -0.524161)
					(width 0.2)
				)
				(gr_arc
					(start -0.621807 1.279127)
					(mid 0.0309 0.033527)
					(end 1.275473 -0.621136)
					(width 0.2)
				)
				(gr_arc
					(start -0.71437 1.279127)
					(mid -0.037758 -0.026651)
					(end 1.263664 -0.711602)
					(width 0.2)
				)
				(gr_arc
					(start -0.806826 1.279127)
					(mid -0.105837 -0.087395)
					(end 1.253435 -0.802342)
					(width 0.2)
				)
				(gr_arc
					(start -0.899187 1.279127)
					(mid -0.165236 -0.156885)
					(end 1.267475 -0.897258)
					(width 0.2)
				)
				(gr_arc
					(start -0.991463 1.279127)
					(mid -0.228522 -0.222449)
					(end 1.270645 -0.990112)
					(width 0.2)
				)
				(gr_arc
					(start -1.083663 1.279127)
					(mid -0.294507 -0.285313)
					(end 1.266278 -1.081674)
					(width 0.2)
				)
				(gr_line
					(start 1.279127 -0.250195)
					(end 1.279127 -1.083663)
					(width 0.2)
				)
				(gr_line
					(start -0.250195 1.279127)
					(end -1.083663 1.279127)
					(width 0.2)
				)
			)
		)
		(pad "" smd custom
			(at 1.7 -1.7)
			(size 0.62 0.62)
			(layers "F.Paste")
			(thermal_bridge_angle 90)
			(options
				(clearance outline)
				(anchor circle)
			)
			(primitives
				(gr_arc
					(start -0.250195 1.279127)
					(mid 0.285453 0.294389)
					(end 1.266786 -0.24747)
					(width 0.2)
				)
				(gr_arc
					(start -0.34334 1.279127)
					(mid 0.218448 0.232561)
					(end 1.259603 -0.339191)
					(width 0.2)
				)
				(gr_arc
					(start -0.436309 1.279127)
					(mid 0.152481 0.169693)
					(end 1.255279 -0.431435)
					(width 0.2)
				)
				(gr_arc
					(start -0.529126 1.279127)
					(mid 0.087542 0.105784)
					(end 1.253811 -0.524161)
					(width 0.2)
				)
				(gr_arc
					(start -0.621807 1.279127)
					(mid 0.0309 0.033527)
					(end 1.275473 -0.621136)
					(width 0.2)
				)
				(gr_arc
					(start -0.71437 1.279127)
					(mid -0.037758 -0.026651)
					(end 1.263664 -0.711602)
					(width 0.2)
				)
				(gr_arc
					(start -0.806826 1.279127)
					(mid -0.105837 -0.087395)
					(end 1.253435 -0.802342)
					(width 0.2)
				)
				(gr_arc
					(start -0.899187 1.279127)
					(mid -0.165236 -0.156885)
					(end 1.267475 -0.897258)
					(width 0.2)
				)
				(gr_arc
					(start -0.991463 1.279127)
					(mid -0.228522 -0.222449)
					(end 1.270645 -0.990112)
					(width 0.2)
				)
				(gr_arc
					(start -1.083663 1.279127)
					(mid -0.294507 -0.285313)
					(end 1.266278 -1.081674)
					(width 0.2)
				)
				(gr_line
					(start 1.279127 -0.250195)
					(end 1.279127 -1.083663)
					(width 0.2)
				)
				(gr_line
					(start -0.250195 1.279127)
					(end -1.083663 1.279127)
					(width 0.2)
				)
			)
		)
		(pad "" smd custom
			(at 1.7 1.7 270)
			(size 0.62 0.62)
			(layers "F.Paste")
			(thermal_bridge_angle 90)
			(options
				(clearance outline)
				(anchor circle)
			)
			(primitives
				(gr_arc
					(start -0.250195 1.279127)
					(mid 0.285453 0.294389)
					(end 1.266786 -0.24747)
					(width 0.2)
				)
				(gr_arc
					(start -0.34334 1.279127)
					(mid 0.218448 0.232561)
					(end 1.259603 -0.339191)
					(width 0.2)
				)
				(gr_arc
					(start -0.436309 1.279127)
					(mid 0.152481 0.169693)
					(end 1.255279 -0.431435)
					(width 0.2)
				)
				(gr_arc
					(start -0.529126 1.279127)
					(mid 0.087542 0.105784)
					(end 1.253811 -0.524161)
					(width 0.2)
				)
				(gr_arc
					(start -0.621807 1.279127)
					(mid 0.0309 0.033527)
					(end 1.275473 -0.621136)
					(width 0.2)
				)
				(gr_arc
					(start -0.71437 1.279127)
					(mid -0.037758 -0.026651)
					(end 1.263664 -0.711602)
					(width 0.2)
				)
				(gr_arc
					(start -0.806826 1.279127)
					(mid -0.105837 -0.087395)
					(end 1.253435 -0.802342)
					(width 0.2)
				)
				(gr_arc
					(start -0.899187 1.279127)
					(mid -0.165236 -0.156885)
					(end 1.267475 -0.897258)
					(width 0.2)
				)
				(gr_arc
					(start -0.991463 1.279127)
					(mid -0.228522 -0.222449)
					(end 1.270645 -0.990112)
					(width 0.2)
				)
				(gr_arc
					(start -1.083663 1.279127)
					(mid -0.294507 -0.285313)
					(end 1.266278 -1.081674)
					(width 0.2)
				)
				(gr_line
					(start 1.279127 -0.250195)
					(end 1.279127 -1.083663)
					(width 0.2)
				)
				(gr_line
					(start -0.250195 1.279127)
					(end -1.083663 1.279127)
					(width 0.2)
				)
			)
		)
		(pad "1" thru_hole circle
			(at 0 0 90)
			(size 6 6)
			(drill 3.7)
			(layers "*.Cu" "*.Mask")
			(remove_unused_layers no)
			(net 3 "GND")
			(pintype "passive")
		)
	)
	(footprint "antmicro-footprints:C_0402_1005Metric"
		(layer "F.Cu")
		(at 69.817962 176.8165 -90)
		(descr "Capacitor SMD 0402")
		(tags "capacitor SMD 0402")
		(property "Reference" "C808"
			(at 1.8735 -0.432038 180)
			(layer "F.SilkS")
			(effects
				(font
					(size 0.7 0.65)
					(thickness 0.15)
				)
				(justify right bottom)
			)
		)
		(property "Value" "C_2u2_0402"
			(at -1.022927 2.155213 90)
			(layer "F.Fab")
			(effects
				(font
					(size 0.7 0.7)
					(thickness 0.15)
				)
				(justify right bottom)
			)
		)
		(property "Datasheet" "https://product.tdk.com/en/search/capacitor/ceramic/mlcc/info?part_no=C1005X5R1A225K050BC"
			(at 0 0 270)
			(layer "F.Fab")
			(hide yes)
			(effects
				(font
					(size 1.27 1.27)
					(thickness 0.15)
				)
			)
		)
		(property "MPN" "C1005X5R1A225K050BC"
			(at 0 0 270)
			(unlocked yes)
			(layer "F.Fab")
			(hide yes)
			(effects
				(font
					(size 1 1)
					(thickness 0.15)
				)
			)
		)
		(property "Manufacturer" "TDK"
			(at 0 0 270)
			(unlocked yes)
			(layer "F.Fab")
			(hide yes)
			(effects
				(font
					(size 1 1)
					(thickness 0.15)
				)
			)
		)
		(property "License" "Apache-2.0"
			(at 0 0 270)
			(unlocked yes)
			(layer "F.Fab")
			(hide yes)
			(effects
				(font
					(size 1 1)
					(thickness 0.15)
				)
			)
		)
		(property "Author" "Antmicro"
			(at 0 0 270)
			(unlocked yes)
			(layer "F.Fab")
			(hide yes)
			(effects
				(font
					(size 1 1)
					(thickness 0.15)
				)
			)
		)
		(property "Val" "2u2"
			(at 0 0 270)
			(unlocked yes)
			(layer "F.Fab")
			(hide yes)
			(effects
				(font
					(size 1 1)
					(thickness 0.15)
				)
			)
		)
		(property "Voltage" ""
			(at 0 0 270)
			(unlocked yes)
			(layer "F.Fab")
			(hide yes)
			(effects
				(font
					(size 1 1)
					(thickness 0.15)
				)
			)
		)
		(property "Dielectric" ""
			(at 0 0 270)
			(unlocked yes)
			(layer "F.Fab")
			(hide yes)
			(effects
				(font
					(size 1 1)
					(thickness 0.15)
				)
			)
		)
		(sheetname "/Peripherals/")
		(sheetfile "peripherals.kicad_sch")
		(attr smd)
		(fp_rect
			(start -0.925 -0.47)
			(end 0.925 0.47)
			(stroke
				(width 0.05)
				(type default)
			)
			(fill no)
			(layer "F.CrtYd")
		)
		(fp_line
			(start -0.494 0.248)
			(end -0.494 -0.25)
			(stroke
				(width 0.15)
				(type solid)
			)
			(layer "F.Fab")
		)
		(fp_line
			(start 0.504 0.248)
			(end -0.494 0.248)
			(stroke
				(width 0.15)
				(type solid)
			)
			(layer "F.Fab")
		)
		(fp_line
			(start -0.494 -0.25)
			(end 0.504 -0.25)
			(stroke
				(width 0.15)
				(type solid)
			)
			(layer "F.Fab")
		)
		(fp_line
			(start 0.504 -0.25)
			(end 0.504 0.248)
			(stroke
				(width 0.15)
				(type solid)
			)
			(layer "F.Fab")
		)
		(fp_text user "License: Apache-2.0"
			(at -0.939 5.799 270)
			(layer "F.Fab")
			(effects
				(font
					(size 0.7 0.7)
					(thickness 0.15)
				)
				(justify left bottom)
			)
		)
		(fp_text user "${REFERENCE}"
			(at -0.939 4.599 270)
			(layer "F.Fab")
			(effects
				(font
					(size 0.7 0.7)
					(thickness 0.15)
				)
				(justify left bottom)
			)
		)
		(fp_text user "Author: Antmicro"
			(at -0.939 3.399 270)
			(layer "F.Fab")
			(effects
				(font
					(size 0.7 0.7)
					(thickness 0.15)
				)
				(justify left bottom)
			)
		)
		(pad "1" smd roundrect
			(at -0.48 0 270)
			(size 0.59 0.64)
			(layers "F.Cu" "F.Mask" "F.Paste")
			(roundrect_rratio 0.25)
			(net 94 "Net-(U801-TVDD_IN)")
			(pintype "passive")
		)
		(pad "2" smd roundrect
			(at 0.48 0 270)
			(size 0.59 0.64)
			(layers "F.Cu" "F.Mask" "F.Paste")
			(roundrect_rratio 0.25)
			(net 3 "GND")
			(pintype "passive")
		)
	)
	(footprint "antmicro-footprints:C_0402_1005Metric"
		(layer "F.Cu")
		(at 66.142962 171.6165 180)
		(descr "Capacitor SMD 0402")
		(tags "capacitor SMD 0402")
		(property "Reference" "C809"
			(at 0.842962 -0.1835 0)
			(layer "F.SilkS")
			(effects
				(font
					(size 0.7 0.7)
					(thickness 0.15)
				)
				(justify right bottom)
			)
		)
		(property "Value" "C_100n_0402"
			(at -1.022927 2.155213 0)
			(layer "F.Fab")
			(effects
				(font
					(size 0.7 0.7)
					(thickness 0.15)
				)
				(justify right bottom)
			)
		)
		(property "Datasheet" "https://www.murata.com/products/productdetail?partno=GRM155R61H104KE14%23"
			(at 0 0 180)
			(layer "F.Fab")
			(hide yes)
			(effects
				(font
					(size 1.27 1.27)
					(thickness 0.15)
				)
			)
		)
		(property "MPN" "GRM155R61H104KE14D"
			(at 0 0 180)
			(unlocked yes)
			(layer "F.Fab")
			(hide yes)
			(effects
				(font
					(size 1 1)
					(thickness 0.15)
				)
			)
		)
		(property "Manufacturer" "Murata"
			(at 0 0 180)
			(unlocked yes)
			(layer "F.Fab")
			(hide yes)
			(effects
				(font
					(size 1 1)
					(thickness 0.15)
				)
			)
		)
		(property "License" "Apache-2.0"
			(at 0 0 180)
			(unlocked yes)
			(layer "F.Fab")
			(hide yes)
			(effects
				(font
					(size 1 1)
					(thickness 0.15)
				)
			)
		)
		(property "Author" "Antmicro"
			(at 0 0 180)
			(unlocked yes)
			(layer "F.Fab")
			(hide yes)
			(effects
				(font
					(size 1 1)
					(thickness 0.15)
				)
			)
		)
		(property "Val" "100n"
			(at 0 0 180)
			(unlocked yes)
			(layer "F.Fab")
			(hide yes)
			(effects
				(font
					(size 1 1)
					(thickness 0.15)
				)
			)
		)
		(property "Voltage" "50V"
			(at 0 0 180)
			(unlocked yes)
			(layer "F.Fab")
			(hide yes)
			(effects
				(font
					(size 1 1)
					(thickness 0.15)
				)
			)
		)
		(property "Dielectric" "X5R"
			(at 0 0 180)
			(unlocked yes)
			(layer "F.Fab")
			(hide yes)
			(effects
				(font
					(size 1 1)
					(thickness 0.15)
				)
			)
		)
		(sheetname "/Peripherals/")
		(sheetfile "peripherals.kicad_sch")
		(attr smd)
		(fp_rect
			(start -0.925 -0.47)
			(end 0.925 0.47)
			(stroke
				(width 0.05)
				(type default)
			)
			(fill no)
			(layer "F.CrtYd")
		)
		(fp_line
			(start 0.504 0.248)
			(end -0.494 0.248)
			(stroke
				(width 0.15)
				(type solid)
			)
			(layer "F.Fab")
		)
		(fp_line
			(start 0.504 -0.25)
			(end 0.504 0.248)
			(stroke
				(width 0.15)
				(type solid)
			)
			(layer "F.Fab")
		)
		(fp_line
			(start -0.494 0.248)
			(end -0.494 -0.25)
			(stroke
				(width 0.15)
				(type solid)
			)
			(layer "F.Fab")
		)
		(fp_line
			(start -0.494 -0.25)
			(end 0.504 -0.25)
			(stroke
				(width 0.15)
				(type solid)
			)
			(layer "F.Fab")
		)
		(fp_text user "License: Apache-2.0"
			(at -0.939 5.799 180)
			(layer "F.Fab")
			(effects
				(font
					(size 0.7 0.7)
					(thickness 0.15)
				)
				(justify left bottom)
			)
		)
		(fp_text user "Author: Antmicro"
			(at -0.939 3.399 180)
			(layer "F.Fab")
			(effects
				(font
					(size 0.7 0.7)
					(thickness 0.15)
				)
				(justify left bottom)
			)
		)
		(fp_text user "${REFERENCE}"
			(at -0.939 4.599 180)
			(layer "F.Fab")
			(effects
				(font
					(size 0.7 0.7)
					(thickness 0.15)
				)
				(justify left bottom)
			)
		)
		(pad "1" smd roundrect
			(at -0.48 0 180)
			(size 0.59 0.64)
			(layers "F.Cu" "F.Mask" "F.Paste")
			(roundrect_rratio 0.25)
			(net 95 "Net-(U801-V_{DD(VMID)})")
			(pintype "passive")
		)
		(pad "2" smd roundrect
			(at 0.48 0 180)
			(size 0.59 0.64)
			(layers "F.Cu" "F.Mask" "F.Paste")
			(roundrect_rratio 0.25)
			(net 3 "GND")
			(pintype "passive")
		)
	)
	(footprint "antmicro-footprints:R_0402_1005Metric"
		(layer "F.Cu")
		(at 89.042962 157.4415 90)
		(descr "Resistor SMD 0402")
		(tags "resistor SMD 0402")
		(property "Reference" "R238"
			(at -3.685 0.435 90)
			(layer "F.SilkS")
			(effects
				(font
					(size 0.7 0.7)
					(thickness 0.15)
				)
				(justify left bottom)
			)
		)
		(property "Value" "R_10k_0402"
			(at -1.011843 1.772047 90)
			(layer "F.Fab")
			(effects
				(font
					(size 0.7 0.7)
					(thickness 0.15)
				)
				(justify left bottom)
			)
		)
		(property "Datasheet" "https://www.bourns.com/docs/product-datasheets/cr.pdf"
			(at 0 0 90)
			(layer "F.Fab")
			(hide yes)
			(effects
				(font
					(size 1.27 1.27)
					(thickness 0.15)
				)
			)
		)
		(property "Manufacturer" "Bourns"
			(at 0 0 90)
			(unlocked yes)
			(layer "F.Fab")
			(hide yes)
			(effects
				(font
					(size 1 1)
					(thickness 0.15)
				)
			)
		)
		(property "MPN" "CR0402-FX-1002GLF"
			(at 0 0 90)
			(unlocked yes)
			(layer "F.Fab")
			(hide yes)
			(effects
				(font
					(size 1 1)
					(thickness 0.15)
				)
			)
		)
		(property "Val" "10k"
			(at 0 0 90)
			(unlocked yes)
			(layer "F.Fab")
			(hide yes)
			(effects
				(font
					(size 1 1)
					(thickness 0.15)
				)
			)
		)
		(property "License" "Apache-2.0"
			(at 0 0 90)
			(unlocked yes)
			(layer "F.Fab")
			(hide yes)
			(effects
				(font
					(size 1 1)
					(thickness 0.15)
				)
			)
		)
		(property "Author" "Antmicro"
			(at 0 0 90)
			(unlocked yes)
			(layer "F.Fab")
			(hide yes)
			(effects
				(font
					(size 1 1)
					(thickness 0.15)
				)
			)
		)
		(property "Tolerance" "1%"
			(at 0 0 90)
			(unlocked yes)
			(layer "F.Fab")
			(hide yes)
			(effects
				(font
					(size 1 1)
					(thickness 0.15)
				)
			)
		)
		(sheetname "/Compute module/")
		(sheetfile "compute-module.kicad_sch")
		(attr smd)
		(fp_rect
			(start -0.925 -0.47)
			(end 0.925 0.47)
			(stroke
				(width 0.05)
				(type default)
			)
			(fill no)
			(layer "F.CrtYd")
		)
		(fp_rect
			(start -0.5 -0.25)
			(end 0.5 0.25)
			(stroke
				(width 0.15)
				(type solid)
			)
			(fill no)
			(layer "F.Fab")
		)
		(fp_text user "Author: Antmicro"
			(at -0.95 4.169 90)
			(layer "F.Fab")
			(effects
				(font
					(size 0.7 0.7)
					(thickness 0.15)
				)
				(justify left bottom)
			)
		)
		(fp_text user "${REFERENCE}"
			(at -0.95 3.168 90)
			(layer "F.Fab")
			(effects
				(font
					(size 0.7 0.7)
					(thickness 0.15)
				)
				(justify left bottom)
			)
		)
		(fp_text user "License: Apache-2.0"
			(at -0.95 5.169 90)
			(layer "F.Fab")
			(effects
				(font
					(size 0.7 0.7)
					(thickness 0.15)
				)
				(justify left bottom)
			)
		)
		(pad "1" smd roundrect
			(at -0.48 0 90)
			(size 0.59 0.64)
			(layers "F.Cu" "F.Mask" "F.Paste")
			(roundrect_rratio 0.25)
			(net 18 "V_{IO}")
			(pintype "passive")
		)
		(pad "2" smd roundrect
			(at 0.48 0 90)
			(size 0.59 0.64)
			(layers "F.Cu" "F.Mask" "F.Paste")
			(roundrect_rratio 0.25)
			(net 235 "/Compute module/GPIO.23")
			(pintype "passive")
		)
	)
	(footprint "antmicro-footprints:C_0402_1005Metric"
		(layer "F.Cu")
		(at 65.092962 175.7005 -90)
		(descr "Capacitor SMD 0402")
		(tags "capacitor SMD 0402")
		(property "Reference" "C819"
			(at -3.504 13.925 90)
			(layer "F.SilkS")
			(effects
				(font
					(size 0.7 0.7)
					(thickness 0.15)
				)
				(justify right bottom)
			)
		)
		(property "Value" "C_470p_100V_0402"
			(at -1.022927 2.155213 90)
			(layer "F.Fab")
			(effects
				(font
					(size 0.7 0.7)
					(thickness 0.15)
				)
				(justify right bottom)
			)
		)
		(property "Datasheet" "https://search.murata.co.jp/Ceramy/image/img/A01X/G101/ENG/GRM1555C2A471JE01-01A.pdf"
			(at 0 0 270)
			(layer "F.Fab")
			(hide yes)
			(effects
				(font
					(size 1.27 1.27)
					(thickness 0.15)
				)
			)
		)
		(property "Description" "MLCC, SMD/SMT, 100V, 470pF, C0G/NP0, 0402 5%"
			(at 0 0 270)
			(layer "F.Fab")
			(hide yes)
			(effects
				(font
					(size 1.27 1.27)
					(thickness 0.15)
				)
			)
		)
		(property "MPN" "GRM1555C2A471JE01D"
			(at 0 0 270)
			(unlocked yes)
			(layer "F.Fab")
			(hide yes)
			(effects
				(font
					(size 1 1)
					(thickness 0.15)
				)
			)
		)
		(property "Manufacturer" "Murata"
			(at 0 0 270)
			(unlocked yes)
			(layer "F.Fab")
			(hide yes)
			(effects
				(font
					(size 1 1)
					(thickness 0.15)
				)
			)
		)
		(property "License" "Apache-2.0"
			(at 0 0 270)
			(unlocked yes)
			(layer "F.Fab")
			(hide yes)
			(effects
				(font
					(size 1 1)
					(thickness 0.15)
				)
			)
		)
		(property "Author" "Antmicro"
			(at 0 0 270)
			(unlocked yes)
			(layer "F.Fab")
			(hide yes)
			(effects
				(font
					(size 1 1)
					(thickness 0.15)
				)
			)
		)
		(property "Val" "470p"
			(at 0 0 270)
			(unlocked yes)
			(layer "F.Fab")
			(hide yes)
			(effects
				(font
					(size 1 1)
					(thickness 0.15)
				)
			)
		)
		(property "Voltage" "100V"
			(at 0 0 270)
			(unlocked yes)
			(layer "F.Fab")
			(hide yes)
			(effects
				(font
					(size 1 1)
					(thickness 0.15)
				)
			)
		)
		(property "Dielectric" "C0G/NP0"
			(at 0 0 270)
			(unlocked yes)
			(layer "F.Fab")
			(hide yes)
			(effects
				(font
					(size 1 1)
					(thickness 0.15)
				)
			)
		)
		(sheetname "/Peripherals/")
		(sheetfile "peripherals.kicad_sch")
		(attr smd)
		(fp_rect
			(start -0.925 -0.47)
			(end 0.925 0.47)
			(stroke
				(width 0.05)
				(type default)
			)
			(fill no)
			(layer "F.CrtYd")
		)
		(fp_line
			(start -0.494 0.248)
			(end -0.494 -0.25)
			(stroke
				(width 0.15)
				(type solid)
			)
			(layer "F.Fab")
		)
		(fp_line
			(start 0.504 0.248)
			(end -0.494 0.248)
			(stroke
				(width 0.15)
				(type solid)
			)
			(layer "F.Fab")
		)
		(fp_line
			(start -0.494 -0.25)
			(end 0.504 -0.25)
			(stroke
				(width 0.15)
				(type solid)
			)
			(layer "F.Fab")
		)
		(fp_line
			(start 0.504 -0.25)
			(end 0.504 0.248)
			(stroke
				(width 0.15)
				(type solid)
			)
			(layer "F.Fab")
		)
		(fp_text user "Author: Antmicro"
			(at -0.939 3.399 270)
			(layer "F.Fab")
			(effects
				(font
					(size 0.7 0.7)
					(thickness 0.15)
				)
				(justify left bottom)
			)
		)
		(fp_text user "${REFERENCE}"
			(at -0.939 4.599 270)
			(layer "F.Fab")
			(effects
				(font
					(size 0.7 0.7)
					(thickness 0.15)
				)
				(justify left bottom)
			)
		)
		(fp_text user "License: Apache-2.0"
			(at -0.939 5.799 270)
			(layer "F.Fab")
			(effects
				(font
					(size 0.7 0.7)
					(thickness 0.15)
				)
				(justify left bottom)
			)
		)
		(pad "1" smd roundrect
			(at -0.48 0 270)
			(size 0.59 0.64)
			(layers "F.Cu" "F.Mask" "F.Paste")
			(roundrect_rratio 0.25)
			(net 110 "Net-(C817-Pad1)")
			(pintype "passive")
		)
		(pad "2" smd roundrect
			(at 0.48 0 270)
			(size 0.59 0.64)
			(layers "F.Cu" "F.Mask" "F.Paste")
			(roundrect_rratio 0.25)
			(net 3 "GND")
			(pintype "passive")
		)
	)
	(footprint "antmicro-footprints:C_0402_1005Metric"
		(layer "F.Cu")
		(at 97.717962 142.7165 180)
		(descr "Capacitor SMD 0402")
		(tags "capacitor SMD 0402")
		(property "Reference" "C935"
			(at -4.15 0.45 0)
			(layer "F.SilkS")
			(effects
				(font
					(size 0.7 0.7)
					(thickness 0.15)
				)
				(justify right bottom)
			)
		)
		(property "Value" "C_100n_0402"
			(at -1.022927 2.155213 0)
			(layer "F.Fab")
			(effects
				(font
					(size 0.7 0.7)
					(thickness 0.15)
				)
				(justify right bottom)
			)
		)
		(property "Datasheet" "https://www.murata.com/products/productdetail?partno=GRM155R61H104KE14%23"
			(at 0 0 180)
			(layer "F.Fab")
			(hide yes)
			(effects
				(font
					(size 1.27 1.27)
					(thickness 0.15)
				)
			)
		)
		(property "MPN" "GRM155R61H104KE14D"
			(at 0 0 180)
			(unlocked yes)
			(layer "F.Fab")
			(hide yes)
			(effects
				(font
					(size 1 1)
					(thickness 0.15)
				)
			)
		)
		(property "Manufacturer" "Murata"
			(at 0 0 180)
			(unlocked yes)
			(layer "F.Fab")
			(hide yes)
			(effects
				(font
					(size 1 1)
					(thickness 0.15)
				)
			)
		)
		(property "License" "Apache-2.0"
			(at 0 0 180)
			(unlocked yes)
			(layer "F.Fab")
			(hide yes)
			(effects
				(font
					(size 1 1)
					(thickness 0.15)
				)
			)
		)
		(property "Author" "Antmicro"
			(at 0 0 180)
			(unlocked yes)
			(layer "F.Fab")
			(hide yes)
			(effects
				(font
					(size 1 1)
					(thickness 0.15)
				)
			)
		)
		(property "Val" "100n"
			(at 0 0 180)
			(unlocked yes)
			(layer "F.Fab")
			(hide yes)
			(effects
				(font
					(size 1 1)
					(thickness 0.15)
				)
			)
		)
		(property "Voltage" "50V"
			(at 0 0 180)
			(unlocked yes)
			(layer "F.Fab")
			(hide yes)
			(effects
				(font
					(size 1 1)
					(thickness 0.15)
				)
			)
		)
		(property "Dielectric" "X5R"
			(at 0 0 180)
			(unlocked yes)
			(layer "F.Fab")
			(hide yes)
			(effects
				(font
					(size 1 1)
					(thickness 0.15)
				)
			)
		)
		(sheetname "/USB/")
		(sheetfile "usb.kicad_sch")
		(attr smd)
		(fp_rect
			(start -0.925 -0.47)
			(end 0.925 0.47)
			(stroke
				(width 0.05)
				(type default)
			)
			(fill no)
			(layer "F.CrtYd")
		)
		(fp_line
			(start 0.504 0.248)
			(end -0.494 0.248)
			(stroke
				(width 0.15)
				(type solid)
			)
			(layer "F.Fab")
		)
		(fp_line
			(start 0.504 -0.25)
			(end 0.504 0.248)
			(stroke
				(width 0.15)
				(type solid)
			)
			(layer "F.Fab")
		)
		(fp_line
			(start -0.494 0.248)
			(end -0.494 -0.25)
			(stroke
				(width 0.15)
				(type solid)
			)
			(layer "F.Fab")
		)
		(fp_line
			(start -0.494 -0.25)
			(end 0.504 -0.25)
			(stroke
				(width 0.15)
				(type solid)
			)
			(layer "F.Fab")
		)
		(fp_text user "${REFERENCE}"
			(at -0.939 4.599 180)
			(layer "F.Fab")
			(effects
				(font
					(size 0.7 0.7)
					(thickness 0.15)
				)
				(justify left bottom)
			)
		)
		(fp_text user "Author: Antmicro"
			(at -0.939 3.399 180)
			(layer "F.Fab")
			(effects
				(font
					(size 0.7 0.7)
					(thickness 0.15)
				)
				(justify left bottom)
			)
		)
		(fp_text user "License: Apache-2.0"
			(at -0.939 5.799 180)
			(layer "F.Fab")
			(effects
				(font
					(size 0.7 0.7)
					(thickness 0.15)
				)
				(justify left bottom)
			)
		)
		(pad "1" smd roundrect
			(at -0.48 0 180)
			(size 0.59 0.64)
			(layers "F.Cu" "F.Mask" "F.Paste")
			(roundrect_rratio 0.25)
			(net 3 "GND")
			(pintype "passive")
		)
		(pad "2" smd roundrect
			(at 0.48 0 180)
			(size 0.59 0.64)
			(layers "F.Cu" "F.Mask" "F.Paste")
			(roundrect_rratio 0.25)
			(net 9 "+3V3")
			(pintype "passive")
		)
	)
	(footprint "antmicro-footprints:R_0402_1005Metric"
		(layer "F.Cu")
		(at 140.852962 126.4565 180)
		(descr "Resistor SMD 0402")
		(tags "resistor SMD 0402")
		(property "Reference" "R214"
			(at 0.802962 -0.5185 0)
			(layer "F.SilkS")
			(effects
				(font
					(size 0.7 0.7)
					(thickness 0.15)
				)
				(justify right bottom)
			)
		)
		(property "Value" "R_100k_0402"
			(at -1.011843 1.772047 0)
			(layer "F.Fab")
			(effects
				(font
					(size 0.7 0.7)
					(thickness 0.15)
				)
				(justify right bottom)
			)
		)
		(property "Datasheet" "https://www.bourns.com/docs/product-datasheets/cr.pdf"
			(at 0 0 180)
			(layer "F.Fab")
			(hide yes)
			(effects
				(font
					(size 1.27 1.27)
					(thickness 0.15)
				)
			)
		)
		(property "Manufacturer" "Bourns"
			(at 0 0 180)
			(unlocked yes)
			(layer "F.Fab")
			(hide yes)
			(effects
				(font
					(size 1 1)
					(thickness 0.15)
				)
			)
		)
		(property "MPN" "CR0402-FX-1003GLF"
			(at 0 0 180)
			(unlocked yes)
			(layer "F.Fab")
			(hide yes)
			(effects
				(font
					(size 1 1)
					(thickness 0.15)
				)
			)
		)
		(property "Val" "100k"
			(at 0 0 180)
			(unlocked yes)
			(layer "F.Fab")
			(hide yes)
			(effects
				(font
					(size 1 1)
					(thickness 0.15)
				)
			)
		)
		(property "License" "Apache-2.0"
			(at 0 0 180)
			(unlocked yes)
			(layer "F.Fab")
			(hide yes)
			(effects
				(font
					(size 1 1)
					(thickness 0.15)
				)
			)
		)
		(property "Author" "Antmicro"
			(at 0 0 180)
			(unlocked yes)
			(layer "F.Fab")
			(hide yes)
			(effects
				(font
					(size 1 1)
					(thickness 0.15)
				)
			)
		)
		(property "Tolerance" "1%"
			(at 0 0 180)
			(unlocked yes)
			(layer "F.Fab")
			(hide yes)
			(effects
				(font
					(size 1 1)
					(thickness 0.15)
				)
			)
		)
		(sheetname "/Compute module/")
		(sheetfile "compute-module.kicad_sch")
		(attr smd)
		(fp_rect
			(start -0.925 -0.47)
			(end 0.925 0.47)
			(stroke
				(width 0.05)
				(type default)
			)
			(fill no)
			(layer "F.CrtYd")
		)
		(fp_rect
			(start -0.5 -0.25)
			(end 0.5 0.25)
			(stroke
				(width 0.15)
				(type solid)
			)
			(fill no)
			(layer "F.Fab")
		)
		(fp_text user "${REFERENCE}"
			(at -0.95 3.168 180)
			(layer "F.Fab")
			(effects
				(font
					(size 0.7 0.7)
					(thickness 0.15)
				)
				(justify left bottom)
			)
		)
		(fp_text user "License: Apache-2.0"
			(at -0.95 5.169 180)
			(layer "F.Fab")
			(effects
				(font
					(size 0.7 0.7)
					(thickness 0.15)
				)
				(justify left bottom)
			)
		)
		(fp_text user "Author: Antmicro"
			(at -0.95 4.169 180)
			(layer "F.Fab")
			(effects
				(font
					(size 0.7 0.7)
					(thickness 0.15)
				)
				(justify left bottom)
			)
		)
		(pad "1" smd roundrect
			(at -0.48 0 180)
			(size 0.59 0.64)
			(layers "F.Cu" "F.Mask" "F.Paste")
			(roundrect_rratio 0.25)
			(net 329 "Net-(Q207-G)")
			(pintype "passive")
		)
		(pad "2" smd roundrect
			(at 0.48 0 180)
			(size 0.59 0.64)
			(layers "F.Cu" "F.Mask" "F.Paste")
			(roundrect_rratio 0.25)
			(net 3 "GND")
			(pintype "passive")
		)
	)
	(footprint "antmicro-footprints:C_0402_1005Metric"
		(layer "F.Cu")
		(at 101.192962 131.9915)
		(descr "Capacitor SMD 0402")
		(tags "capacitor SMD 0402")
		(property "Reference" "C931"
			(at 0.935 0.425 180)
			(layer "F.SilkS")
			(effects
				(font
					(size 0.7 0.7)
					(thickness 0.15)
				)
				(justify left bottom)
			)
		)
		(property "Value" "C_1u_25V_0402"
			(at -1.022927 2.155213 0)
			(layer "F.Fab")
			(effects
				(font
					(size 0.7 0.7)
					(thickness 0.15)
				)
				(justify left bottom)
			)
		)
		(property "Datasheet" "https://www.murata.com/products/productdetail?partno=GRM155R61E105KE11%23"
			(at 0 0 0)
			(layer "F.Fab")
			(hide yes)
			(effects
				(font
					(size 1.27 1.27)
					(thickness 0.15)
				)
			)
		)
		(property "MPN" "GRM155R61E105KE11J"
			(at 0 0 0)
			(unlocked yes)
			(layer "F.Fab")
			(hide yes)
			(effects
				(font
					(size 1 1)
					(thickness 0.15)
				)
			)
		)
		(property "Manufacturer" "Murata"
			(at 0 0 0)
			(unlocked yes)
			(layer "F.Fab")
			(hide yes)
			(effects
				(font
					(size 1 1)
					(thickness 0.15)
				)
			)
		)
		(property "License" "Apache-2.0"
			(at 0 0 0)
			(unlocked yes)
			(layer "F.Fab")
			(hide yes)
			(effects
				(font
					(size 1 1)
					(thickness 0.15)
				)
			)
		)
		(property "Author" "Antmicro"
			(at 0 0 0)
			(unlocked yes)
			(layer "F.Fab")
			(hide yes)
			(effects
				(font
					(size 1 1)
					(thickness 0.15)
				)
			)
		)
		(property "Val" "1u"
			(at 0 0 0)
			(unlocked yes)
			(layer "F.Fab")
			(hide yes)
			(effects
				(font
					(size 1 1)
					(thickness 0.15)
				)
			)
		)
		(property "Voltage" "25V"
			(at 0 0 0)
			(unlocked yes)
			(layer "F.Fab")
			(hide yes)
			(effects
				(font
					(size 1 1)
					(thickness 0.15)
				)
			)
		)
		(property "Dielectric" "X5R"
			(at 0 0 0)
			(unlocked yes)
			(layer "F.Fab")
			(hide yes)
			(effects
				(font
					(size 1 1)
					(thickness 0.15)
				)
			)
		)
		(sheetname "/USB/")
		(sheetfile "usb.kicad_sch")
		(attr smd)
		(fp_rect
			(start -0.925 -0.47)
			(end 0.925 0.47)
			(stroke
				(width 0.05)
				(type default)
			)
			(fill no)
			(layer "F.CrtYd")
		)
		(fp_line
			(start -0.494 -0.25)
			(end 0.504 -0.25)
			(stroke
				(width 0.15)
				(type solid)
			)
			(layer "F.Fab")
		)
		(fp_line
			(start -0.494 0.248)
			(end -0.494 -0.25)
			(stroke
				(width 0.15)
				(type solid)
			)
			(layer "F.Fab")
		)
		(fp_line
			(start 0.504 -0.25)
			(end 0.504 0.248)
			(stroke
				(width 0.15)
				(type solid)
			)
			(layer "F.Fab")
		)
		(fp_line
			(start 0.504 0.248)
			(end -0.494 0.248)
			(stroke
				(width 0.15)
				(type solid)
			)
			(layer "F.Fab")
		)
		(fp_text user "License: Apache-2.0"
			(at -0.939 5.799 0)
			(layer "F.Fab")
			(effects
				(font
					(size 0.7 0.7)
					(thickness 0.15)
				)
				(justify left bottom)
			)
		)
		(fp_text user "Author: Antmicro"
			(at -0.939 3.399 0)
			(layer "F.Fab")
			(effects
				(font
					(size 0.7 0.7)
					(thickness 0.15)
				)
				(justify left bottom)
			)
		)
		(fp_text user "${REFERENCE}"
			(at -0.939 4.599 0)
			(layer "F.Fab")
			(effects
				(font
					(size 0.7 0.7)
					(thickness 0.15)
				)
				(justify left bottom)
			)
		)
		(pad "1" smd roundrect
			(at -0.48 0)
			(size 0.59 0.64)
			(layers "F.Cu" "F.Mask" "F.Paste")
			(roundrect_rratio 0.25)
			(net 127 "Net-(Q903-G)")
			(pintype "passive")
		)
		(pad "2" smd roundrect
			(at 0.48 0)
			(size 0.59 0.64)
			(layers "F.Cu" "F.Mask" "F.Paste")
			(roundrect_rratio 0.25)
			(net 10 "+5V")
			(pintype "passive")
		)
	)
	(footprint "antmicro-footprints:QFN-76-1EP_9x9mm_P0.4mm_EP6.3x6.3mm"
		(layer "F.Cu")
		(at 89.667962 138.307236)
		(property "Reference" "U905"
			(at -7.73 4.379264 0)
			(layer "F.SilkS")
			(effects
				(font
					(size 0.7 0.7)
					(thickness 0.15)
				)
				(justify left bottom)
			)
		)
		(property "Value" "FT4233HPQ"
			(at 0.1 6.2 0)
			(layer "F.Fab")
			(effects
				(font
					(size 0.7 0.7)
					(thickness 0.15)
				)
				(justify left bottom)
			)
		)
		(property "Datasheet" "https://ftdichip.com/wp-content/uploads/2023/09/DS_FT4233HP-v1.5.pdf"
			(at 0 0 0)
			(layer "F.Fab")
			(hide yes)
			(effects
				(font
					(size 1.27 1.27)
					(thickness 0.15)
				)
			)
		)
		(property "MPN" "FT4233HPQ-REEL"
			(at 0 0 0)
			(unlocked yes)
			(layer "F.Fab")
			(hide yes)
			(effects
				(font
					(size 1 1)
					(thickness 0.15)
				)
			)
		)
		(property "Manufacturer" "FTDI Chip"
			(at 0 0 0)
			(unlocked yes)
			(layer "F.Fab")
			(hide yes)
			(effects
				(font
					(size 1 1)
					(thickness 0.15)
				)
			)
		)
		(property "License" "Apache-2.0"
			(at 0 0 0)
			(unlocked yes)
			(layer "F.Fab")
			(hide yes)
			(effects
				(font
					(size 1 1)
					(thickness 0.15)
				)
			)
		)
		(property "Author" "Antmicro"
			(at 0 0 0)
			(unlocked yes)
			(layer "F.Fab")
			(hide yes)
			(effects
				(font
					(size 1 1)
					(thickness 0.15)
				)
			)
		)
		(sheetname "/USB/")
		(sheetfile "usb.kicad_sch")
		(attr smd)
		(fp_line
			(start -4.55 -4.55)
			(end -4.55 -3.85)
			(stroke
				(width 0.15)
				(type solid)
			)
			(layer "F.SilkS")
		)
		(fp_line
			(start -4.55 -4.55)
			(end -3.85 -4.55)
			(stroke
				(width 0.15)
				(type solid)
			)
			(layer "F.SilkS")
		)
		(fp_line
			(start -4.55 4.55)
			(end -4.55 3.85)
			(stroke
				(width 0.15)
				(type solid)
			)
			(layer "F.SilkS")
		)
		(fp_line
			(start -4.55 4.55)
			(end -3.85 4.55)
			(stroke
				(width 0.15)
				(type solid)
			)
			(layer "F.SilkS")
		)
		(fp_line
			(start 4.55 -4.55)
			(end 3.85 -4.55)
			(stroke
				(width 0.15)
				(type solid)
			)
			(layer "F.SilkS")
		)
		(fp_line
			(start 4.55 -4.55)
			(end 4.55 -3.85)
			(stroke
				(width 0.15)
				(type solid)
			)
			(layer "F.SilkS")
		)
		(fp_line
			(start 4.55 4.55)
			(end 3.85 4.55)
			(stroke
				(width 0.15)
				(type solid)
			)
			(layer "F.SilkS")
		)
		(fp_line
			(start 4.55 4.55)
			(end 4.55 3.85)
			(stroke
				(width 0.15)
				(type solid)
			)
			(layer "F.SilkS")
		)
		(fp_circle
			(center -5.25 -3.6)
			(end -5.2 -3.6)
			(stroke
				(width 0.15)
				(type solid)
			)
			(fill yes)
			(layer "F.SilkS")
		)
		(fp_poly
			(pts
				(xy -2.9 -2.9) (xy -1.9 -2.9) (xy -1.9 -1.9) (xy -2.9 -1.9)
			)
			(stroke
				(width 0.01)
				(type solid)
			)
			(fill yes)
			(layer "F.Paste")
		)
		(fp_poly
			(pts
				(xy -2.9 -1.7) (xy -1.9 -1.7) (xy -1.9 -0.7) (xy -2.9 -0.7)
			)
			(stroke
				(width 0.01)
				(type solid)
			)
			(fill yes)
			(layer "F.Paste")
		)
		(fp_poly
			(pts
				(xy -2.9 -0.5) (xy -1.9 -0.5) (xy -1.9 0.5) (xy -2.9 0.5)
			)
			(stroke
				(width 0.01)
				(type solid)
			)
			(fill yes)
			(layer "F.Paste")
		)
		(fp_poly
			(pts
				(xy -2.9 0.7) (xy -1.9 0.7) (xy -1.9 1.7) (xy -2.9 1.7)
			)
			(stroke
				(width 0.01)
				(type solid)
			)
			(fill yes)
			(layer "F.Paste")
		)
		(fp_poly
			(pts
				(xy -2.9 1.9) (xy -1.9 1.9) (xy -1.9 2.9) (xy -2.9 2.9)
			)
			(stroke
				(width 0.01)
				(type solid)
			)
			(fill yes)
			(layer "F.Paste")
		)
		(fp_poly
			(pts
				(xy -1.7 -2.9) (xy -0.7 -2.9) (xy -0.7 -1.9) (xy -1.7 -1.9)
			)
			(stroke
				(width 0.01)
				(type solid)
			)
			(fill yes)
			(layer "F.Paste")
		)
		(fp_poly
			(pts
				(xy -1.7 -1.7) (xy -0.7 -1.7) (xy -0.7 -0.7) (xy -1.7 -0.7)
			)
			(stroke
				(width 0.01)
				(type solid)
			)
			(fill yes)
			(layer "F.Paste")
		)
		(fp_poly
			(pts
				(xy -1.7 -0.5) (xy -0.7 -0.5) (xy -0.7 0.5) (xy -1.7 0.5)
			)
			(stroke
				(width 0.01)
				(type solid)
			)
			(fill yes)
			(layer "F.Paste")
		)
		(fp_poly
			(pts
				(xy -1.7 0.7) (xy -0.7 0.7) (xy -0.7 1.7) (xy -1.7 1.7)
			)
			(stroke
				(width 0.01)
				(type solid)
			)
			(fill yes)
			(layer "F.Paste")
		)
		(fp_poly
			(pts
				(xy -1.7 1.9) (xy -0.7 1.9) (xy -0.7 2.9) (xy -1.7 2.9)
			)
			(stroke
				(width 0.01)
				(type solid)
			)
			(fill yes)
			(layer "F.Paste")
		)
		(fp_poly
			(pts
				(xy -0.5 -2.9) (xy 0.5 -2.9) (xy 0.5 -1.9) (xy -0.5 -1.9)
			)
			(stroke
				(width 0.01)
				(type solid)
			)
			(fill yes)
			(layer "F.Paste")
		)
		(fp_poly
			(pts
				(xy -0.5 -1.7) (xy 0.5 -1.7) (xy 0.5 -0.7) (xy -0.5 -0.7)
			)
			(stroke
				(width 0.01)
				(type solid)
			)
			(fill yes)
			(layer "F.Paste")
		)
		(fp_poly
			(pts
				(xy -0.5 -0.5) (xy 0.5 -0.5) (xy 0.5 0.5) (xy -0.5 0.5)
			)
			(stroke
				(width 0.01)
				(type solid)
			)
			(fill yes)
			(layer "F.Paste")
		)
		(fp_poly
			(pts
				(xy -0.5 0.7) (xy 0.5 0.7) (xy 0.5 1.7) (xy -0.5 1.7)
			)
			(stroke
				(width 0.01)
				(type solid)
			)
			(fill yes)
			(layer "F.Paste")
		)
		(fp_poly
			(pts
				(xy -0.5 1.9) (xy 0.5 1.9) (xy 0.5 2.9) (xy -0.5 2.9)
			)
			(stroke
				(width 0.01)
				(type solid)
			)
			(fill yes)
			(layer "F.Paste")
		)
		(fp_poly
			(pts
				(xy 0.7 -2.9) (xy 1.7 -2.9) (xy 1.7 -1.9) (xy 0.7 -1.9)
			)
			(stroke
				(width 0.01)
				(type solid)
			)
			(fill yes)
			(layer "F.Paste")
		)
		(fp_poly
			(pts
				(xy 0.7 -1.7) (xy 1.7 -1.7) (xy 1.7 -0.7) (xy 0.7 -0.7)
			)
			(stroke
				(width 0.01)
				(type solid)
			)
			(fill yes)
			(layer "F.Paste")
		)
		(fp_poly
			(pts
				(xy 0.7 -0.5) (xy 1.7 -0.5) (xy 1.7 0.5) (xy 0.7 0.5)
			)
			(stroke
				(width 0.01)
				(type solid)
			)
			(fill yes)
			(layer "F.Paste")
		)
		(fp_poly
			(pts
				(xy 0.7 0.7) (xy 1.7 0.7) (xy 1.7 1.7) (xy 0.7 1.7)
			)
			(stroke
				(width 0.01)
				(type solid)
			)
			(fill yes)
			(layer "F.Paste")
		)
		(fp_poly
			(pts
				(xy 0.7 1.9) (xy 1.7 1.9) (xy 1.7 2.9) (xy 0.7 2.9)
			)
			(stroke
				(width 0.01)
				(type solid)
			)
			(fill yes)
			(layer "F.Paste")
		)
		(fp_poly
			(pts
				(xy 1.9 -2.9) (xy 2.9 -2.9) (xy 2.9 -1.9) (xy 1.9 -1.9)
			)
			(stroke
				(width 0.01)
				(type solid)
			)
			(fill yes)
			(layer "F.Paste")
		)
		(fp_poly
			(pts
				(xy 1.9 -1.7) (xy 2.9 -1.7) (xy 2.9 -0.7) (xy 1.9 -0.7)
			)
			(stroke
				(width 0.01)
				(type solid)
			)
			(fill yes)
			(layer "F.Paste")
		)
		(fp_poly
			(pts
				(xy 1.9 -0.5) (xy 2.9 -0.5) (xy 2.9 0.5) (xy 1.9 0.5)
			)
			(stroke
				(width 0.01)
				(type solid)
			)
			(fill yes)
			(layer "F.Paste")
		)
		(fp_poly
			(pts
				(xy 1.9 0.7) (xy 2.9 0.7) (xy 2.9 1.7) (xy 1.9 1.7)
			)
			(stroke
				(width 0.01)
				(type solid)
			)
			(fill yes)
			(layer "F.Paste")
		)
		(fp_poly
			(pts
				(xy 1.9 1.9) (xy 2.9 1.9) (xy 2.9 2.9) (xy 1.9 2.9)
			)
			(stroke
				(width 0.01)
				(type solid)
			)
			(fill yes)
			(layer "F.Paste")
		)
		(fp_rect
			(start -4.95 -4.75)
			(end 4.95 4.75)
			(stroke
				(width 0.05)
				(type solid)
			)
			(fill no)
			(layer "F.CrtYd")
		)
		(fp_line
			(start -4.5 -2.5)
			(end -2.5 -4.5)
			(stroke
				(width 0.15)
				(type solid)
			)
			(layer "F.Fab")
		)
		(fp_rect
			(start -4.5 -4.5)
			(end 4.5 4.5)
			(stroke
				(width 0.15)
				(type solid)
			)
			(fill no)
			(layer "F.Fab")
		)
		(fp_text user "Author: Antmicro"
			(at -5.3 9.4 0)
			(layer "F.Fab")
			(effects
				(font
					(size 0.7 0.7)
					(thickness 0.15)
				)
				(justify left bottom)
			)
		)
		(fp_text user "${REFERENCE}"
			(at -5.3 8.2 0)
			(layer "F.Fab")
			(effects
				(font
					(size 0.7 0.7)
					(thickness 0.15)
				)
				(justify left bottom)
			)
		)
		(fp_text user "License: Apache-2.0"
			(at -5.3 10.6 0)
			(layer "F.Fab")
			(effects
				(font
					(size 0.7 0.7)
					(thickness 0.15)
				)
				(justify left bottom)
			)
		)
		(pad "1" smd rect
			(at -4.35 -3.6)
			(size 0.7 0.2)
			(layers "F.Cu" "F.Mask" "F.Paste")
			(net 282 "/USB/EECLK")
			(pinfunction "EECLK")
			(pintype "output")
		)
		(pad "2" smd rect
			(at -4.35 -3.2)
			(size 0.7 0.2)
			(layers "F.Cu" "F.Mask" "F.Paste")
			(net 281 "/USB/EEDATA")
			(pinfunction "EEDATA")
			(pintype "bidirectional")
		)
		(pad "3" smd rect
			(at -4.35 -2.8)
			(size 0.7 0.2)
			(layers "F.Cu" "F.Mask" "F.Paste")
			(net 3 "GND")
			(pinfunction "TEST")
			(pintype "input")
		)
		(pad "4" smd rect
			(at -4.35 -2.4)
			(size 0.7 0.2)
			(layers "F.Cu" "F.Mask" "F.Paste")
			(net 379 "Net-(U905-~{RESET})")
			(pinfunction "~{RESET}")
			(pintype "input")
		)
		(pad "5" smd rect
			(at -4.35 -2)
			(size 0.7 0.2)
			(layers "F.Cu" "F.Mask" "F.Paste")
			(net 338 "/USB/USBD_IN_EN")
			(pinfunction "GPIO3")
			(pintype "bidirectional")
		)
		(pad "6" smd rect
			(at -4.35 -1.6)
			(size 0.7 0.2)
			(layers "F.Cu" "F.Mask" "F.Paste")
			(net 441 "Net-(U905-GPIO4)")
			(pinfunction "GPIO4")
			(pintype "bidirectional")
		)
		(pad "7" smd rect
			(at -4.35 -1.2)
			(size 0.7 0.2)
			(layers "F.Cu" "F.Mask" "F.Paste")
			(net 442 "Net-(U905-GPIO5)")
			(pinfunction "GPIO5")
			(pintype "bidirectional")
		)
		(pad "8" smd rect
			(at -4.35 -0.8)
			(size 0.7 0.2)
			(layers "F.Cu" "F.Mask" "F.Paste")
			(net 36 "/Compute module/UART.0.RX")
			(pinfunction "ADBUS0")
			(pintype "bidirectional")
		)
		(pad "9" smd rect
			(at -4.35 -0.4)
			(size 0.7 0.2)
			(layers "F.Cu" "F.Mask" "F.Paste")
			(net 37 "/Compute module/UART.0.TX")
			(pinfunction "ADBUS1")
			(pintype "bidirectional")
		)
		(pad "10" smd rect
			(at -4.35 0)
			(size 0.7 0.2)
			(layers "F.Cu" "F.Mask" "F.Paste")
			(net 30 "/USB/USB_1V2")
			(pinfunction "VCORE")
			(pintype "power_in")
		)
		(pad "11" smd rect
			(at -4.35 0.4)
			(size 0.7 0.2)
			(layers "F.Cu" "F.Mask" "F.Paste")
			(net 3 "GND")
			(pinfunction "GND")
			(pintype "power_in")
		)
		(pad "12" smd rect
			(at -4.35 0.8)
			(size 0.7 0.2)
			(layers "F.Cu" "F.Mask" "F.Paste")
			(net 27 "/USB/USB_3V3")
			(pinfunction "VCCIO")
			(pintype "power_in")
		)
		(pad "13" smd rect
			(at -4.35 1.2)
			(size 0.7 0.2)
			(layers "F.Cu" "F.Mask" "F.Paste")
			(net 431 "unconnected-(U905-ADBUS2-Pad13)")
			(pinfunction "ADBUS2")
			(pintype "bidirectional+no_connect")
		)
		(pad "14" smd rect
			(at -4.35 1.6)
			(size 0.7 0.2)
			(layers "F.Cu" "F.Mask" "F.Paste")
			(net 430 "unconnected-(U905-ADBUS3-Pad14)")
			(pinfunction "ADBUS3")
			(pintype "bidirectional+no_connect")
		)
		(pad "15" smd rect
			(at -4.35 2)
			(size 0.7 0.2)
			(layers "F.Cu" "F.Mask" "F.Paste")
			(net 429 "unconnected-(U905-ADBUS4-Pad15)")
			(pinfunction "ADBUS4")
			(pintype "bidirectional+no_connect")
		)
		(pad "16" smd rect
			(at -4.35 2.4)
			(size 0.7 0.2)
			(layers "F.Cu" "F.Mask" "F.Paste")
			(net 428 "unconnected-(U905-ADBUS5-Pad16)")
			(pinfunction "ADBUS5")
			(pintype "bidirectional+no_connect")
		)
		(pad "17" smd rect
			(at -4.35 2.8)
			(size 0.7 0.2)
			(layers "F.Cu" "F.Mask" "F.Paste")
			(net 427 "unconnected-(U905-ADBUS6-Pad17)")
			(pinfunction "ADBUS6")
			(pintype "bidirectional+no_connect")
		)
		(pad "18" smd rect
			(at -4.35 3.2)
			(size 0.7 0.2)
			(layers "F.Cu" "F.Mask" "F.Paste")
			(net 426 "unconnected-(U905-ADBUS7-Pad18)")
			(pinfunction "ADBUS7")
			(pintype "bidirectional+no_connect")
		)
		(pad "19" smd rect
			(at -4.35 3.6)
			(size 0.7 0.2)
			(layers "F.Cu" "F.Mask" "F.Paste")
			(net 456 "/USB/BDBUS0")
			(pinfunction "BDBUS0")
			(pintype "bidirectional")
		)
		(pad "20" smd rect
			(at -3.6 4.35 90)
			(size 0.7 0.2)
			(layers "F.Cu" "F.Mask" "F.Paste")
			(net 457 "/USB/BDBUS1")
			(pinfunction "BDBUS1")
			(pintype "bidirectional")
		)
		(pad "21" smd rect
			(at -3.2 4.35 90)
			(size 0.7 0.2)
			(layers "F.Cu" "F.Mask" "F.Paste")
			(net 458 "/USB/BDBUS2")
			(pinfunction "BDBUS2")
			(pintype "bidirectional")
		)
		(pad "22" smd rect
			(at -2.8 4.35 90)
			(size 0.7 0.2)
			(layers "F.Cu" "F.Mask" "F.Paste")
			(net 425 "unconnected-(U905-BDBUS3-Pad22)")
			(pinfunction "BDBUS3")
			(pintype "bidirectional+no_connect")
		)
		(pad "23" smd rect
			(at -2.4 4.35 90)
			(size 0.7 0.2)
			(layers "F.Cu" "F.Mask" "F.Paste")
			(net 424 "unconnected-(U905-BDBUS4-Pad23)")
			(pinfunction "BDBUS4")
			(pintype "bidirectional+no_connect")
		)
		(pad "24" smd rect
			(at -2 4.35 90)
			(size 0.7 0.2)
			(layers "F.Cu" "F.Mask" "F.Paste")
			(net 463 "/USB/I2C_EN")
			(pinfunction "BDBUS5")
			(pintype "bidirectional")
		)
		(pad "25" smd rect
			(at -1.6 4.35 90)
			(size 0.7 0.2)
			(layers "F.Cu" "F.Mask" "F.Paste")
			(net 423 "unconnected-(U905-BDBUS6-Pad25)")
			(pinfunction "BDBUS6")
			(pintype "bidirectional+no_connect")
		)
		(pad "26" smd rect
			(at -1.2 4.35 90)
			(size 0.7 0.2)
			(layers "F.Cu" "F.Mask" "F.Paste")
			(net 422 "unconnected-(U905-BDBUS7-Pad26)")
			(pinfunction "BDBUS7")
			(pintype "bidirectional+no_connect")
		)
		(pad "27" smd rect
			(at -0.8 4.35 90)
			(size 0.7 0.2)
			(layers "F.Cu" "F.Mask" "F.Paste")
			(net 30 "/USB/USB_1V2")
			(pinfunction "VCORE")
			(pintype "passive")
		)
		(pad "28" smd rect
			(at -0.4 4.35 90)
			(size 0.7 0.2)
			(layers "F.Cu" "F.Mask" "F.Paste")
			(net 27 "/USB/USB_3V3")
			(pinfunction "VCCIO")
			(pintype "passive")
		)
		(pad "29" smd rect
			(at 0 4.35 90)
			(size 0.7 0.2)
			(layers "F.Cu" "F.Mask" "F.Paste")
			(net 114 "Net-(U905-OSCI)")
			(pinfunction "OSCI")
			(pintype "input")
		)
		(pad "30" smd rect
			(at 0.4 4.35 90)
			(size 0.7 0.2)
			(layers "F.Cu" "F.Mask" "F.Paste")
			(net 115 "Net-(U905-OSCO)")
			(pinfunction "OSCO")
			(pintype "output")
		)
		(pad "31" smd rect
			(at 0.8 4.35 90)
			(size 0.7 0.2)
			(layers "F.Cu" "F.Mask" "F.Paste")
			(net 3 "GND")
			(pinfunction "GND")
			(pintype "passive")
		)
		(pad "32" smd rect
			(at 1.2 4.35 90)
			(size 0.7 0.2)
			(layers "F.Cu" "F.Mask" "F.Paste")
			(net 31 "/USB/VREGIN")
			(pinfunction "VREGIN")
			(pintype "input")
		)
		(pad "33" smd rect
			(at 1.6 4.35 90)
			(size 0.7 0.2)
			(layers "F.Cu" "F.Mask" "F.Paste")
			(net 30 "/USB/USB_1V2")
			(pinfunction "VREGOUT")
			(pintype "output")
		)
		(pad "34" smd rect
			(at 2 4.35 90)
			(size 0.7 0.2)
			(layers "F.Cu" "F.Mask" "F.Paste")
			(net 421 "unconnected-(U905-FSOURCE-Pad34)")
			(pinfunction "FSOURCE")
			(pintype "input+no_connect")
		)
		(pad "35" smd rect
			(at 2.4 4.35 90)
			(size 0.7 0.2)
			(layers "F.Cu" "F.Mask" "F.Paste")
			(net 420 "unconnected-(U905-VPP-Pad35)")
			(pinfunction "VPP")
			(pintype "input+no_connect")
		)
		(pad "36" smd rect
			(at 2.8 4.35 90)
			(size 0.7 0.2)
			(layers "F.Cu" "F.Mask" "F.Paste")
			(net 189 "/Compute module/UART.2.RX")
			(pinfunction "CDBUS0")
			(pintype "bidirectional")
		)
		(pad "37" smd rect
			(at 3.2 4.35 90)
			(size 0.7 0.2)
			(layers "F.Cu" "F.Mask" "F.Paste")
			(net 188 "/Compute module/UART.2.TX")
			(pinfunction "CDBUS1")
			(pintype "bidirectional")
		)
		(pad "38" smd rect
			(at 3.6 4.35 90)
			(size 0.7 0.2)
			(layers "F.Cu" "F.Mask" "F.Paste")
			(net 419 "unconnected-(U905-CDBUS2-Pad38)")
			(pinfunction "CDBUS2")
			(pintype "bidirectional+no_connect")
		)
		(pad "39" smd rect
			(at 4.35 3.6)
			(size 0.7 0.2)
			(layers "F.Cu" "F.Mask" "F.Paste")
			(net 418 "unconnected-(U905-CDBUS3-Pad39)")
			(pinfunction "CDBUS3")
			(pintype "bidirectional+no_connect")
		)
		(pad "40" smd rect
			(at 4.35 3.2)
			(size 0.7 0.2)
			(layers "F.Cu" "F.Mask" "F.Paste")
			(net 417 "unconnected-(U905-CDBUS4-Pad40)")
			(pinfunction "CDBUS4")
			(pintype "bidirectional+no_connect")
		)
		(pad "41" smd rect
			(at 4.35 2.8)
			(size 0.7 0.2)
			(layers "F.Cu" "F.Mask" "F.Paste")
			(net 27 "/USB/USB_3V3")
			(pinfunction "VCCIO")
			(pintype "passive")
		)
		(pad "42" smd rect
			(at 4.35 2.4)
			(size 0.7 0.2)
			(layers "F.Cu" "F.Mask" "F.Paste")
			(net 416 "unconnected-(U905-CDBUS5-Pad42)")
			(pinfunction "CDBUS5")
			(pintype "bidirectional+no_connect")
		)
		(pad "43" smd rect
			(at 4.35 2)
			(size 0.7 0.2)
			(layers "F.Cu" "F.Mask" "F.Paste")
			(net 415 "unconnected-(U905-CDBUS6-Pad43)")
			(pinfunction "CDBUS6")
			(pintype "bidirectional+no_connect")
		)
		(pad "44" smd rect
			(at 4.35 1.6)
			(size 0.7 0.2)
			(layers "F.Cu" "F.Mask" "F.Paste")
			(net 414 "unconnected-(U905-CDBUS7-Pad44)")
			(pinfunction "CDBUS7")
			(pintype "bidirectional+no_connect")
		)
		(pad "45" smd rect
			(at 4.35 1.2)
			(size 0.7 0.2)
			(layers "F.Cu" "F.Mask" "F.Paste")
			(net 486 "Net-(D911-C)")
			(pinfunction "~{SUSPEND}")
			(pintype "output")
		)
		(pad "46" smd rect
			(at 4.35 0.8)
			(size 0.7 0.2)
			(layers "F.Cu" "F.Mask" "F.Paste")
			(net 384 "Net-(U905-GPIO6)")
			(pinfunction "GPIO6")
			(pintype "bidirectional")
		)
		(pad "47" smd rect
			(at 4.35 0.4)
			(size 0.7 0.2)
			(layers "F.Cu" "F.Mask" "F.Paste")
			(net 30 "/USB/USB_1V2")
			(pinfunction "VCORE")
			(pintype "passive")
		)
		(pad "48" smd rect
			(at 4.35 0)
			(size 0.7 0.2)
			(layers "F.Cu" "F.Mask" "F.Paste")
			(net 191 "/Compute module/UART.3.RX")
			(pinfunction "DDBUS0")
			(pintype "bidirectional")
		)
		(pad "49" smd rect
			(at 4.35 -0.4)
			(size 0.7 0.2)
			(layers "F.Cu" "F.Mask" "F.Paste")
			(net 190 "/Compute module/UART.3.TX")
			(pinfunction "DDBUS1")
			(pintype "bidirectional")
		)
		(pad "50" smd rect
			(at 4.35 -0.8)
			(size 0.7 0.2)
			(layers "F.Cu" "F.Mask" "F.Paste")
			(net 413 "unconnected-(U905-DDBUS2-Pad50)")
			(pinfunction "DDBUS2")
			(pintype "bidirectional+no_connect")
		)
		(pad "51" smd rect
			(at 4.35 -1.2)
			(size 0.7 0.2)
			(layers "F.Cu" "F.Mask" "F.Paste")
			(net 412 "unconnected-(U905-DDBUS3-Pad51)")
			(pinfunction "DDBUS3")
			(pintype "bidirectional+no_connect")
		)
		(pad "52" smd rect
			(at 4.35 -1.6)
			(size 0.7 0.2)
			(layers "F.Cu" "F.Mask" "F.Paste")
			(net 411 "unconnected-(U905-DDBUS4-Pad52)")
			(pinfunction "DDBUS4")
			(pintype "bidirectional+no_connect")
		)
		(pad "53" smd rect
			(at 4.35 -2)
			(size 0.7 0.2)
			(layers "F.Cu" "F.Mask" "F.Paste")
			(net 410 "unconnected-(U905-DDBUS5-Pad53)")
			(pinfunction "DDBUS5")
			(pintype "bidirectional+no_connect")
		)
		(pad "54" smd rect
			(at 4.35 -2.4)
			(size 0.7 0.2)
			(layers "F.Cu" "F.Mask" "F.Paste")
			(net 27 "/USB/USB_3V3")
			(pinfunction "VCCIO")
			(pintype "passive")
		)
		(pad "55" smd rect
			(at 4.35 -2.8)
			(size 0.7 0.2)
			(layers "F.Cu" "F.Mask" "F.Paste")
			(net 3 "GND")
			(pinfunction "GND")
			(pintype "passive")
		)
		(pad "56" smd rect
			(at 4.35 -3.2)
			(size 0.7 0.2)
			(layers "F.Cu" "F.Mask" "F.Paste")
			(net 409 "unconnected-(U905-DDBUS6-Pad56)")
			(pinfunction "DDBUS6")
			(pintype "bidirectional+no_connect")
		)
		(pad "57" smd rect
			(at 4.35 -3.6)
			(size 0.7 0.2)
			(layers "F.Cu" "F.Mask" "F.Paste")
			(net 408 "unconnected-(U905-DDBUS7-Pad57)")
			(pinfunction "DDBUS7")
			(pintype "bidirectional+no_connect")
		)
		(pad "58" smd rect
			(at 3.6 -4.35 90)
			(size 0.7 0.2)
			(layers "F.Cu" "F.Mask" "F.Paste")
			(net 385 "Net-(U905-GPIO7)")
			(pinfunction "GPIO7")
			(pintype "bidirectional")
		)
		(pad "59" smd rect
			(at 3.2 -4.35 90)
			(size 0.7 0.2)
			(layers "F.Cu" "F.Mask" "F.Paste")
			(net 450 "Net-(U905-GPIO2)")
			(pinfunction "GPIO2")
			(pintype "bidirectional")
		)
		(pad "60" smd rect
			(at 2.8 -4.35 90)
			(size 0.7 0.2)
			(layers "F.Cu" "F.Mask" "F.Paste")
			(net 449 "Net-(U905-GPIO1)")
			(pinfunction "GPIO1")
			(pintype "bidirectional")
		)
		(pad "61" smd rect
			(at 2.4 -4.35 90)
			(size 0.7 0.2)
			(layers "F.Cu" "F.Mask" "F.Paste")
			(net 448 "Net-(U905-GPIO0)")
			(pinfunction "GPIO0")
			(pintype "bidirectional")
		)
		(pad "62" smd rect
			(at 2 -4.35 90)
			(size 0.7 0.2)
			(layers "F.Cu" "F.Mask" "F.Paste")
			(net 32 "/USB/VCC_USB")
			(pinfunction "VCC_USB")
			(pintype "power_in")
		)
		(pad "63" smd rect
			(at 1.6 -4.35 90)
			(size 0.7 0.2)
			(layers "F.Cu" "F.Mask" "F.Paste")
			(net 277 "/USB/USBD.D_N")
			(pinfunction "DM")
			(pintype "bidirectional")
		)
		(pad "64" smd rect
			(at 1.2 -4.35 90)
			(size 0.7 0.2)
			(layers "F.Cu" "F.Mask" "F.Paste")
			(net 278 "/USB/USBD.D_P")
			(pinfunction "DP")
			(pintype "bidirectional")
		)
		(pad "65" smd rect
			(at 0.8 -4.35 90)
			(size 0.7 0.2)
			(layers "F.Cu" "F.Mask" "F.Paste")
			(net 378 "Net-(U905-REF)")
			(pinfunction "REF")
			(pintype "input")
		)
		(pad "66" smd rect
			(at 0.4 -4.35 90)
			(size 0.7 0.2)
			(layers "F.Cu" "F.Mask" "F.Paste")
			(net 211 "/USB/VCC_PD")
			(pinfunction "VCC_PD")
			(pintype "power_in")
		)
		(pad "67" smd rect
			(at 0 -4.35 90)
			(size 0.7 0.2)
			(layers "F.Cu" "F.Mask" "F.Paste")
			(net 208 "/USB/USBD_CC2")
			(pinfunction "PD1_CC2")
			(pintype "bidirectional")
		)
		(pad "68" smd rect
			(at -0.4 -4.35 90)
			(size 0.7 0.2)
			(layers "F.Cu" "F.Mask" "F.Paste")
			(net 29 "/USB/USBD_SVBUS")
			(pinfunction "PD1_SVBUS")
			(pintype "input")
		)
		(pad "69" smd rect
			(at -0.8 -4.35 90)
			(size 0.7 0.2)
			(layers "F.Cu" "F.Mask" "F.Paste")
			(net 211 "/USB/VCC_PD")
			(pinfunction "PD1_VCONN")
			(pintype "power_in")
		)
		(pad "70" smd rect
			(at -1.2 -4.35 90)
			(size 0.7 0.2)
			(layers "F.Cu" "F.Mask" "F.Paste")
			(net 207 "/USB/USBD_CC1")
			(pinfunction "PD1_CC1")
			(pintype "bidirectional")
		)
		(pad "71" smd rect
			(at -1.6 -4.35 90)
			(size 0.7 0.2)
			(layers "F.Cu" "F.Mask" "F.Paste")
			(net 439 "Net-(U905-PD2_CC1)")
			(pinfunction "PD2_CC1")
			(pintype "bidirectional")
		)
		(pad "72" smd rect
			(at -2 -4.35 90)
			(size 0.7 0.2)
			(layers "F.Cu" "F.Mask" "F.Paste")
			(net 438 "Net-(U905-PD2_SVBUS)")
			(pinfunction "PD2_SVBUS")
			(pintype "input")
		)
		(pad "73" smd rect
			(at -2.4 -4.35 90)
			(size 0.7 0.2)
			(layers "F.Cu" "F.Mask" "F.Paste")
			(net 440 "Net-(U905-PD2_CC2)")
			(pinfunction "PD2_CC2")
			(pintype "bidirectional")
		)
		(pad "74" smd rect
			(at -2.8 -4.35 90)
			(size 0.7 0.2)
			(layers "F.Cu" "F.Mask" "F.Paste")
			(net 30 "/USB/USB_1V2")
			(pinfunction "VCORE")
			(pintype "passive")
		)
		(pad "75" smd rect
			(at -3.2 -4.35 90)
			(size 0.7 0.2)
			(layers "F.Cu" "F.Mask" "F.Paste")
			(net 488 "Net-(D912-C)")
			(pinfunction "~{PWREN}")
			(pintype "output")
		)
		(pad "76" smd rect
			(at -3.6 -4.35 90)
			(size 0.7 0.2)
			(layers "F.Cu" "F.Mask" "F.Paste")
			(net 283 "/USB/EECS")
			(pinfunction "EECS")
			(pintype "bidirectional")
		)
		(pad "77" smd rect
			(at 0 0)
			(size 6.3 6.3)
			(layers "F.Cu" "F.Mask")
			(net 3 "GND")
			(pinfunction "GND")
			(pintype "passive")
		)
	)
	(footprint "antmicro-footprints:R_0402_1005Metric"
		(layer "F.Cu")
		(at 54.827962 131.8265)
		(descr "Resistor SMD 0402")
		(tags "resistor SMD 0402")
		(property "Reference" "R409"
			(at -1.745 -5.41 0)
			(layer "F.SilkS")
			(effects
				(font
					(size 0.7 0.7)
					(thickness 0.15)
				)
				(justify left bottom)
			)
		)
		(property "Value" "R_10k_0402"
			(at -1.011843 1.772047 0)
			(layer "F.Fab")
			(effects
				(font
					(size 0.7 0.7)
					(thickness 0.15)
				)
				(justify left bottom)
			)
		)
		(property "Datasheet" "https://www.bourns.com/docs/product-datasheets/cr.pdf"
			(at 0 0 0)
			(layer "F.Fab")
			(hide yes)
			(effects
				(font
					(size 1.27 1.27)
					(thickness 0.15)
				)
			)
		)
		(property "Manufacturer" "Bourns"
			(at 0 0 0)
			(unlocked yes)
			(layer "F.Fab")
			(hide yes)
			(effects
				(font
					(size 1 1)
					(thickness 0.15)
				)
			)
		)
		(property "MPN" "CR0402-FX-1002GLF"
			(at 0 0 0)
			(unlocked yes)
			(layer "F.Fab")
			(hide yes)
			(effects
				(font
					(size 1 1)
					(thickness 0.15)
				)
			)
		)
		(property "Val" "10k"
			(at 0 0 0)
			(unlocked yes)
			(layer "F.Fab")
			(hide yes)
			(effects
				(font
					(size 1 1)
					(thickness 0.15)
				)
			)
		)
		(property "License" "Apache-2.0"
			(at 0 0 0)
			(unlocked yes)
			(layer "F.Fab")
			(hide yes)
			(effects
				(font
					(size 1 1)
					(thickness 0.15)
				)
			)
		)
		(property "Author" "Antmicro"
			(at 0 0 0)
			(unlocked yes)
			(layer "F.Fab")
			(hide yes)
			(effects
				(font
					(size 1 1)
					(thickness 0.15)
				)
			)
		)
		(property "Tolerance" "1%"
			(at 0 0 0)
			(unlocked yes)
			(layer "F.Fab")
			(hide yes)
			(effects
				(font
					(size 1 1)
					(thickness 0.15)
				)
			)
		)
		(sheetname "/Ethernet/")
		(sheetfile "ethernet.kicad_sch")
		(attr smd exclude_from_pos_files exclude_from_bom dnp)
		(fp_rect
			(start -0.925 -0.47)
			(end 0.925 0.47)
			(stroke
				(width 0.05)
				(type default)
			)
			(fill no)
			(layer "F.CrtYd")
		)
		(fp_rect
			(start -0.5 -0.25)
			(end 0.5 0.25)
			(stroke
				(width 0.15)
				(type solid)
			)
			(fill no)
			(layer "F.Fab")
		)
		(fp_text user "${REFERENCE}"
			(at -0.95 3.168 0)
			(layer "F.Fab")
			(effects
				(font
					(size 0.7 0.7)
					(thickness 0.15)
				)
				(justify left bottom)
			)
		)
		(fp_text user "Author: Antmicro"
			(at -0.95 4.169 0)
			(layer "F.Fab")
			(effects
				(font
					(size 0.7 0.7)
					(thickness 0.15)
				)
				(justify left bottom)
			)
		)
		(fp_text user "License: Apache-2.0"
			(at -0.95 5.169 0)
			(layer "F.Fab")
			(effects
				(font
					(size 0.7 0.7)
					(thickness 0.15)
				)
				(justify left bottom)
			)
		)
		(pad "1" smd roundrect
			(at -0.48 0)
			(size 0.59 0.64)
			(layers "F.Cu" "F.Mask" "F.Paste")
			(roundrect_rratio 0.25)
			(net 364 "/Ethernet/TPL")
			(pintype "passive")
		)
		(pad "2" smd roundrect
			(at 0.48 0)
			(size 0.59 0.64)
			(layers "F.Cu" "F.Mask" "F.Paste")
			(roundrect_rratio 0.25)
			(net 33 "/Ethernet/VDD")
			(pintype "passive")
		)
	)
	(footprint "antmicro-footprints:C_0402_1005Metric"
		(layer "F.Cu")
		(at 135.137962 159.5665 90)
		(descr "Capacitor SMD 0402")
		(tags "capacitor SMD 0402")
		(property "Reference" "C602"
			(at -8.02 1.63 90)
			(layer "F.SilkS")
			(effects
				(font
					(size 0.7 0.7)
					(thickness 0.15)
				)
				(justify left bottom)
			)
		)
		(property "Value" "C_100n_0402"
			(at -1.022927 2.155213 90)
			(layer "F.Fab")
			(effects
				(font
					(size 0.7 0.7)
					(thickness 0.15)
				)
				(justify left bottom)
			)
		)
		(property "Datasheet" "https://www.murata.com/products/productdetail?partno=GRM155R61H104KE14%23"
			(at 0 0 90)
			(layer "F.Fab")
			(hide yes)
			(effects
				(font
					(size 1.27 1.27)
					(thickness 0.15)
				)
			)
		)
		(property "Manufacturer" "Murata"
			(at 0 0 90)
			(unlocked yes)
			(layer "F.Fab")
			(hide yes)
			(effects
				(font
					(size 1 1)
					(thickness 0.15)
				)
			)
		)
		(property "MPN" "GRM155R61H104KE14D"
			(at 0 0 90)
			(unlocked yes)
			(layer "F.Fab")
			(hide yes)
			(effects
				(font
					(size 1 1)
					(thickness 0.15)
				)
			)
		)
		(property "Val" "100n"
			(at 0 0 90)
			(unlocked yes)
			(layer "F.Fab")
			(hide yes)
			(effects
				(font
					(size 1 1)
					(thickness 0.15)
				)
			)
		)
		(property "License" "Apache-2.0"
			(at 0 0 90)
			(unlocked yes)
			(layer "F.Fab")
			(hide yes)
			(effects
				(font
					(size 1 1)
					(thickness 0.15)
				)
			)
		)
		(property "Author" "Antmicro"
			(at 0 0 90)
			(unlocked yes)
			(layer "F.Fab")
			(hide yes)
			(effects
				(font
					(size 1 1)
					(thickness 0.15)
				)
			)
		)
		(property "Voltage" "50V"
			(at 0 0 90)
			(unlocked yes)
			(layer "F.Fab")
			(hide yes)
			(effects
				(font
					(size 1 1)
					(thickness 0.15)
				)
			)
		)
		(property "Dielectric" "X5R"
			(at 0 0 90)
			(unlocked yes)
			(layer "F.Fab")
			(hide yes)
			(effects
				(font
					(size 1 1)
					(thickness 0.15)
				)
			)
		)
		(sheetname "/CSI/")
		(sheetfile "csi.kicad_sch")
		(attr smd)
		(fp_rect
			(start -0.925 -0.47)
			(end 0.925 0.47)
			(stroke
				(width 0.05)
				(type default)
			)
			(fill no)
			(layer "F.CrtYd")
		)
		(fp_line
			(start 0.504 -0.25)
			(end 0.504 0.248)
			(stroke
				(width 0.15)
				(type solid)
			)
			(layer "F.Fab")
		)
		(fp_line
			(start -0.494 -0.25)
			(end 0.504 -0.25)
			(stroke
				(width 0.15)
				(type solid)
			)
			(layer "F.Fab")
		)
		(fp_line
			(start 0.504 0.248)
			(end -0.494 0.248)
			(stroke
				(width 0.15)
				(type solid)
			)
			(layer "F.Fab")
		)
		(fp_line
			(start -0.494 0.248)
			(end -0.494 -0.25)
			(stroke
				(width 0.15)
				(type solid)
			)
			(layer "F.Fab")
		)
		(fp_text user "Author: Antmicro"
			(at -0.939 3.399 90)
			(layer "F.Fab")
			(effects
				(font
					(size 0.7 0.7)
					(thickness 0.15)
				)
				(justify left bottom)
			)
		)
		(fp_text user "License: Apache-2.0"
			(at -0.939 5.799 90)
			(layer "F.Fab")
			(effects
				(font
					(size 0.7 0.7)
					(thickness 0.15)
				)
				(justify left bottom)
			)
		)
		(fp_text user "${REFERENCE}"
			(at -0.939 4.599 90)
			(layer "F.Fab")
			(effects
				(font
					(size 0.7 0.7)
					(thickness 0.15)
				)
				(justify left bottom)
			)
		)
		(pad "1" smd roundrect
			(at -0.48 0 90)
			(size 0.59 0.64)
			(layers "F.Cu" "F.Mask" "F.Paste")
			(roundrect_rratio 0.25)
			(net 9 "+3V3")
			(pintype "passive")
		)
		(pad "2" smd roundrect
			(at 0.48 0 90)
			(size 0.59 0.64)
			(layers "F.Cu" "F.Mask" "F.Paste")
			(roundrect_rratio 0.25)
			(net 3 "GND")
			(pintype "passive")
		)
	)
	(footprint "antmicro-footprints:R_0402_1005Metric"
		(layer "F.Cu")
		(at 76.692962 155.7415 90)
		(descr "Resistor SMD 0402")
		(tags "resistor SMD 0402")
		(property "Reference" "R258"
			(at -3.125 1.25 90)
			(layer "F.SilkS")
			(effects
				(font
					(size 0.7 0.7)
					(thickness 0.15)
				)
				(justify left bottom)
			)
		)
		(property "Value" "R_0R_0402"
			(at -1.011843 1.772047 90)
			(layer "F.Fab")
			(effects
				(font
					(size 0.7 0.7)
					(thickness 0.15)
				)
				(justify left bottom)
			)
		)
		(property "Datasheet" "https://industrial.panasonic.com/cdbs/www-data/pdf/RDA0000/AOA0000C301.pdf"
			(at 0 0 90)
			(layer "F.Fab")
			(hide yes)
			(effects
				(font
					(size 1.27 1.27)
					(thickness 0.15)
				)
			)
		)
		(property "Manufacturer" "Panasonic"
			(at 0 0 90)
			(unlocked yes)
			(layer "F.Fab")
			(hide yes)
			(effects
				(font
					(size 1 1)
					(thickness 0.15)
				)
			)
		)
		(property "MPN" "ERJ2GE0R00X"
			(at 0 0 90)
			(unlocked yes)
			(layer "F.Fab")
			(hide yes)
			(effects
				(font
					(size 1 1)
					(thickness 0.15)
				)
			)
		)
		(property "Val" "0R"
			(at 0 0 90)
			(unlocked yes)
			(layer "F.Fab")
			(hide yes)
			(effects
				(font
					(size 1 1)
					(thickness 0.15)
				)
			)
		)
		(property "License" "Apache-2.0"
			(at 0 0 90)
			(unlocked yes)
			(layer "F.Fab")
			(hide yes)
			(effects
				(font
					(size 1 1)
					(thickness 0.15)
				)
			)
		)
		(property "Author" "Antmicro"
			(at 0 0 90)
			(unlocked yes)
			(layer "F.Fab")
			(hide yes)
			(effects
				(font
					(size 1 1)
					(thickness 0.15)
				)
			)
		)
		(property "Tolerance" "~"
			(at 0 0 90)
			(unlocked yes)
			(layer "F.Fab")
			(hide yes)
			(effects
				(font
					(size 1 1)
					(thickness 0.15)
				)
			)
		)
		(property "Current" "1A"
			(at 0 0 90)
			(unlocked yes)
			(layer "F.Fab")
			(hide yes)
			(effects
				(font
					(size 1 1)
					(thickness 0.15)
				)
			)
		)
		(sheetname "/Compute module/")
		(sheetfile "compute-module.kicad_sch")
		(attr smd)
		(fp_rect
			(start -0.925 -0.47)
			(end 0.925 0.47)
			(stroke
				(width 0.05)
				(type default)
			)
			(fill no)
			(layer "F.CrtYd")
		)
		(fp_rect
			(start -0.5 -0.25)
			(end 0.5 0.25)
			(stroke
				(width 0.15)
				(type solid)
			)
			(fill no)
			(layer "F.Fab")
		)
		(fp_text user "${REFERENCE}"
			(at -0.95 3.168 90)
			(layer "F.Fab")
			(effects
				(font
					(size 0.7 0.7)
					(thickness 0.15)
				)
				(justify left bottom)
			)
		)
		(fp_text user "License: Apache-2.0"
			(at -0.95 5.169 90)
			(layer "F.Fab")
			(effects
				(font
					(size 0.7 0.7)
					(thickness 0.15)
				)
				(justify left bottom)
			)
		)
		(fp_text user "Author: Antmicro"
			(at -0.95 4.169 90)
			(layer "F.Fab")
			(effects
				(font
					(size 0.7 0.7)
					(thickness 0.15)
				)
				(justify left bottom)
			)
		)
		(pad "1" smd roundrect
			(at -0.48 0 90)
			(size 0.59 0.64)
			(layers "F.Cu" "F.Mask" "F.Paste")
			(roundrect_rratio 0.25)
			(net 124 "/Compute module/DSICtrl.DIM")
			(pintype "passive")
		)
		(pad "2" smd roundrect
			(at 0.48 0 90)
			(size 0.59 0.64)
			(layers "F.Cu" "F.Mask" "F.Paste")
			(roundrect_rratio 0.25)
			(net 237 "/Compute module/GPIO.18")
			(pintype "passive")
		)
	)
	(footprint "antmicro-footprints:C_0402_1005Metric"
		(layer "F.Cu")
		(at 95.117962 135.707236 90)
		(descr "Capacitor SMD 0402")
		(tags "capacitor SMD 0402")
		(property "Reference" "C918"
			(at -2.639264 1.3 90)
			(layer "F.SilkS")
			(effects
				(font
					(size 0.7 0.7)
					(thickness 0.15)
				)
				(justify left bottom)
			)
		)
		(property "Value" "C_100n_0402"
			(at -1.022927 2.155213 90)
			(layer "F.Fab")
			(effects
				(font
					(size 0.7 0.7)
					(thickness 0.15)
				)
				(justify left bottom)
			)
		)
		(property "Datasheet" "https://www.murata.com/products/productdetail?partno=GRM155R61H104KE14%23"
			(at 0 0 90)
			(layer "F.Fab")
			(hide yes)
			(effects
				(font
					(size 1.27 1.27)
					(thickness 0.15)
				)
			)
		)
		(property "Manufacturer" "Murata"
			(at 0 0 90)
			(unlocked yes)
			(layer "F.Fab")
			(hide yes)
			(effects
				(font
					(size 1 1)
					(thickness 0.15)
				)
			)
		)
		(property "MPN" "GRM155R61H104KE14D"
			(at 0 0 90)
			(unlocked yes)
			(layer "F.Fab")
			(hide yes)
			(effects
				(font
					(size 1 1)
					(thickness 0.15)
				)
			)
		)
		(property "Val" "100n"
			(at 0 0 90)
			(unlocked yes)
			(layer "F.Fab")
			(hide yes)
			(effects
				(font
					(size 1 1)
					(thickness 0.15)
				)
			)
		)
		(property "License" "Apache-2.0"
			(at 0 0 90)
			(unlocked yes)
			(layer "F.Fab")
			(hide yes)
			(effects
				(font
					(size 1 1)
					(thickness 0.15)
				)
			)
		)
		(property "Author" "Antmicro"
			(at 0 0 90)
			(unlocked yes)
			(layer "F.Fab")
			(hide yes)
			(effects
				(font
					(size 1 1)
					(thickness 0.15)
				)
			)
		)
		(property "Voltage" "50V"
			(at 0 0 90)
			(unlocked yes)
			(layer "F.Fab")
			(hide yes)
			(effects
				(font
					(size 1 1)
					(thickness 0.15)
				)
			)
		)
		(property "Dielectric" "X5R"
			(at 0 0 90)
			(unlocked yes)
			(layer "F.Fab")
			(hide yes)
			(effects
				(font
					(size 1 1)
					(thickness 0.15)
				)
			)
		)
		(sheetname "/USB/")
		(sheetfile "usb.kicad_sch")
		(attr smd)
		(fp_rect
			(start -0.925 -0.47)
			(end 0.925 0.47)
			(stroke
				(width 0.05)
				(type default)
			)
			(fill no)
			(layer "F.CrtYd")
		)
		(fp_line
			(start 0.504 -0.25)
			(end 0.504 0.248)
			(stroke
				(width 0.15)
				(type solid)
			)
			(layer "F.Fab")
		)
		(fp_line
			(start -0.494 -0.25)
			(end 0.504 -0.25)
			(stroke
				(width 0.15)
				(type solid)
			)
			(layer "F.Fab")
		)
		(fp_line
			(start 0.504 0.248)
			(end -0.494 0.248)
			(stroke
				(width 0.15)
				(type solid)
			)
			(layer "F.Fab")
		)
		(fp_line
			(start -0.494 0.248)
			(end -0.494 -0.25)
			(stroke
				(width 0.15)
				(type solid)
			)
			(layer "F.Fab")
		)
		(fp_text user "Author: Antmicro"
			(at -0.939 3.399 90)
			(layer "F.Fab")
			(effects
				(font
					(size 0.7 0.7)
					(thickness 0.15)
				)
				(justify left bottom)
			)
		)
		(fp_text user "${REFERENCE}"
			(at -0.939 4.599 90)
			(layer "F.Fab")
			(effects
				(font
					(size 0.7 0.7)
					(thickness 0.15)
				)
				(justify left bottom)
			)
		)
		(fp_text user "License: Apache-2.0"
			(at -0.939 5.799 90)
			(layer "F.Fab")
			(effects
				(font
					(size 0.7 0.7)
					(thickness 0.15)
				)
				(justify left bottom)
			)
		)
		(pad "1" smd roundrect
			(at -0.48 0 90)
			(size 0.59 0.64)
			(layers "F.Cu" "F.Mask" "F.Paste")
			(roundrect_rratio 0.25)
			(net 27 "/USB/USB_3V3")
			(pintype "passive")
		)
		(pad "2" smd roundrect
			(at 0.48 0 90)
			(size 0.59 0.64)
			(layers "F.Cu" "F.Mask" "F.Paste")
			(roundrect_rratio 0.25)
			(net 3 "GND")
			(pintype "passive")
		)
	)
	(footprint "antmicro-footprints:C_0805_2012Metric"
		(layer "F.Cu")
		(at 50.917962 127.4365)
		(descr "Capacitor SMD 0805")
		(tags "capacitor SMD 0805")
		(property "Reference" "C401"
			(at -4.6 0.72 0)
			(layer "F.SilkS")
			(effects
				(font
					(size 0.7 0.7)
					(thickness 0.15)
				)
				(justify left bottom)
			)
		)
		(property "Value" "C_100n_100V_0805"
			(at -2.055717 1.963152 0)
			(layer "F.Fab")
			(effects
				(font
					(size 0.7 0.7)
					(thickness 0.15)
				)
				(justify left bottom)
			)
		)
		(property "Datasheet" "https://product.samsungsem.com/mlcc/CL21B104KCFNNN.do"
			(at 0 0 0)
			(layer "F.Fab")
			(hide yes)
			(effects
				(font
					(size 1.27 1.27)
					(thickness 0.15)
				)
			)
		)
		(property "Manufacturer" "Samsung Electro-Mechanics"
			(at 0 0 0)
			(unlocked yes)
			(layer "F.Fab")
			(hide yes)
			(effects
				(font
					(size 1 1)
					(thickness 0.15)
				)
			)
		)
		(property "MPN" "CL21B104KCFNNNE"
			(at 0 0 0)
			(unlocked yes)
			(layer "F.Fab")
			(hide yes)
			(effects
				(font
					(size 1 1)
					(thickness 0.15)
				)
			)
		)
		(property "Val" "100n"
			(at 0 0 0)
			(unlocked yes)
			(layer "F.Fab")
			(hide yes)
			(effects
				(font
					(size 1 1)
					(thickness 0.15)
				)
			)
		)
		(property "License" "Apache-2.0"
			(at 0 0 0)
			(unlocked yes)
			(layer "F.Fab")
			(hide yes)
			(effects
				(font
					(size 1 1)
					(thickness 0.15)
				)
			)
		)
		(property "Author" "Antmicro"
			(at 0 0 0)
			(unlocked yes)
			(layer "F.Fab")
			(hide yes)
			(effects
				(font
					(size 1 1)
					(thickness 0.15)
				)
			)
		)
		(property "Voltage" "100V"
			(at 0 0 0)
			(unlocked yes)
			(layer "F.Fab")
			(hide yes)
			(effects
				(font
					(size 1 1)
					(thickness 0.15)
				)
			)
		)
		(property "Dielectric" "X7R"
			(at 0 0 0)
			(unlocked yes)
			(layer "F.Fab")
			(hide yes)
			(effects
				(font
					(size 1 1)
					(thickness 0.15)
				)
			)
		)
		(property "Public" "False"
			(at 0 0 0)
			(unlocked yes)
			(layer "F.Fab")
			(hide yes)
			(effects
				(font
					(size 1 1)
					(thickness 0.15)
				)
			)
		)
		(sheetname "/Ethernet/")
		(sheetfile "ethernet.kicad_sch")
		(attr smd)
		(fp_line
			(start -0.3 -0.7)
			(end 0.3 -0.7)
			(stroke
				(width 0.15)
				(type solid)
			)
			(layer "F.SilkS")
		)
		(fp_line
			(start -0.3 0.7)
			(end 0.3 0.7)
			(stroke
				(width 0.15)
				(type solid)
			)
			(layer "F.SilkS")
		)
		(fp_rect
			(start 1.95 -0.9)
			(end -1.95 0.9)
			(stroke
				(width 0.05)
				(type default)
			)
			(fill no)
			(layer "F.CrtYd")
		)
		(fp_rect
			(start -0.95 -0.675)
			(end 0.95 0.675)
			(stroke
				(width 0.15)
				(type solid)
			)
			(fill no)
			(layer "F.Fab")
		)
		(fp_text user "Author: Antmicro"
			(at -1.9 5.947 0)
			(layer "F.Fab")
			(effects
				(font
					(size 0.7 0.7)
					(thickness 0.15)
				)
				(justify left bottom)
			)
		)
		(fp_text user "${REFERENCE}"
			(at -1.9 3.947 0)
			(layer "F.Fab")
			(effects
				(font
					(size 0.7 0.7)
					(thickness 0.15)
				)
				(justify left bottom)
			)
		)
		(fp_text user "License: Apache-2.0"
			(at -1.9 4.947 0)
			(layer "F.Fab")
			(effects
				(font
					(size 0.7 0.7)
					(thickness 0.15)
				)
				(justify left bottom)
			)
		)
		(pad "1" smd roundrect
			(at -1.1 0)
			(size 1.2 1.3)
			(layers "F.Cu" "F.Mask" "F.Paste")
			(roundrect_rratio 0.25)
			(net 90 "/Ethernet/VSS")
			(pintype "passive")
		)
		(pad "2" smd roundrect
			(at 1.1 0)
			(size 1.2 1.3)
			(layers "F.Cu" "F.Mask" "F.Paste")
			(roundrect_rratio 0.25)
			(net 33 "/Ethernet/VDD")
			(pintype "passive")
		)
	)
	(footprint "antmicro-footprints:C_0402_1005Metric"
		(layer "F.Cu")
		(at 72.717962 176.6665 90)
		(descr "Capacitor SMD 0402")
		(tags "capacitor SMD 0402")
		(property "Reference" "C801"
			(at -2.83 -1.73 180)
			(layer "F.SilkS")
			(effects
				(font
					(size 0.7 0.7)
					(thickness 0.15)
				)
				(justify left bottom)
			)
		)
		(property "Value" "C_4u7_0402"
			(at -1.022927 2.155213 90)
			(layer "F.Fab")
			(effects
				(font
					(size 0.7 0.7)
					(thickness 0.15)
				)
				(justify left bottom)
			)
		)
		(property "Datasheet" "https://www.murata.com/products/productdetail?partno=GRM155R61A475MEAA%23"
			(at 0 0 90)
			(layer "F.Fab")
			(hide yes)
			(effects
				(font
					(size 1.27 1.27)
					(thickness 0.15)
				)
			)
		)
		(property "MPN" "GRM155R61A475MEAAD"
			(at 0 0 90)
			(unlocked yes)
			(layer "F.Fab")
			(hide yes)
			(effects
				(font
					(size 1 1)
					(thickness 0.15)
				)
			)
		)
		(property "Manufacturer" "Murata"
			(at 0 0 90)
			(unlocked yes)
			(layer "F.Fab")
			(hide yes)
			(effects
				(font
					(size 1 1)
					(thickness 0.15)
				)
			)
		)
		(property "License" "Apache-2.0"
			(at 0 0 90)
			(unlocked yes)
			(layer "F.Fab")
			(hide yes)
			(effects
				(font
					(size 1 1)
					(thickness 0.15)
				)
			)
		)
		(property "Author" "Antmicro"
			(at 0 0 90)
			(unlocked yes)
			(layer "F.Fab")
			(hide yes)
			(effects
				(font
					(size 1 1)
					(thickness 0.15)
				)
			)
		)
		(property "Val" "4u7"
			(at 0 0 90)
			(unlocked yes)
			(layer "F.Fab")
			(hide yes)
			(effects
				(font
					(size 1 1)
					(thickness 0.15)
				)
			)
		)
		(property "Voltage" ""
			(at 0 0 90)
			(unlocked yes)
			(layer "F.Fab")
			(hide yes)
			(effects
				(font
					(size 1 1)
					(thickness 0.15)
				)
			)
		)
		(property "Dielectric" ""
			(at 0 0 90)
			(unlocked yes)
			(layer "F.Fab")
			(hide yes)
			(effects
				(font
					(size 1 1)
					(thickness 0.15)
				)
			)
		)
		(sheetname "/Peripherals/")
		(sheetfile "peripherals.kicad_sch")
		(attr smd)
		(fp_rect
			(start -0.925 -0.47)
			(end 0.925 0.47)
			(stroke
				(width 0.05)
				(type default)
			)
			(fill no)
			(layer "F.CrtYd")
		)
		(fp_line
			(start 0.504 -0.25)
			(end 0.504 0.248)
			(stroke
				(width 0.15)
				(type solid)
			)
			(layer "F.Fab")
		)
		(fp_line
			(start -0.494 -0.25)
			(end 0.504 -0.25)
			(stroke
				(width 0.15)
				(type solid)
			)
			(layer "F.Fab")
		)
		(fp_line
			(start 0.504 0.248)
			(end -0.494 0.248)
			(stroke
				(width 0.15)
				(type solid)
			)
			(layer "F.Fab")
		)
		(fp_line
			(start -0.494 0.248)
			(end -0.494 -0.25)
			(stroke
				(width 0.15)
				(type solid)
			)
			(layer "F.Fab")
		)
		(fp_text user "License: Apache-2.0"
			(at -0.939 5.799 90)
			(layer "F.Fab")
			(effects
				(font
					(size 0.7 0.7)
					(thickness 0.15)
				)
				(justify left bottom)
			)
		)
		(fp_text user "${REFERENCE}"
			(at -0.939 4.599 90)
			(layer "F.Fab")
			(effects
				(font
					(size 0.7 0.7)
					(thickness 0.15)
				)
				(justify left bottom)
			)
		)
		(fp_text user "Author: Antmicro"
			(at -0.939 3.399 90)
			(layer "F.Fab")
			(effects
				(font
					(size 0.7 0.7)
					(thickness 0.15)
				)
				(justify left bottom)
			)
		)
		(pad "1" smd roundrect
			(at -0.48 0 90)
			(size 0.59 0.64)
			(layers "F.Cu" "F.Mask" "F.Paste")
			(roundrect_rratio 0.25)
			(net 3 "GND")
			(pintype "passive")
		)
		(pad "2" smd roundrect
			(at 0.48 0 90)
			(size 0.59 0.64)
			(layers "F.Cu" "F.Mask" "F.Paste")
			(roundrect_rratio 0.25)
			(net 501 "Net-(U801-V_{DD(UP)})")
			(pintype "passive")
		)
	)
	(footprint "antmicro-footprints:TP_SMD_0.75mm"
		(layer "F.Cu")
		(at 108.867962 147.4665)
		(property "Reference" "TP215"
			(at 1.35 0.35 90)
			(layer "F.SilkS")
			(effects
				(font
					(size 0.7 0.7)
					(thickness 0.15)
				)
				(justify left bottom)
			)
		)
		(property "Value" "TP_0.75mm_SMD"
			(at 0 1.2 0)
			(layer "F.Fab")
			(effects
				(font
					(size 0.7 0.7)
					(thickness 0.15)
				)
				(justify left bottom)
			)
		)
		(property "MPN" ""
			(at 0 0 0)
			(unlocked yes)
			(layer "F.Fab")
			(hide yes)
			(effects
				(font
					(size 1 1)
					(thickness 0.15)
				)
			)
		)
		(property "Manufacturer" ""
			(at 0 0 0)
			(unlocked yes)
			(layer "F.Fab")
			(hide yes)
			(effects
				(font
					(size 1 1)
					(thickness 0.15)
				)
			)
		)
		(property "Author" "Antmicro"
			(at 0 0 0)
			(unlocked yes)
			(layer "F.Fab")
			(hide yes)
			(effects
				(font
					(size 1 1)
					(thickness 0.15)
				)
			)
		)
		(property "License" "Apache-2.0"
			(at 0 0 0)
			(unlocked yes)
			(layer "F.Fab")
			(hide yes)
			(effects
				(font
					(size 1 1)
					(thickness 0.15)
				)
			)
		)
		(sheetname "/Compute module/")
		(sheetfile "compute-module.kicad_sch")
		(attr exclude_from_pos_files exclude_from_bom)
		(fp_circle
			(center 0 0)
			(end 0.475 0)
			(stroke
				(width 0.05)
				(type default)
			)
			(fill no)
			(layer "F.CrtYd")
		)
		(fp_text user "License: Apache-2.0"
			(at -0.4 5.101 0)
			(layer "F.Fab")
			(effects
				(font
					(size 0.7 0.7)
					(thickness 0.15)
				)
				(justify left bottom)
			)
		)
		(fp_text user "Author: Antmicro"
			(at -0.4 3.901 0)
			(layer "F.Fab")
			(effects
				(font
					(size 0.7 0.7)
					(thickness 0.15)
				)
				(justify left bottom)
			)
		)
		(fp_text user "${REFERENCE}"
			(at -0.4 2.7 0)
			(layer "F.Fab")
			(effects
				(font
					(size 0.7 0.7)
					(thickness 0.15)
				)
				(justify left bottom)
			)
		)
		(pad "1" smd circle
			(at 0 0)
			(size 0.75 0.75)
			(layers "F.Cu" "F.Mask")
			(net 258 "/Compute module/Pf_5V.SDA")
			(pinfunction "1")
			(pintype "passive")
		)
	)
	(footprint "antmicro-footprints:TP_SMD_0.75mm"
		(layer "F.Cu")
		(at 75.75 169.5 -90)
		(property "Reference" "TP802"
			(at -1.76 -8.225 0)
			(layer "F.SilkS")
			(effects
				(font
					(size 0.7 0.7)
					(thickness 0.15)
				)
				(justify left bottom)
			)
		)
		(property "Value" "TP_0.75mm_SMD"
			(at 0 1.2 270)
			(layer "F.Fab")
			(effects
				(font
					(size 0.7 0.7)
					(thickness 0.15)
				)
				(justify left bottom)
			)
		)
		(property "Author" "Antmicro"
			(at 0 0 270)
			(unlocked yes)
			(layer "F.Fab")
			(hide yes)
			(effects
				(font
					(size 1 1)
					(thickness 0.15)
				)
			)
		)
		(property "License" "Apache-2.0"
			(at 0 0 270)
			(unlocked yes)
			(layer "F.Fab")
			(hide yes)
			(effects
				(font
					(size 1 1)
					(thickness 0.15)
				)
			)
		)
		(property "MPN" ""
			(at 0 0 270)
			(unlocked yes)
			(layer "F.Fab")
			(hide yes)
			(effects
				(font
					(size 1 1)
					(thickness 0.15)
				)
			)
		)
		(property "Manufacturer" ""
			(at 0 0 270)
			(unlocked yes)
			(layer "F.Fab")
			(hide yes)
			(effects
				(font
					(size 1 1)
					(thickness 0.15)
				)
			)
		)
		(sheetname "/Peripherals/")
		(sheetfile "peripherals.kicad_sch")
		(attr exclude_from_pos_files exclude_from_bom)
		(fp_circle
			(center 0 0)
			(end 0.475 0)
			(stroke
				(width 0.05)
				(type default)
			)
			(fill no)
			(layer "F.CrtYd")
		)
		(fp_text user "License: Apache-2.0"
			(at -0.4 5.101 270)
			(layer "F.Fab")
			(effects
				(font
					(size 0.7 0.7)
					(thickness 0.15)
				)
				(justify left bottom)
			)
		)
		(fp_text user "Author: Antmicro"
			(at -0.4 3.901 270)
			(layer "F.Fab")
			(effects
				(font
					(size 0.7 0.7)
					(thickness 0.15)
				)
				(justify left bottom)
			)
		)
		(fp_text user "${REFERENCE}"
			(at -0.4 2.7 270)
			(layer "F.Fab")
			(effects
				(font
					(size 0.7 0.7)
					(thickness 0.15)
				)
				(justify left bottom)
			)
		)
		(pad "1" smd circle
			(at 0 0 270)
			(size 0.75 0.75)
			(layers "F.Cu" "F.Mask")
			(net 382 "Net-(U801-CLK_REQ)")
			(pinfunction "1")
			(pintype "passive")
		)
	)
	(footprint "antmicro-footprints:L_TE_0603_1811Metric"
		(layer "F.Cu")
		(at 66.74 174.05 180)
		(property "Reference" "L802"
			(at 1.64 1 0)
			(layer "F.SilkS")
			(effects
				(font
					(size 0.7 0.7)
					(thickness 0.15)
				)
				(justify right top)
			)
		)
		(property "Value" "L_160n_0.28A_0603"
			(at -1.41 1.759999 0)
			(layer "F.Fab")
			(effects
				(font
					(size 0.7 0.7)
					(thickness 0.15)
				)
				(justify right top)
			)
		)
		(property "Datasheet" "https://www.te.com/commerce/DocumentDelivery/DDEController?Action=showdoc&DocId=Data+Sheet%7F1773163%7FE%7Fpdf%7FEnglish%7FENG_DS_1773163_E.pdf"
			(at 0 0 0)
			(layer "F.Fab")
			(effects
				(font
					(size 0.7 0.7)
					(thickness 0.15)
				)
				(justify right top)
			)
		)
		(property "Description" "RF Inductor - 160 nH, 5%, 280 mA, 0603"
			(at 0 0 0)
			(layer "F.Fab")
			(effects
				(font
					(size 0.7 0.7)
					(thickness 0.15)
				)
				(justify right top)
			)
		)
		(property "Val" "160 nH"
			(at 0 0 180)
			(unlocked yes)
			(layer "F.Fab")
			(hide yes)
			(effects
				(font
					(size 1 1)
					(thickness 0.15)
				)
			)
		)
		(property "Manufacturer" "TE Connectivity"
			(at 0 0 180)
			(unlocked yes)
			(layer "F.Fab")
			(hide yes)
			(effects
				(font
					(size 1 1)
					(thickness 0.15)
				)
			)
		)
		(property "MPN" "36501JR16JTDG"
			(at 0 0 180)
			(unlocked yes)
			(layer "F.Fab")
			(hide yes)
			(effects
				(font
					(size 1 1)
					(thickness 0.15)
				)
			)
		)
		(property "ISat" ""
			(at 0 0 180)
			(unlocked yes)
			(layer "F.Fab")
			(hide yes)
			(effects
				(font
					(size 1 1)
					(thickness 0.15)
				)
			)
		)
		(property "IMax" "0.28 A"
			(at 0 0 180)
			(unlocked yes)
			(layer "F.Fab")
			(hide yes)
			(effects
				(font
					(size 1 1)
					(thickness 0.15)
				)
			)
		)
		(property "Size" "1.8 x 1.12"
			(at 0 0 180)
			(unlocked yes)
			(layer "F.Fab")
			(hide yes)
			(effects
				(font
					(size 1 1)
					(thickness 0.15)
				)
			)
		)
		(property "Author" "Antmicro"
			(at 0 0 180)
			(unlocked yes)
			(layer "F.Fab")
			(hide yes)
			(effects
				(font
					(size 1 1)
					(thickness 0.15)
				)
			)
		)
		(property "License" "Apache-2.0"
			(at 0 0 180)
			(unlocked yes)
			(layer "F.Fab")
			(hide yes)
			(effects
				(font
					(size 1 1)
					(thickness 0.15)
				)
			)
		)
		(sheetname "/Peripherals/")
		(sheetfile "peripherals.kicad_sch")
		(attr smd)
		(fp_line
			(start -0.15 0.4)
			(end 0.15 0.4)
			(stroke
				(width 0.15)
				(type solid)
			)
			(layer "F.SilkS")
		)
		(fp_line
			(start -0.15 -0.4)
			(end 0.15 -0.4)
			(stroke
				(width 0.15)
				(type solid)
			)
			(layer "F.SilkS")
		)
		(fp_poly
			(pts
				(xy -1.06 -0.66) (xy 1.06 -0.66) (xy 1.06 0.66) (xy -1.06 0.66)
			)
			(stroke
				(width 0.05)
				(type solid)
			)
			(fill no)
			(layer "F.CrtYd")
		)
		(fp_poly
			(pts
				(xy -0.8 -0.4) (xy 0.8 -0.4) (xy 0.8 0.4) (xy -0.8 0.4)
			)
			(stroke
				(width 0.15)
				(type solid)
			)
			(fill no)
			(layer "F.Fab")
		)
		(fp_text user "Author: Antmicro"
			(at -1.41 4.16 0)
			(layer "F.Fab")
			(effects
				(font
					(size 0.7 0.7)
					(thickness 0.15)
				)
				(justify right top)
			)
		)
		(fp_text user "License: Apache-2.0"
			(at -1.41 5.36 0)
			(layer "F.Fab")
			(effects
				(font
					(size 0.7 0.7)
					(thickness 0.15)
				)
				(justify right top)
			)
		)
		(fp_text user "${REFERENCE}"
			(at -1.41 2.960001 0)
			(layer "F.Fab")
			(effects
				(font
					(size 0.7 0.7)
					(thickness 0.15)
				)
				(justify right top)
			)
		)
		(pad "1" smd roundrect
			(at -0.64 0 180)
			(size 0.64 1.02)
			(layers "F.Cu" "F.Mask" "F.Paste")
			(roundrect_rratio 0.2)
			(net 326 "Net-(U801-TX2)")
			(pintype "passive")
		)
		(pad "2" smd roundrect
			(at 0.64 0 180)
			(size 0.64 1.02)
			(layers "F.Cu" "F.Mask" "F.Paste")
			(roundrect_rratio 0.2)
			(net 110 "Net-(C817-Pad1)")
			(pintype "passive")
		)
	)
	(footprint "antmicro-footprints:HDMI-A_Receptacle_WE_685119134923"
		(layer "F.Cu")
		(at 109.417962 117.3365)
		(property "Reference" "J702"
			(at 8.41 -2.89 90)
			(layer "F.SilkS")
			(effects
				(font
					(size 0.7 0.7)
					(thickness 0.15)
				)
				(justify left bottom)
			)
		)
		(property "Value" "HDMI-A_WE_685119134923"
			(at 0 7.8 0)
			(layer "F.Fab")
			(effects
				(font
					(size 0.7 0.7)
					(thickness 0.15)
				)
				(justify left bottom)
			)
		)
		(property "Datasheet" "https://www.we-online.com/components/products/datasheet/685119134923.pdf"
			(at 0 0 0)
			(layer "F.Fab")
			(hide yes)
			(effects
				(font
					(size 1.27 1.27)
					(thickness 0.15)
				)
			)
		)
		(property "MPN" "685119134923"
			(at 0 0 0)
			(unlocked yes)
			(layer "F.Fab")
			(hide yes)
			(effects
				(font
					(size 1 1)
					(thickness 0.15)
				)
			)
		)
		(property "Manufacturer" "Würth Elektronik"
			(at 0 0 0)
			(unlocked yes)
			(layer "F.Fab")
			(hide yes)
			(effects
				(font
					(size 1 1)
					(thickness 0.15)
				)
			)
		)
		(property "Author" "Antmicro"
			(at 0 0 0)
			(unlocked yes)
			(layer "F.Fab")
			(hide yes)
			(effects
				(font
					(size 1 1)
					(thickness 0.15)
				)
			)
		)
		(property "License" "Apache-2.0"
			(at 0 0 0)
			(unlocked yes)
			(layer "F.Fab")
			(hide yes)
			(effects
				(font
					(size 1 1)
					(thickness 0.15)
				)
			)
		)
		(property ki_fp_filters "685119134923")
		(sheetname "/Display/")
		(sheetfile "display.kicad_sch")
		(attr smd)
		(fp_line
			(start -7.55 -0.125)
			(end -7.55 2.65)
			(stroke
				(width 0.12)
				(type solid)
			)
			(layer "F.SilkS")
		)
		(fp_line
			(start -4.85 5.65)
			(end -5.8 5.65)
			(stroke
				(width 0.12)
				(type solid)
			)
			(layer "F.SilkS")
		)
		(fp_line
			(start 5.7 5.65)
			(end 4.75 5.65)
			(stroke
				(width 0.12)
				(type solid)
			)
			(layer "F.SilkS")
		)
		(fp_line
			(start 7.55 2.75)
			(end 7.55 -0.15)
			(stroke
				(width 0.12)
				(type solid)
			)
			(layer "F.SilkS")
		)
		(fp_circle
			(center -4.9 5.9)
			(end -4.85 5.9)
			(stroke
				(width 0.15)
				(type solid)
			)
			(fill no)
			(layer "F.SilkS")
		)
		(fp_rect
			(start -8.05 -6.32)
			(end 7.949 6.78)
			(stroke
				(width 0.05)
				(type solid)
			)
			(fill no)
			(layer "F.CrtYd")
		)
		(fp_line
			(start -7.05 -5.616)
			(end 6.95 -5.616)
			(stroke
				(width 0.15)
				(type solid)
			)
			(layer "F.Fab")
		)
		(fp_line
			(start -7.05 5.525)
			(end -7.05 -5.616)
			(stroke
				(width 0.15)
				(type solid)
			)
			(layer "F.Fab")
		)
		(fp_line
			(start -7.05 5.525)
			(end -6.05 6.525)
			(stroke
				(width 0.15)
				(type solid)
			)
			(layer "F.Fab")
		)
		(fp_line
			(start 6.95 6.535)
			(end -6.05 6.535)
			(stroke
				(width 0.15)
				(type solid)
			)
			(layer "F.Fab")
		)
		(fp_line
			(start 6.95 6.535)
			(end 6.95 -5.616)
			(stroke
				(width 0.15)
				(type solid)
			)
			(layer "F.Fab")
		)
		(fp_text user "License: Apache-2.0"
			(at -8 12.5 0)
			(layer "F.Fab")
			(effects
				(font
					(size 0.7 0.7)
					(thickness 0.15)
				)
				(justify left bottom)
			)
		)
		(fp_text user "Author: Antmicro"
			(at -8 11 0)
			(layer "F.Fab")
			(effects
				(font
					(size 0.7 0.7)
					(thickness 0.15)
				)
				(justify left bottom)
			)
		)
		(fp_text user "${REFERENCE}"
			(at -8 9.5 0)
			(layer "F.Fab")
			(effects
				(font
					(size 0.7 0.7)
					(thickness 0.15)
				)
				(justify left bottom)
			)
		)
		(pad "1" smd rect
			(at -4.55 5.224)
			(size 0.28 2.6)
			(layers "F.Cu" "F.Mask" "F.Paste")
			(net 16 "/Compute module/HDMI.D2_P")
			(pinfunction "D2+")
			(pintype "bidirectional")
		)
		(pad "2" smd rect
			(at -4.05 5.224)
			(size 0.28 2.6)
			(layers "F.Cu" "F.Mask" "F.Paste")
			(net 3 "GND")
			(pinfunction "D2S")
			(pintype "passive")
		)
		(pad "3" smd rect
			(at -3.551 5.224)
			(size 0.28 2.6)
			(layers "F.Cu" "F.Mask" "F.Paste")
			(net 15 "/Compute module/HDMI.D2_N")
			(pinfunction "D2-")
			(pintype "bidirectional")
		)
		(pad "4" smd rect
			(at -3.051 5.224)
			(size 0.28 2.6)
			(layers "F.Cu" "F.Mask" "F.Paste")
			(net 14 "/Compute module/HDMI.D1_P")
			(pinfunction "D1+")
			(pintype "bidirectional")
		)
		(pad "5" smd rect
			(at -2.551 5.224)
			(size 0.28 2.6)
			(layers "F.Cu" "F.Mask" "F.Paste")
			(net 3 "GND")
			(pinfunction "D1S")
			(pintype "passive")
		)
		(pad "6" smd rect
			(at -2.05 5.224)
			(size 0.28 2.6)
			(layers "F.Cu" "F.Mask" "F.Paste")
			(net 13 "/Compute module/HDMI.D1_N")
			(pinfunction "D1-")
			(pintype "bidirectional")
		)
		(pad "7" smd rect
			(at -1.551 5.224)
			(size 0.28 2.6)
			(layers "F.Cu" "F.Mask" "F.Paste")
			(net 35 "/Compute module/HDMI.D0_P")
			(pinfunction "D0+")
			(pintype "bidirectional")
		)
		(pad "8" smd rect
			(at -1.051 5.224)
			(size 0.28 2.6)
			(layers "F.Cu" "F.Mask" "F.Paste")
			(net 3 "GND")
			(pinfunction "D0S")
			(pintype "passive")
		)
		(pad "9" smd rect
			(at -0.551 5.224)
			(size 0.28 2.6)
			(layers "F.Cu" "F.Mask" "F.Paste")
			(net 34 "/Compute module/HDMI.D0_N")
			(pinfunction "D0-")
			(pintype "bidirectional")
		)
		(pad "10" smd rect
			(at -0.051 5.224)
			(size 0.28 2.6)
			(layers "F.Cu" "F.Mask" "F.Paste")
			(net 25 "/Compute module/HDMI.CLK_P")
			(pinfunction "CK+")
			(pintype "bidirectional")
		)
		(pad "11" smd rect
			(at 0.45 5.224)
			(size 0.28 2.6)
			(layers "F.Cu" "F.Mask" "F.Paste")
			(net 3 "GND")
			(pinfunction "CKS")
			(pintype "passive")
		)
		(pad "12" smd rect
			(at 0.95 5.224)
			(size 0.28 2.6)
			(layers "F.Cu" "F.Mask" "F.Paste")
			(net 23 "/Compute module/HDMI.CLK_N")
			(pinfunction "CK-")
			(pintype "bidirectional")
		)
		(pad "13" smd rect
			(at 1.449 5.224)
			(size 0.28 2.6)
			(layers "F.Cu" "F.Mask" "F.Paste")
			(net 451 "/Display/CEC")
			(pinfunction "CEC")
			(pintype "bidirectional")
		)
		(pad "14" smd rect
			(at 1.949 5.224)
			(size 0.28 2.6)
			(layers "F.Cu" "F.Mask" "F.Paste")
			(net 318 "unconnected-(J702-UTILITY{slash}HEAC+-Pad14)")
			(pinfunction "UTILITY/HEAC+")
			(pintype "bidirectional+no_connect")
		)
		(pad "15" smd rect
			(at 2.45 5.224)
			(size 0.28 2.6)
			(layers "F.Cu" "F.Mask" "F.Paste")
			(net 452 "/Display/SCL")
			(pinfunction "SCL")
			(pintype "bidirectional")
		)
		(pad "16" smd rect
			(at 2.95 5.224)
			(size 0.28 2.6)
			(layers "F.Cu" "F.Mask" "F.Paste")
			(net 453 "/Display/SDA")
			(pinfunction "SDA")
			(pintype "bidirectional")
		)
		(pad "17" smd rect
			(at 3.45 5.224)
			(size 0.28 2.6)
			(layers "F.Cu" "F.Mask" "F.Paste")
			(net 3 "GND")
			(pinfunction "GND")
			(pintype "power_in")
		)
		(pad "18" smd rect
			(at 3.95 5.224)
			(size 0.28 2.6)
			(layers "F.Cu" "F.Mask" "F.Paste")
			(net 119 "Net-(D710-C)")
			(pinfunction "+5V")
			(pintype "power_in")
		)
		(pad "19" smd rect
			(at 4.45 5.224)
			(size 0.28 2.6)
			(layers "F.Cu" "F.Mask" "F.Paste")
			(net 454 "/Display/HPD")
			(pinfunction "HPD/HEAC-")
			(pintype "bidirectional")
		)
		(pad "SH" thru_hole oval
			(at -7.3 -1.577)
			(size 1.5 2.7)
			(drill oval 0.9 2.1)
			(layers "*.Cu" "*.Mask")
			(remove_unused_layers no)
			(net 3 "GND")
			(pinfunction "SH")
			(pintype "passive")
		)
		(pad "SH" thru_hole oval
			(at -7.3 4.424)
			(size 1.5 3.3)
			(drill oval 0.9 2.7)
			(layers "*.Cu" "*.Mask")
			(remove_unused_layers no)
			(net 3 "GND")
			(pinfunction "SH")
			(pintype "passive")
		)
		(pad "SH" thru_hole oval
			(at 7.2 -1.577)
			(size 1.5 2.7)
			(drill oval 0.9 2.1)
			(layers "*.Cu" "*.Mask")
			(remove_unused_layers no)
			(net 3 "GND")
			(pinfunction "SH")
			(pintype "passive")
		)
		(pad "SH" thru_hole oval
			(at 7.2 4.424)
			(size 1.5 3.3)
			(drill oval 0.9 2.7)
			(layers "*.Cu" "*.Mask")
			(remove_unused_layers no)
			(net 3 "GND")
			(pinfunction "SH")
			(pintype "passive")
		)
	)
	(footprint "antmicro-footprints:R_0402_1005Metric"
		(layer "F.Cu")
		(at 72.867962 167.4115)
		(descr "Resistor SMD 0402")
		(tags "resistor SMD 0402")
		(property "Reference" "R806"
			(at -1.887962 -1.475 0)
			(layer "F.SilkS")
			(effects
				(font
					(size 0.7 0.7)
					(thickness 0.15)
				)
				(justify left bottom)
			)
		)
		(property "Value" "R_10k_0402"
			(at -1.011843 1.772047 0)
			(layer "F.Fab")
			(effects
				(font
					(size 0.7 0.7)
					(thickness 0.15)
				)
				(justify left bottom)
			)
		)
		(property "Datasheet" "https://www.bourns.com/docs/product-datasheets/cr.pdf"
			(at 0 0 0)
			(layer "F.Fab")
			(hide yes)
			(effects
				(font
					(size 1.27 1.27)
					(thickness 0.15)
				)
			)
		)
		(property "MPN" "CR0402-FX-1002GLF"
			(at 0 0 0)
			(unlocked yes)
			(layer "F.Fab")
			(hide yes)
			(effects
				(font
					(size 1 1)
					(thickness 0.15)
				)
			)
		)
		(property "Manufacturer" "Bourns"
			(at 0 0 0)
			(unlocked yes)
			(layer "F.Fab")
			(hide yes)
			(effects
				(font
					(size 1 1)
					(thickness 0.15)
				)
			)
		)
		(property "License" "Apache-2.0"
			(at 0 0 0)
			(unlocked yes)
			(layer "F.Fab")
			(hide yes)
			(effects
				(font
					(size 1 1)
					(thickness 0.15)
				)
			)
		)
		(property "Author" "Antmicro"
			(at 0 0 0)
			(unlocked yes)
			(layer "F.Fab")
			(hide yes)
			(effects
				(font
					(size 1 1)
					(thickness 0.15)
				)
			)
		)
		(property "Val" "10k"
			(at 0 0 0)
			(unlocked yes)
			(layer "F.Fab")
			(hide yes)
			(effects
				(font
					(size 1 1)
					(thickness 0.15)
				)
			)
		)
		(property "Tolerance" "1%"
			(at 0 0 0)
			(unlocked yes)
			(layer "F.Fab")
			(hide yes)
			(effects
				(font
					(size 1 1)
					(thickness 0.15)
				)
			)
		)
		(sheetname "/Peripherals/")
		(sheetfile "peripherals.kicad_sch")
		(attr smd)
		(fp_rect
			(start -0.925 -0.47)
			(end 0.925 0.47)
			(stroke
				(width 0.05)
				(type default)
			)
			(fill no)
			(layer "F.CrtYd")
		)
		(fp_rect
			(start -0.5 -0.25)
			(end 0.5 0.25)
			(stroke
				(width 0.15)
				(type solid)
			)
			(fill no)
			(layer "F.Fab")
		)
		(fp_text user "License: Apache-2.0"
			(at -0.95 5.169 0)
			(layer "F.Fab")
			(effects
				(font
					(size 0.7 0.7)
					(thickness 0.15)
				)
				(justify left bottom)
			)
		)
		(fp_text user "Author: Antmicro"
			(at -0.95 4.169 0)
			(layer "F.Fab")
			(effects
				(font
					(size 0.7 0.7)
					(thickness 0.15)
				)
				(justify left bottom)
			)
		)
		(fp_text user "${REFERENCE}"
			(at -0.95 3.168 0)
			(layer "F.Fab")
			(effects
				(font
					(size 0.7 0.7)
					(thickness 0.15)
				)
				(justify left bottom)
			)
		)
		(pad "1" smd roundrect
			(at -0.48 0)
			(size 0.59 0.64)
			(layers "F.Cu" "F.Mask" "F.Paste")
			(roundrect_rratio 0.25)
			(net 3 "GND")
			(pintype "passive")
		)
		(pad "2" smd roundrect
			(at 0.48 0)
			(size 0.59 0.64)
			(layers "F.Cu" "F.Mask" "F.Paste")
			(roundrect_rratio 0.25)
			(net 375 "Net-(U801-I2C_ADR1)")
			(pintype "passive")
		)
	)
	(footprint "antmicro-footprints:R_0402_1005Metric"
		(layer "F.Cu")
		(at 96.117962 129.2165)
		(descr "Resistor SMD 0402")
		(tags "resistor SMD 0402")
		(property "Reference" "R905"
			(at -1.65 1.2 0)
			(layer "F.SilkS")
			(effects
				(font
					(size 0.7 0.7)
					(thickness 0.15)
				)
				(justify left bottom)
			)
		)
		(property "Value" "R_4k7_0402"
			(at -1.011843 1.772047 0)
			(layer "F.Fab")
			(effects
				(font
					(size 0.7 0.7)
					(thickness 0.15)
				)
				(justify left bottom)
			)
		)
		(property "Datasheet" "https://www.bourns.com/docs/product-datasheets/cr.pdf"
			(at 0 0 0)
			(layer "F.Fab")
			(hide yes)
			(effects
				(font
					(size 1.27 1.27)
					(thickness 0.15)
				)
			)
		)
		(property "Manufacturer" "Bourns"
			(at 0 0 0)
			(unlocked yes)
			(layer "F.Fab")
			(hide yes)
			(effects
				(font
					(size 1 1)
					(thickness 0.15)
				)
			)
		)
		(property "MPN" "CR0402-FX-4701GLF"
			(at 0 0 0)
			(unlocked yes)
			(layer "F.Fab")
			(hide yes)
			(effects
				(font
					(size 1 1)
					(thickness 0.15)
				)
			)
		)
		(property "Val" "4k7"
			(at 0 0 0)
			(unlocked yes)
			(layer "F.Fab")
			(hide yes)
			(effects
				(font
					(size 1 1)
					(thickness 0.15)
				)
			)
		)
		(property "License" "Apache-2.0"
			(at 0 0 0)
			(unlocked yes)
			(layer "F.Fab")
			(hide yes)
			(effects
				(font
					(size 1 1)
					(thickness 0.15)
				)
			)
		)
		(property "Author" "Antmicro"
			(at 0 0 0)
			(unlocked yes)
			(layer "F.Fab")
			(hide yes)
			(effects
				(font
					(size 1 1)
					(thickness 0.15)
				)
			)
		)
		(property "Tolerance" "1%"
			(at 0 0 0)
			(unlocked yes)
			(layer "F.Fab")
			(hide yes)
			(effects
				(font
					(size 1 1)
					(thickness 0.15)
				)
			)
		)
		(sheetname "/USB/")
		(sheetfile "usb.kicad_sch")
		(attr smd)
		(fp_rect
			(start -0.925 -0.47)
			(end 0.925 0.47)
			(stroke
				(width 0.05)
				(type default)
			)
			(fill no)
			(layer "F.CrtYd")
		)
		(fp_rect
			(start -0.5 -0.25)
			(end 0.5 0.25)
			(stroke
				(width 0.15)
				(type solid)
			)
			(fill no)
			(layer "F.Fab")
		)
		(fp_text user "${REFERENCE}"
			(at -0.95 3.168 0)
			(layer "F.Fab")
			(effects
				(font
					(size 0.7 0.7)
					(thickness 0.15)
				)
				(justify left bottom)
			)
		)
		(fp_text user "Author: Antmicro"
			(at -0.95 4.169 0)
			(layer "F.Fab")
			(effects
				(font
					(size 0.7 0.7)
					(thickness 0.15)
				)
				(justify left bottom)
			)
		)
		(fp_text user "License: Apache-2.0"
			(at -0.95 5.169 0)
			(layer "F.Fab")
			(effects
				(font
					(size 0.7 0.7)
					(thickness 0.15)
				)
				(justify left bottom)
			)
		)
		(pad "1" smd roundrect
			(at -0.48 0)
			(size 0.59 0.64)
			(layers "F.Cu" "F.Mask" "F.Paste")
			(roundrect_rratio 0.25)
			(net 3 "GND")
			(pintype "passive")
		)
		(pad "2" smd roundrect
			(at 0.48 0)
			(size 0.59 0.64)
			(layers "F.Cu" "F.Mask" "F.Paste")
			(roundrect_rratio 0.25)
			(net 376 "Net-(U901-ISET)")
			(pintype "passive")
		)
	)
	(footprint "antmicro-footprints:LED_0603_1608Metric_G"
		(layer "F.Cu")
		(at 58.467962 134.9865 90)
		(descr "LED SMD 0603 Green")
		(tags "LED SMD 0603 Green")
		(property "Reference" "D404"
			(at -1.355 3.3 90)
			(layer "F.SilkS")
			(effects
				(font
					(size 0.7 0.7)
					(thickness 0.15)
				)
				(justify left bottom)
			)
		)
		(property "Value" "LED_G_0603_KP-1608CGCK"
			(at -0.001 1.599 90)
			(layer "F.Fab")
			(effects
				(font
					(size 0.7 0.7)
					(thickness 0.15)
				)
				(justify left bottom)
			)
		)
		(property "Datasheet" "http://www.kingbright.com/attachments/file/psearch//000/00/00/KP-1608CGCK(Ver.23B).pdf"
			(at 0 0 90)
			(layer "F.Fab")
			(hide yes)
			(effects
				(font
					(size 1.27 1.27)
					(thickness 0.15)
				)
			)
		)
		(property "MPN" "KP-1608CGCK"
			(at 0 0 90)
			(unlocked yes)
			(layer "F.Fab")
			(hide yes)
			(effects
				(font
					(size 1 1)
					(thickness 0.15)
				)
			)
		)
		(property "Manufacturer" "Kingbright"
			(at 0 0 90)
			(unlocked yes)
			(layer "F.Fab")
			(hide yes)
			(effects
				(font
					(size 1 1)
					(thickness 0.15)
				)
			)
		)
		(property "Color" "Green"
			(at 0 0 90)
			(unlocked yes)
			(layer "F.Fab")
			(hide yes)
			(effects
				(font
					(size 1 1)
					(thickness 0.15)
				)
			)
		)
		(property "Author" "Antmicro"
			(at 0 0 90)
			(unlocked yes)
			(layer "F.Fab")
			(hide yes)
			(effects
				(font
					(size 1 1)
					(thickness 0.15)
				)
			)
		)
		(property "License" "Apache-2.0"
			(at 0 0 90)
			(unlocked yes)
			(layer "F.Fab")
			(hide yes)
			(effects
				(font
					(size 1 1)
					(thickness 0.15)
				)
			)
		)
		(sheetname "/Ethernet/")
		(sheetfile "ethernet.kicad_sch")
		(attr smd)
		(fp_line
			(start 0.22 -0.35)
			(end -0.22 -0.35)
			(stroke
				(width 0.15)
				(type solid)
			)
			(layer "F.SilkS")
		)
		(fp_line
			(start -1.18 -0.319)
			(end -1.18 0.321)
			(stroke
				(width 0.15)
				(type solid)
			)
			(layer "F.SilkS")
		)
		(fp_line
			(start 0.105328 0.001008)
			(end 0.24 0.001)
			(stroke
				(width 0.1)
				(type solid)
			)
			(layer "F.SilkS")
		)
		(fp_line
			(start -0.094672 0.001008)
			(end 0.105328 -0.198992)
			(stroke
				(width 0.1)
				(type solid)
			)
			(layer "F.SilkS")
		)
		(fp_line
			(start -0.094672 0.001008)
			(end -0.24 0.001008)
			(stroke
				(width 0.1)
				(type solid)
			)
			(layer "F.SilkS")
		)
		(fp_line
			(start 0.105328 0.201008)
			(end 0.105328 -0.198992)
			(stroke
				(width 0.1)
				(type solid)
			)
			(layer "F.SilkS")
		)
		(fp_line
			(start 0.105328 0.201008)
			(end -0.094672 0.001008)
			(stroke
				(width 0.1)
				(type solid)
			)
			(layer "F.SilkS")
		)
		(fp_line
			(start -0.094672 0.201008)
			(end -0.094672 -0.198992)
			(stroke
				(width 0.1)
				(type solid)
			)
			(layer "F.SilkS")
		)
		(fp_line
			(start 0.22 0.35)
			(end -0.22 0.35)
			(stroke
				(width 0.15)
				(type solid)
			)
			(layer "F.SilkS")
		)
		(fp_rect
			(start 1.25 0.65)
			(end -1.25 -0.65)
			(stroke
				(width 0.05)
				(type solid)
			)
			(fill no)
			(layer "F.CrtYd")
		)
		(fp_line
			(start 0.201 -0.202)
			(end -0.101 0)
			(stroke
				(width 0.15)
				(type solid)
			)
			(layer "F.Fab")
		)
		(fp_line
			(start -0.199 -0.202)
			(end -0.199 0.1)
			(stroke
				(width 0.15)
				(type solid)
			)
			(layer "F.Fab")
		)
		(fp_line
			(start 0.599 0)
			(end 0.201 0)
			(stroke
				(width 0.15)
				(type solid)
			)
			(layer "F.Fab")
		)
		(fp_line
			(start 0.201 0)
			(end 0.201 -0.202)
			(stroke
				(width 0.15)
				(type solid)
			)
			(layer "F.Fab")
		)
		(fp_line
			(start -0.101 0)
			(end 0.201 0.2)
			(stroke
				(width 0.15)
				(type solid)
			)
			(layer "F.Fab")
		)
		(fp_line
			(start -0.199 0)
			(end -0.597 0)
			(stroke
				(width 0.15)
				(type solid)
			)
			(layer "F.Fab")
		)
		(fp_line
			(start 0.201 0.2)
			(end 0.201 0)
			(stroke
				(width 0.15)
				(type solid)
			)
			(layer "F.Fab")
		)
		(fp_line
			(start -0.199 0.2)
			(end -0.199 0.1)
			(stroke
				(width 0.15)
				(type solid)
			)
			(layer "F.Fab")
		)
		(fp_rect
			(start 0.848 0.4)
			(end -0.85 -0.402)
			(stroke
				(width 0.15)
				(type solid)
			)
			(fill no)
			(layer "F.Fab")
		)
		(fp_text user "License: Apache-2.0"
			(at -1.4224 3.599 90)
			(layer "F.Fab")
			(effects
				(font
					(size 0.7 0.7)
					(thickness 0.15)
				)
				(justify left bottom)
			)
		)
		(fp_text user "${REFERENCE}"
			(at -1.4224 5.999 90)
			(layer "F.Fab")
			(effects
				(font
					(size 0.7 0.7)
					(thickness 0.15)
				)
				(justify left bottom)
			)
		)
		(fp_text user "Author: Antmicro"
			(at -1.4224 4.799 90)
			(layer "F.Fab")
			(effects
				(font
					(size 0.7 0.7)
					(thickness 0.15)
				)
				(justify left bottom)
			)
		)
		(pad "1" smd roundrect
			(at -0.7 0 270)
			(size 0.8 1)
			(layers "F.Cu" "F.Mask" "F.Paste")
			(roundrect_rratio 0.2)
			(net 1 "GNDD")
			(pinfunction "C")
			(pintype "passive")
		)
		(pad "2" smd roundrect
			(at 0.7 0 270)
			(size 0.8 1)
			(layers "F.Cu" "F.Mask" "F.Paste")
			(roundrect_rratio 0.2)
			(net 477 "Net-(D404-A)")
			(pinfunction "A")
			(pintype "passive")
		)
	)
	(footprint "antmicro-footprints:LED_0603_1608Metric_G"
		(layer "F.Cu")
		(at 88.992962 120.9915 180)
		(descr "LED SMD 0603 Green")
		(tags "LED SMD 0603 Green")
		(property "Reference" "D905"
			(at -0.175 0.525 0)
			(layer "F.SilkS")
			(effects
				(font
					(size 0.7 0.7)
					(thickness 0.15)
				)
				(justify right bottom)
			)
		)
		(property "Value" "LED_G_0603_KP-1608CGCK"
			(at -0.001 1.599 0)
			(layer "F.Fab")
			(effects
				(font
					(size 0.7 0.7)
					(thickness 0.15)
				)
				(justify right bottom)
			)
		)
		(property "Datasheet" "http://www.kingbright.com/attachments/file/psearch//000/00/00/KP-1608CGCK(Ver.23B).pdf"
			(at 0 0 180)
			(layer "F.Fab")
			(hide yes)
			(effects
				(font
					(size 1.27 1.27)
					(thickness 0.15)
				)
			)
		)
		(property "MPN" "KP-1608CGCK"
			(at 0 0 180)
			(unlocked yes)
			(layer "F.Fab")
			(hide yes)
			(effects
				(font
					(size 1 1)
					(thickness 0.15)
				)
			)
		)
		(property "Manufacturer" "Kingbright"
			(at 0 0 180)
			(unlocked yes)
			(layer "F.Fab")
			(hide yes)
			(effects
				(font
					(size 1 1)
					(thickness 0.15)
				)
			)
		)
		(property "Color" "Green"
			(at 0 0 180)
			(unlocked yes)
			(layer "F.Fab")
			(hide yes)
			(effects
				(font
					(size 1 1)
					(thickness 0.15)
				)
			)
		)
		(property "Author" "Antmicro"
			(at 0 0 180)
			(unlocked yes)
			(layer "F.Fab")
			(hide yes)
			(effects
				(font
					(size 1 1)
					(thickness 0.15)
				)
			)
		)
		(property "License" "Apache-2.0"
			(at 0 0 180)
			(unlocked yes)
			(layer "F.Fab")
			(hide yes)
			(effects
				(font
					(size 1 1)
					(thickness 0.15)
				)
			)
		)
		(sheetname "/USB/")
		(sheetfile "usb.kicad_sch")
		(attr smd)
		(fp_line
			(start 0.22 0.35)
			(end -0.22 0.35)
			(stroke
				(width 0.15)
				(type solid)
			)
			(layer "F.SilkS")
		)
		(fp_line
			(start 0.22 -0.35)
			(end -0.22 -0.35)
			(stroke
				(width 0.15)
				(type solid)
			)
			(layer "F.SilkS")
		)
		(fp_line
			(start 0.105328 0.201008)
			(end 0.105328 -0.198992)
			(stroke
				(width 0.1)
				(type solid)
			)
			(layer "F.SilkS")
		)
		(fp_line
			(start 0.105328 0.201008)
			(end -0.094672 0.001008)
			(stroke
				(width 0.1)
				(type solid)
			)
			(layer "F.SilkS")
		)
		(fp_line
			(start 0.105328 0.001008)
			(end 0.24 0.001)
			(stroke
				(width 0.1)
				(type solid)
			)
			(layer "F.SilkS")
		)
		(fp_line
			(start -0.094672 0.201008)
			(end -0.094672 -0.198992)
			(stroke
				(width 0.1)
				(type solid)
			)
			(layer "F.SilkS")
		)
		(fp_line
			(start -0.094672 0.001008)
			(end 0.105328 -0.198992)
			(stroke
				(width 0.1)
				(type solid)
			)
			(layer "F.SilkS")
		)
		(fp_line
			(start -0.094672 0.001008)
			(end -0.24 0.001008)
			(stroke
				(width 0.1)
				(type solid)
			)
			(layer "F.SilkS")
		)
		(fp_line
			(start -1.18 -0.319)
			(end -1.18 0.321)
			(stroke
				(width 0.15)
				(type solid)
			)
			(layer "F.SilkS")
		)
		(fp_rect
			(start 1.25 0.65)
			(end -1.25 -0.65)
			(stroke
				(width 0.05)
				(type solid)
			)
			(fill no)
			(layer "F.CrtYd")
		)
		(fp_line
			(start 0.599 0)
			(end 0.201 0)
			(stroke
				(width 0.15)
				(type solid)
			)
			(layer "F.Fab")
		)
		(fp_line
			(start 0.201 0.2)
			(end 0.201 0)
			(stroke
				(width 0.15)
				(type solid)
			)
			(layer "F.Fab")
		)
		(fp_line
			(start 0.201 0)
			(end 0.201 -0.202)
			(stroke
				(width 0.15)
				(type solid)
			)
			(layer "F.Fab")
		)
		(fp_line
			(start 0.201 -0.202)
			(end -0.101 0)
			(stroke
				(width 0.15)
				(type solid)
			)
			(layer "F.Fab")
		)
		(fp_line
			(start -0.101 0)
			(end 0.201 0.2)
			(stroke
				(width 0.15)
				(type solid)
			)
			(layer "F.Fab")
		)
		(fp_line
			(start -0.199 0.2)
			(end -0.199 0.1)
			(stroke
				(width 0.15)
				(type solid)
			)
			(layer "F.Fab")
		)
		(fp_line
			(start -0.199 0)
			(end -0.597 0)
			(stroke
				(width 0.15)
				(type solid)
			)
			(layer "F.Fab")
		)
		(fp_line
			(start -0.199 -0.202)
			(end -0.199 0.1)
			(stroke
				(width 0.15)
				(type solid)
			)
			(layer "F.Fab")
		)
		(fp_rect
			(start 0.848 0.4)
			(end -0.85 -0.402)
			(stroke
				(width 0.15)
				(type solid)
			)
			(fill no)
			(layer "F.Fab")
		)
		(fp_text user "Author: Antmicro"
			(at -1.4224 4.799 180)
			(layer "F.Fab")
			(effects
				(font
					(size 0.7 0.7)
					(thickness 0.15)
				)
				(justify left bottom)
			)
		)
		(fp_text user "License: Apache-2.0"
			(at -1.4224 3.599 180)
			(layer "F.Fab")
			(effects
				(font
					(size 0.7 0.7)
					(thickness 0.15)
				)
				(justify left bottom)
			)
		)
		(fp_text user "${REFERENCE}"
			(at -1.4224 5.999 180)
			(layer "F.Fab")
			(effects
				(font
					(size 0.7 0.7)
					(thickness 0.15)
				)
				(justify left bottom)
			)
		)
		(pad "1" smd roundrect
			(at -0.7 0)
			(size 0.8 1)
			(layers "F.Cu" "F.Mask" "F.Paste")
			(roundrect_rratio 0.2)
			(net 3 "GND")
			(pinfunction "C")
			(pintype "passive")
		)
		(pad "2" smd roundrect
			(at 0.7 0)
			(size 0.8 1)
			(layers "F.Cu" "F.Mask" "F.Paste")
			(roundrect_rratio 0.2)
			(net 482 "Net-(D905-A)")
			(pinfunction "A")
			(pintype "passive")
		)
	)
	(footprint "antmicro-footprints:R_0402_1005Metric"
		(layer "F.Cu")
		(at 92.817962 156.7665 180)
		(descr "Resistor SMD 0402")
		(tags "resistor SMD 0402")
		(property "Reference" "R234"
			(at -3.86 -0.6 0)
			(layer "F.SilkS")
			(effects
				(font
					(size 0.7 0.7)
					(thickness 0.15)
				)
				(justify right bottom)
			)
		)
		(property "Value" "R_10k_0402"
			(at -1.011843 1.772047 0)
			(layer "F.Fab")
			(effects
				(font
					(size 0.7 0.7)
					(thickness 0.15)
				)
				(justify right bottom)
			)
		)
		(property "Datasheet" "https://www.bourns.com/docs/product-datasheets/cr.pdf"
			(at 0 0 180)
			(layer "F.Fab")
			(hide yes)
			(effects
				(font
					(size 1.27 1.27)
					(thickness 0.15)
				)
			)
		)
		(property "MPN" "CR0402-FX-1002GLF"
			(at 0 0 180)
			(unlocked yes)
			(layer "F.Fab")
			(hide yes)
			(effects
				(font
					(size 1 1)
					(thickness 0.15)
				)
			)
		)
		(property "Manufacturer" "Bourns"
			(at 0 0 180)
			(unlocked yes)
			(layer "F.Fab")
			(hide yes)
			(effects
				(font
					(size 1 1)
					(thickness 0.15)
				)
			)
		)
		(property "License" "Apache-2.0"
			(at 0 0 180)
			(unlocked yes)
			(layer "F.Fab")
			(hide yes)
			(effects
				(font
					(size 1 1)
					(thickness 0.15)
				)
			)
		)
		(property "Author" "Antmicro"
			(at 0 0 180)
			(unlocked yes)
			(layer "F.Fab")
			(hide yes)
			(effects
				(font
					(size 1 1)
					(thickness 0.15)
				)
			)
		)
		(property "Val" "10k"
			(at 0 0 180)
			(unlocked yes)
			(layer "F.Fab")
			(hide yes)
			(effects
				(font
					(size 1 1)
					(thickness 0.15)
				)
			)
		)
		(property "Tolerance" "1%"
			(at 0 0 180)
			(unlocked yes)
			(layer "F.Fab")
			(hide yes)
			(effects
				(font
					(size 1 1)
					(thickness 0.15)
				)
			)
		)
		(sheetname "/Compute module/")
		(sheetfile "compute-module.kicad_sch")
		(attr smd)
		(fp_rect
			(start -0.925 -0.47)
			(end 0.925 0.47)
			(stroke
				(width 0.05)
				(type default)
			)
			(fill no)
			(layer "F.CrtYd")
		)
		(fp_rect
			(start -0.5 -0.25)
			(end 0.5 0.25)
			(stroke
				(width 0.15)
				(type solid)
			)
			(fill no)
			(layer "F.Fab")
		)
		(fp_text user "Author: Antmicro"
			(at -0.95 4.169 180)
			(layer "F.Fab")
			(effects
				(font
					(size 0.7 0.7)
					(thickness 0.15)
				)
				(justify left bottom)
			)
		)
		(fp_text user "License: Apache-2.0"
			(at -0.95 5.169 180)
			(layer "F.Fab")
			(effects
				(font
					(size 0.7 0.7)
					(thickness 0.15)
				)
				(justify left bottom)
			)
		)
		(fp_text user "${REFERENCE}"
			(at -0.95 3.168 180)
			(layer "F.Fab")
			(effects
				(font
					(size 0.7 0.7)
					(thickness 0.15)
				)
				(justify left bottom)
			)
		)
		(pad "1" smd roundrect
			(at -0.48 0 180)
			(size 0.59 0.64)
			(layers "F.Cu" "F.Mask" "F.Paste")
			(roundrect_rratio 0.25)
			(net 347 "/Compute module/ExpanderINT")
			(pintype "passive")
		)
		(pad "2" smd roundrect
			(at 0.48 0 180)
			(size 0.59 0.64)
			(layers "F.Cu" "F.Mask" "F.Paste")
			(roundrect_rratio 0.25)
			(net 9 "+3V3")
			(pintype "passive")
		)
	)
	(footprint "antmicro-footprints:Nexperia_DFN-10_2.5x1mm_P0.5mm"
		(layer "F.Cu")
		(at 92.767962 121.309429)
		(property "Reference" "D901"
			(at -1.18 -0.702929 0)
			(layer "F.SilkS")
			(effects
				(font
					(size 0.7 0.7)
					(thickness 0.15)
				)
				(justify left bottom)
			)
		)
		(property "Value" "PUSB3F96X_PASS"
			(at -0.016 1.705 0)
			(layer "F.Fab")
			(effects
				(font
					(size 0.7 0.7)
					(thickness 0.15)
				)
				(justify left bottom)
			)
		)
		(property "Datasheet" "https://mouser.com/datasheet/2/916/PUSB3F96-1600324.pdf"
			(at 0 0 0)
			(layer "F.Fab")
			(hide yes)
			(effects
				(font
					(size 1.27 1.27)
					(thickness 0.15)
				)
			)
		)
		(property "Manufacturer" "Nexperia"
			(at 0 0 0)
			(unlocked yes)
			(layer "F.Fab")
			(hide yes)
			(effects
				(font
					(size 1 1)
					(thickness 0.15)
				)
			)
		)
		(property "MPN" "PUSB3F96X"
			(at 0 0 0)
			(unlocked yes)
			(layer "F.Fab")
			(hide yes)
			(effects
				(font
					(size 1 1)
					(thickness 0.15)
				)
			)
		)
		(property "Author" "Antmicro"
			(at 0 0 0)
			(unlocked yes)
			(layer "F.Fab")
			(hide yes)
			(effects
				(font
					(size 1 1)
					(thickness 0.15)
				)
			)
		)
		(property "License" "Apache-2.0"
			(at 0 0 0)
			(unlocked yes)
			(layer "F.Fab")
			(hide yes)
			(effects
				(font
					(size 1 1)
					(thickness 0.15)
				)
			)
		)
		(sheetname "/USB/")
		(sheetfile "usb.kicad_sch")
		(attr smd)
		(fp_line
			(start -1.375 -0.4)
			(end -1.375 0.4)
			(stroke
				(width 0.15)
				(type solid)
			)
			(layer "F.SilkS")
		)
		(fp_line
			(start 1.375 0.4)
			(end 1.375 -0.4)
			(stroke
				(width 0.15)
				(type solid)
			)
			(layer "F.SilkS")
		)
		(fp_circle
			(center -1.4 0.7)
			(end -1.349 0.7)
			(stroke
				(width 0.15)
				(type solid)
			)
			(fill yes)
			(layer "F.SilkS")
		)
		(fp_rect
			(start -1.4 -0.725)
			(end 1.4 0.725)
			(stroke
				(width 0.05)
				(type solid)
			)
			(fill no)
			(layer "F.CrtYd")
		)
		(fp_line
			(start -1.25 -0.5)
			(end -1.25 0.15)
			(stroke
				(width 0.15)
				(type solid)
			)
			(layer "F.Fab")
		)
		(fp_line
			(start -1.25 0.15)
			(end -0.9 0.5)
			(stroke
				(width 0.15)
				(type solid)
			)
			(layer "F.Fab")
		)
		(fp_line
			(start -0.9 0.5)
			(end 1.25 0.5)
			(stroke
				(width 0.15)
				(type solid)
			)
			(layer "F.Fab")
		)
		(fp_line
			(start 1.25 -0.5)
			(end -1.25 -0.5)
			(stroke
				(width 0.15)
				(type solid)
			)
			(layer "F.Fab")
		)
		(fp_line
			(start 1.25 0.5)
			(end 1.25 -0.5)
			(stroke
				(width 0.15)
				(type solid)
			)
			(layer "F.Fab")
		)
		(fp_text user "${REFERENCE}"
			(at -1.367 3.704 0)
			(layer "F.Fab")
			(effects
				(font
					(size 0.7 0.7)
					(thickness 0.15)
				)
				(justify left bottom)
			)
		)
		(fp_text user "Author: Antmicro"
			(at -1.367 4.905 0)
			(layer "F.Fab")
			(effects
				(font
					(size 0.7 0.7)
					(thickness 0.15)
				)
				(justify left bottom)
			)
		)
		(fp_text user "License: Apache-2.0"
			(at -1.367 6.105 0)
			(layer "F.Fab")
			(effects
				(font
					(size 0.7 0.7)
					(thickness 0.15)
				)
				(justify left bottom)
			)
		)
		(pad "1" smd rect
			(at -1 0.3875)
			(size 0.2 0.475)
			(layers "F.Cu" "F.Mask" "F.Paste")
			(net 203 "/USB/USBA_CC1")
			(pinfunction "CH1")
			(pintype "passive")
			(solder_mask_margin 0.05)
		)
		(pad "2" smd rect
			(at -0.5 0.3875)
			(size 0.2 0.475)
			(layers "F.Cu" "F.Mask" "F.Paste")
			(net 204 "/USB/USBA_CC2")
			(pinfunction "CH2")
			(pintype "passive")
			(solder_mask_margin 0.05)
		)
		(pad "3" smd rect
			(at 0 0.3875)
			(size 0.2 0.475)
			(layers "F.Cu" "F.Mask" "F.Paste")
			(net 3 "GND")
			(pinfunction "GND")
			(pintype "passive")
			(solder_mask_margin 0.05)
		)
		(pad "4" smd rect
			(at 0.5 0.3875)
			(size 0.2 0.475)
			(layers "F.Cu" "F.Mask" "F.Paste")
			(net 205 "/USB/AD_P")
			(pinfunction "CH3")
			(pintype "passive")
			(solder_mask_margin 0.05)
		)
		(pad "5" smd rect
			(at 1 0.3875)
			(size 0.2 0.475)
			(layers "F.Cu" "F.Mask" "F.Paste")
			(net 206 "/USB/AD_N")
			(pinfunction "CH4")
			(pintype "passive")
			(solder_mask_margin 0.05)
		)
		(pad "6" smd rect
			(at 1 -0.3875)
			(size 0.2 0.475)
			(layers "F.Cu" "F.Mask" "F.Paste")
			(net 206 "/USB/AD_N")
			(pinfunction "CH4")
			(pintype "passive")
			(solder_mask_margin 0.05)
		)
		(pad "7" smd rect
			(at 0.5 -0.3875)
			(size 0.2 0.475)
			(layers "F.Cu" "F.Mask" "F.Paste")
			(net 205 "/USB/AD_P")
			(pinfunction "CH3")
			(pintype "passive")
			(solder_mask_margin 0.05)
		)
		(pad "8" smd rect
			(at 0 -0.3875)
			(size 0.2 0.475)
			(layers "F.Cu" "F.Mask" "F.Paste")
			(net 3 "GND")
			(pinfunction "GND")
			(pintype "passive")
			(solder_mask_margin 0.05)
		)
		(pad "9" smd rect
			(at -0.501 -0.3875)
			(size 0.2 0.475)
			(layers "F.Cu" "F.Mask" "F.Paste")
			(net 204 "/USB/USBA_CC2")
			(pinfunction "CH2")
			(pintype "passive")
			(solder_mask_margin 0.05)
		)
		(pad "10" smd rect
			(at -1 -0.3875)
			(size 0.2 0.475)
			(layers "F.Cu" "F.Mask" "F.Paste")
			(net 203 "/USB/USBA_CC1")
			(pinfunction "CH1")
			(pintype "passive")
			(solder_mask_margin 0.05)
		)
	)
	(footprint "antmicro-footprints:SOT-523"
		(layer "B.Cu")
		(at 86.5 120.0895)
		(property "Reference" "Q906"
			(at 1.1 0.9 180)
			(layer "B.SilkS")
			(effects
				(font
					(size 0.7 0.7)
					(thickness 0.15)
				)
				(justify right bottom mirror)
			)
		)
		(property "Value" "PJE138K"
			(at 0.1 -1.824 0)
			(layer "B.Fab")
			(effects
				(font
					(size 0.7 0.7)
					(thickness 0.15)
				)
				(justify right bottom mirror)
			)
		)
		(property "Datasheet" "https://www.mouser.com/datasheet/2/1057/PJE138K-1876698.pdf"
			(at 0 0 0)
			(layer "B.Fab")
			(hide yes)
			(effects
				(font
					(size 1.27 1.27)
					(thickness 0.15)
				)
			)
		)
		(property "MPN" "PJE138K_R1_00001"
			(at 0 0 0)
			(unlocked yes)
			(layer "B.Fab")
			(hide yes)
			(effects
				(font
					(size 1 1)
					(thickness 0.15)
				)
				(justify mirror)
			)
		)
		(property "Manufacturer" "PANJIT"
			(at 0 0 0)
			(unlocked yes)
			(layer "B.Fab")
			(hide yes)
			(effects
				(font
					(size 1 1)
					(thickness 0.15)
				)
				(justify mirror)
			)
		)
		(property "Author" "Antmicro"
			(at 0 0 0)
			(unlocked yes)
			(layer "B.Fab")
			(hide yes)
			(effects
				(font
					(size 1 1)
					(thickness 0.15)
				)
				(justify mirror)
			)
		)
		(property "License" "Apache-2.0"
			(at 0 0 0)
			(unlocked yes)
			(layer "B.Fab")
			(hide yes)
			(effects
				(font
					(size 1 1)
					(thickness 0.15)
				)
				(justify mirror)
			)
		)
		(sheetname "/USB/")
		(sheetfile "usb.kicad_sch")
		(attr smd)
		(fp_line
			(start -0.927 0.051)
			(end -0.927 0.351)
			(stroke
				(width 0.15)
				(type solid)
			)
			(layer "B.SilkS")
		)
		(fp_line
			(start -0.927 0.351)
			(end -0.725 0.551)
			(stroke
				(width 0.15)
				(type solid)
			)
			(layer "B.SilkS")
		)
		(fp_line
			(start -0.725 0.551)
			(end -0.277 0.551)
			(stroke
				(width 0.15)
				(type solid)
			)
			(layer "B.SilkS")
		)
		(fp_line
			(start -0.277 0.551)
			(end -0.277 0.75)
			(stroke
				(width 0.15)
				(type solid)
			)
			(layer "B.SilkS")
		)
		(fp_circle
			(center -0.9652 -0.9652)
			(end -0.9152 -0.9652)
			(stroke
				(width 0.15)
				(type solid)
			)
			(fill yes)
			(layer "B.SilkS")
		)
		(fp_line
			(start -1.12 -1.15)
			(end 1.1 -1.15)
			(stroke
				(width 0.05)
				(type solid)
			)
			(layer "B.CrtYd")
		)
		(fp_line
			(start -1.12 1.16)
			(end -1.12 -1.15)
			(stroke
				(width 0.05)
				(type solid)
			)
			(layer "B.CrtYd")
		)
		(fp_line
			(start -1.12 1.16)
			(end 1.1 1.16)
			(stroke
				(width 0.05)
				(type solid)
			)
			(layer "B.CrtYd")
		)
		(fp_line
			(start 1.1 1.16)
			(end 1.1 -1.15)
			(stroke
				(width 0.05)
				(type solid)
			)
			(layer "B.CrtYd")
		)
		(fp_line
			(start -0.802 0.276)
			(end -0.802 -0.424)
			(stroke
				(width 0.15)
				(type solid)
			)
			(layer "B.Fab")
		)
		(fp_line
			(start -0.652 0.425)
			(end -0.802 0.276)
			(stroke
				(width 0.15)
				(type solid)
			)
			(layer "B.Fab")
		)
		(fp_line
			(start 0.8 -0.424)
			(end -0.802 -0.424)
			(stroke
				(width 0.15)
				(type solid)
			)
			(layer "B.Fab")
		)
		(fp_line
			(start 0.8 0.425)
			(end -0.652 0.425)
			(stroke
				(width 0.15)
				(type solid)
			)
			(layer "B.Fab")
		)
		(fp_line
			(start 0.8 0.425)
			(end 0.8 -0.424)
			(stroke
				(width 0.15)
				(type solid)
			)
			(layer "B.Fab")
		)
		(fp_circle
			(center -0.9652 -0.9652)
			(end -0.9144 -0.9652)
			(stroke
				(width 0.15)
				(type solid)
			)
			(fill no)
			(layer "B.Fab")
		)
		(fp_text user "Author: Antmicro"
			(at -1.12 -6.224 180)
			(layer "B.Fab")
			(effects
				(font
					(size 0.7 0.7)
					(thickness 0.15)
				)
				(justify left bottom mirror)
			)
		)
		(fp_text user "${REFERENCE}"
			(at -1.12 -3.824 180)
			(layer "B.Fab")
			(effects
				(font
					(size 0.7 0.7)
					(thickness 0.15)
				)
				(justify left bottom mirror)
			)
		)
		(fp_text user "License: Apache-2.0"
			(at -1.12 -5.024 180)
			(layer "B.Fab")
			(effects
				(font
					(size 0.7 0.7)
					(thickness 0.15)
				)
				(justify left bottom mirror)
			)
		)
		(pad "1" smd rect
			(at -0.5 -0.65)
			(size 0.4 0.51)
			(layers "B.Cu" "B.Mask" "B.Paste")
			(net 499 "Net-(Q906-G)")
			(pinfunction "G")
			(pintype "input")
		)
		(pad "2" smd rect
			(at 0.498 -0.65)
			(size 0.4 0.51)
			(layers "B.Cu" "B.Mask" "B.Paste")
			(net 3 "GND")
			(pinfunction "S")
			(pintype "passive")
		)
		(pad "3" smd rect
			(at 0 0.652)
			(size 0.4 0.51)
			(layers "B.Cu" "B.Mask" "B.Paste")
			(net 498 "Net-(D906-C)")
			(pinfunction "D")
			(pintype "passive")
		)
	)
	(footprint "antmicro-footprints:C_0402_1005Metric"
		(layer "B.Cu")
		(at 119.117962 134.2665 90)
		(descr "Capacitor SMD 0402")
		(tags "capacitor SMD 0402")
		(property "Reference" "C502"
			(at -3.57 0.45 90)
			(layer "B.SilkS")
			(effects
				(font
					(size 0.7 0.7)
					(thickness 0.15)
				)
				(justify right bottom mirror)
			)
		)
		(property "Value" "C_1u_0402"
			(at -1.022927 -2.155213 90)
			(layer "B.Fab")
			(effects
				(font
					(size 0.7 0.7)
					(thickness 0.15)
				)
				(justify right bottom mirror)
			)
		)
		(property "Datasheet" "https://product.tdk.com/en/search/capacitor/ceramic/mlcc/info?part_no=C1005X6S1A105K050BC"
			(at 0 0 90)
			(layer "B.Fab")
			(hide yes)
			(effects
				(font
					(size 1.27 1.27)
					(thickness 0.15)
				)
			)
		)
		(property "Manufacturer" "TDK"
			(at 0 0 90)
			(unlocked yes)
			(layer "B.Fab")
			(hide yes)
			(effects
				(font
					(size 1 1)
					(thickness 0.15)
				)
				(justify mirror)
			)
		)
		(property "MPN" "C1005X6S1A105K050BC"
			(at 0 0 90)
			(unlocked yes)
			(layer "B.Fab")
			(hide yes)
			(effects
				(font
					(size 1 1)
					(thickness 0.15)
				)
				(justify mirror)
			)
		)
		(property "Val" "1u"
			(at 0 0 90)
			(unlocked yes)
			(layer "B.Fab")
			(hide yes)
			(effects
				(font
					(size 1 1)
					(thickness 0.15)
				)
				(justify mirror)
			)
		)
		(property "License" "Apache-2.0"
			(at 0 0 90)
			(unlocked yes)
			(layer "B.Fab")
			(hide yes)
			(effects
				(font
					(size 1 1)
					(thickness 0.15)
				)
				(justify mirror)
			)
		)
		(property "Author" "Antmicro"
			(at 0 0 90)
			(unlocked yes)
			(layer "B.Fab")
			(hide yes)
			(effects
				(font
					(size 1 1)
					(thickness 0.15)
				)
				(justify mirror)
			)
		)
		(property "Voltage" ""
			(at 0 0 90)
			(unlocked yes)
			(layer "B.Fab")
			(hide yes)
			(effects
				(font
					(size 1 1)
					(thickness 0.15)
				)
				(justify mirror)
			)
		)
		(property "Dielectric" ""
			(at 0 0 90)
			(unlocked yes)
			(layer "B.Fab")
			(hide yes)
			(effects
				(font
					(size 1 1)
					(thickness 0.15)
				)
				(justify mirror)
			)
		)
		(sheetname "/NVMe & microSD/")
		(sheetfile "nvme-micro-sd.kicad_sch")
		(attr smd)
		(fp_rect
			(start -0.925 0.47)
			(end 0.925 -0.47)
			(stroke
				(width 0.05)
				(type default)
			)
			(fill no)
			(layer "B.CrtYd")
		)
		(fp_line
			(start 0.504 -0.248)
			(end -0.494 -0.248)
			(stroke
				(width 0.15)
				(type solid)
			)
			(layer "B.Fab")
		)
		(fp_line
			(start -0.494 -0.248)
			(end -0.494 0.25)
			(stroke
				(width 0.15)
				(type solid)
			)
			(layer "B.Fab")
		)
		(fp_line
			(start 0.504 0.25)
			(end 0.504 -0.248)
			(stroke
				(width 0.15)
				(type solid)
			)
			(layer "B.Fab")
		)
		(fp_line
			(start -0.494 0.25)
			(end 0.504 0.25)
			(stroke
				(width 0.15)
				(type solid)
			)
			(layer "B.Fab")
		)
		(fp_text user "${REFERENCE}"
			(at -0.939 -4.599 270)
			(layer "B.Fab")
			(effects
				(font
					(size 0.7 0.7)
					(thickness 0.15)
				)
				(justify left bottom mirror)
			)
		)
		(fp_text user "License: Apache-2.0"
			(at -0.939 -5.799 270)
			(layer "B.Fab")
			(effects
				(font
					(size 0.7 0.7)
					(thickness 0.15)
				)
				(justify left bottom mirror)
			)
		)
		(fp_text user "Author: Antmicro"
			(at -0.939 -3.399 270)
			(layer "B.Fab")
			(effects
				(font
					(size 0.7 0.7)
					(thickness 0.15)
				)
				(justify left bottom mirror)
			)
		)
		(pad "1" smd roundrect
			(at -0.48 0 90)
			(size 0.59 0.64)
			(layers "B.Cu" "B.Mask" "B.Paste")
			(roundrect_rratio 0.25)
			(net 3 "GND")
			(pintype "passive")
		)
		(pad "2" smd roundrect
			(at 0.48 0 90)
			(size 0.59 0.64)
			(layers "B.Cu" "B.Mask" "B.Paste")
			(roundrect_rratio 0.25)
			(net 65 "3V3_SSD")
			(pintype "passive")
		)
	)
	(footprint "antmicro-footprints:C_0805_2012Metric"
		(layer "B.Cu")
		(at 63.512962 166.0415 -90)
		(descr "Capacitor SMD 0805")
		(tags "capacitor SMD 0805")
		(property "Reference" "C306"
			(at -0.465 -1.795 90)
			(layer "B.SilkS")
			(effects
				(font
					(size 0.7 0.7)
					(thickness 0.15)
				)
				(justify left bottom mirror)
			)
		)
		(property "Value" "C_22u_25V_0805"
			(at -2.055717 -1.963152 90)
			(layer "B.Fab")
			(effects
				(font
					(size 0.7 0.7)
					(thickness 0.15)
				)
				(justify left bottom mirror)
			)
		)
		(property "Datasheet" "https://product.samsungsem.com/mlcc/CL21A226MAYNNN.do"
			(at 0 0 270)
			(layer "B.Fab")
			(hide yes)
			(effects
				(font
					(size 1.27 1.27)
					(thickness 0.15)
				)
			)
		)
		(property "Manufacturer" "Samsung Electro-Mechanics"
			(at 0 0 270)
			(unlocked yes)
			(layer "B.Fab")
			(hide yes)
			(effects
				(font
					(size 1 1)
					(thickness 0.15)
				)
				(justify mirror)
			)
		)
		(property "MPN" "CL21A226MAYNNNE"
			(at 0 0 270)
			(unlocked yes)
			(layer "B.Fab")
			(hide yes)
			(effects
				(font
					(size 1 1)
					(thickness 0.15)
				)
				(justify mirror)
			)
		)
		(property "Val" "22u"
			(at 0 0 270)
			(unlocked yes)
			(layer "B.Fab")
			(hide yes)
			(effects
				(font
					(size 1 1)
					(thickness 0.15)
				)
				(justify mirror)
			)
		)
		(property "License" "Apache-2.0"
			(at 0 0 270)
			(unlocked yes)
			(layer "B.Fab")
			(hide yes)
			(effects
				(font
					(size 1 1)
					(thickness 0.15)
				)
				(justify mirror)
			)
		)
		(property "Author" "Antmicro"
			(at 0 0 270)
			(unlocked yes)
			(layer "B.Fab")
			(hide yes)
			(effects
				(font
					(size 1 1)
					(thickness 0.15)
				)
				(justify mirror)
			)
		)
		(property "Voltage" "25V"
			(at 0 0 270)
			(unlocked yes)
			(layer "B.Fab")
			(hide yes)
			(effects
				(font
					(size 1 1)
					(thickness 0.15)
				)
				(justify mirror)
			)
		)
		(property "Dielectric" "X5R"
			(at 0 0 270)
			(unlocked yes)
			(layer "B.Fab")
			(hide yes)
			(effects
				(font
					(size 1 1)
					(thickness 0.15)
				)
				(justify mirror)
			)
		)
		(property "Public" "False"
			(at 0 0 270)
			(unlocked yes)
			(layer "B.Fab")
			(hide yes)
			(effects
				(font
					(size 1 1)
					(thickness 0.15)
				)
				(justify mirror)
			)
		)
		(sheetname "/Supply/")
		(sheetfile "supply.kicad_sch")
		(attr smd)
		(fp_line
			(start -0.3 0.7)
			(end 0.3 0.7)
			(stroke
				(width 0.15)
				(type solid)
			)
			(layer "B.SilkS")
		)
		(fp_line
			(start -0.3 -0.7)
			(end 0.3 -0.7)
			(stroke
				(width 0.15)
				(type solid)
			)
			(layer "B.SilkS")
		)
		(fp_rect
			(start 1.95 0.9)
			(end -1.95 -0.9)
			(stroke
				(width 0.05)
				(type default)
			)
			(fill no)
			(layer "B.CrtYd")
		)
		(fp_rect
			(start -0.95 0.675)
			(end 0.95 -0.675)
			(stroke
				(width 0.15)
				(type solid)
			)
			(fill no)
			(layer "B.Fab")
		)
		(fp_text user "License: Apache-2.0"
			(at -1.9 -4.947 90)
			(layer "B.Fab")
			(effects
				(font
					(size 0.7 0.7)
					(thickness 0.15)
				)
				(justify left bottom mirror)
			)
		)
		(fp_text user "Author: Antmicro"
			(at -1.9 -5.947 90)
			(layer "B.Fab")
			(effects
				(font
					(size 0.7 0.7)
					(thickness 0.15)
				)
				(justify left bottom mirror)
			)
		)
		(fp_text user "${REFERENCE}"
			(at -1.9 -3.947 90)
			(layer "B.Fab")
			(effects
				(font
					(size 0.7 0.7)
					(thickness 0.15)
				)
				(justify left bottom mirror)
			)
		)
		(pad "1" smd roundrect
			(at -1.1 0 270)
			(size 1.2 1.3)
			(layers "B.Cu" "B.Mask" "B.Paste")
			(roundrect_rratio 0.25)
			(net 43 "VCC")
			(pintype "passive")
		)
		(pad "2" smd roundrect
			(at 1.1 0 270)
			(size 1.2 1.3)
			(layers "B.Cu" "B.Mask" "B.Paste")
			(roundrect_rratio 0.25)
			(net 3 "GND")
			(pintype "passive")
		)
	)
	(footprint "antmicro-footprints:FB_0603_1608Metric"
		(layer "B.Cu")
		(at 101.167962 176.4965 180)
		(property "Reference" "FB702"
			(at -4.945 -0.295 0)
			(layer "B.SilkS")
			(effects
				(font
					(size 0.7 0.7)
					(thickness 0.15)
				)
				(justify left bottom mirror)
			)
		)
		(property "Value" "FB_220Z_2.2A_TDK-MPZ_0603"
			(at 0 -1.5 0)
			(layer "B.Fab")
			(effects
				(font
					(size 0.7 0.7)
					(thickness 0.15)
				)
				(justify left bottom mirror)
			)
		)
		(property "Datasheet" "https://product.tdk.com/info/en/catalog/datasheets/beads_commercial_power_mpz1608_en.pdf"
			(at 0 0 180)
			(layer "B.Fab")
			(hide yes)
			(effects
				(font
					(size 1.27 1.27)
					(thickness 0.15)
				)
			)
		)
		(property "MPN" "MPZ1608S221ATA00"
			(at 0 0 180)
			(unlocked yes)
			(layer "B.Fab")
			(hide yes)
			(effects
				(font
					(size 1 1)
					(thickness 0.15)
				)
				(justify mirror)
			)
		)
		(property "Manufacturer" "TDK"
			(at 0 0 180)
			(unlocked yes)
			(layer "B.Fab")
			(hide yes)
			(effects
				(font
					(size 1 1)
					(thickness 0.15)
				)
				(justify mirror)
			)
		)
		(property "Author" "Antmicro"
			(at 0 0 180)
			(unlocked yes)
			(layer "B.Fab")
			(hide yes)
			(effects
				(font
					(size 1 1)
					(thickness 0.15)
				)
				(justify mirror)
			)
		)
		(property "License" "Apache-2.0"
			(at 0 0 180)
			(unlocked yes)
			(layer "B.Fab")
			(hide yes)
			(effects
				(font
					(size 1 1)
					(thickness 0.15)
				)
				(justify mirror)
			)
		)
		(property "Val" "220Z/2.2A"
			(at 0 0 180)
			(unlocked yes)
			(layer "B.Fab")
			(hide yes)
			(effects
				(font
					(size 1 1)
					(thickness 0.15)
				)
				(justify mirror)
			)
		)
		(property "Current" ""
			(at 0 0 180)
			(unlocked yes)
			(layer "B.Fab")
			(hide yes)
			(effects
				(font
					(size 1 1)
					(thickness 0.15)
				)
				(justify mirror)
			)
		)
		(sheetname "/Display/")
		(sheetfile "display.kicad_sch")
		(attr smd)
		(fp_line
			(start -0.15 0.4)
			(end 0.15 0.4)
			(stroke
				(width 0.15)
				(type solid)
			)
			(layer "B.SilkS")
		)
		(fp_line
			(start -0.15 -0.4)
			(end 0.15 -0.4)
			(stroke
				(width 0.15)
				(type solid)
			)
			(layer "B.SilkS")
		)
		(fp_rect
			(start -1.25 0.65)
			(end 1.25 -0.65)
			(stroke
				(width 0.05)
				(type solid)
			)
			(fill no)
			(layer "B.CrtYd")
		)
		(fp_line
			(start 0.8 0.408)
			(end 0.8 -0.406)
			(stroke
				(width 0.15)
				(type solid)
			)
			(layer "B.Fab")
		)
		(fp_line
			(start 0.8 0.408)
			(end -0.803 0.408)
			(stroke
				(width 0.15)
				(type solid)
			)
			(layer "B.Fab")
		)
		(fp_line
			(start 0.8 -0.406)
			(end -0.803 -0.406)
			(stroke
				(width 0.15)
				(type solid)
			)
			(layer "B.Fab")
		)
		(fp_line
			(start -0.803 -0.406)
			(end -0.803 0.408)
			(stroke
				(width 0.15)
				(type solid)
			)
			(layer "B.Fab")
		)
		(fp_text user "License: Apache-2.0"
			(at -1.653 -5.9 0)
			(layer "B.Fab")
			(effects
				(font
					(size 0.7 0.7)
					(thickness 0.15)
				)
				(justify left bottom mirror)
			)
		)
		(fp_text user "${REFERENCE}"
			(at -1.653 -4.6 0)
			(layer "B.Fab")
			(effects
				(font
					(size 0.7 0.7)
					(thickness 0.15)
				)
				(justify left bottom mirror)
			)
		)
		(fp_text user "Author: Antmicro"
			(at -1.653 -3.162 0)
			(layer "B.Fab")
			(effects
				(font
					(size 0.7 0.7)
					(thickness 0.15)
				)
				(justify left bottom mirror)
			)
		)
		(pad "1" smd roundrect
			(at -0.7 0 180)
			(size 0.8 1)
			(layers "B.Cu" "B.Mask" "B.Paste")
			(roundrect_rratio 0.2)
			(net 10 "+5V")
			(pintype "passive")
		)
		(pad "2" smd roundrect
			(at 0.7 0 180)
			(size 0.8 1)
			(layers "B.Cu" "B.Mask" "B.Paste")
			(roundrect_rratio 0.2)
			(net 464 "Net-(D709-C)")
			(pintype "passive")
		)
	)
	(footprint "antmicro-footprints:SOD-523"
		(layer "B.Cu")
		(at 98.342962 176.8415 -90)
		(property "Reference" "D709"
			(at 0.065 -2.515 90)
			(layer "B.SilkS")
			(effects
				(font
					(size 0.7 0.7)
					(thickness 0.15)
				)
				(justify left bottom mirror)
			)
		)
		(property "Value" "PESD5Z5_0F"
			(at 0 -1.499 90)
			(layer "B.Fab")
			(effects
				(font
					(size 0.7 0.7)
					(thickness 0.15)
				)
				(justify left bottom mirror)
			)
		)
		(property "Datasheet" "https://assets.nexperia.com/documents/data-sheet/PESD5Z5_0.pdf"
			(at 0 0 270)
			(layer "B.Fab")
			(hide yes)
			(effects
				(font
					(size 1.27 1.27)
					(thickness 0.15)
				)
			)
		)
		(property "Manufacturer" "Nexperia"
			(at 0 0 270)
			(unlocked yes)
			(layer "B.Fab")
			(hide yes)
			(effects
				(font
					(size 1 1)
					(thickness 0.15)
				)
				(justify mirror)
			)
		)
		(property "MPN" "PESD5Z5.0F"
			(at 0 0 270)
			(unlocked yes)
			(layer "B.Fab")
			(hide yes)
			(effects
				(font
					(size 1 1)
					(thickness 0.15)
				)
				(justify mirror)
			)
		)
		(property "Author" "Antmicro"
			(at 0 0 270)
			(unlocked yes)
			(layer "B.Fab")
			(hide yes)
			(effects
				(font
					(size 1 1)
					(thickness 0.15)
				)
				(justify mirror)
			)
		)
		(property "License" "Apache-2.0"
			(at 0 0 270)
			(unlocked yes)
			(layer "B.Fab")
			(hide yes)
			(effects
				(font
					(size 1 1)
					(thickness 0.15)
				)
				(justify mirror)
			)
		)
		(sheetname "/Display/")
		(sheetfile "display.kicad_sch")
		(attr smd)
		(fp_line
			(start -0.35 0.5)
			(end -0.35 -0.5)
			(stroke
				(width 0.15)
				(type solid)
			)
			(layer "B.SilkS")
		)
		(fp_rect
			(start -1 0.6)
			(end 1 -0.6)
			(stroke
				(width 0.05)
				(type solid)
			)
			(fill no)
			(layer "B.CrtYd")
		)
		(fp_line
			(start -0.652 0.425)
			(end 0.65 0.425)
			(stroke
				(width 0.15)
				(type solid)
			)
			(layer "B.Fab")
		)
		(fp_line
			(start 0.65 0.425)
			(end 0.65 -0.423)
			(stroke
				(width 0.15)
				(type solid)
			)
			(layer "B.Fab")
		)
		(fp_line
			(start -0.35 0.4)
			(end -0.35 -0.4)
			(stroke
				(width 0.15)
				(type solid)
			)
			(layer "B.Fab")
		)
		(fp_line
			(start -0.652 -0.423)
			(end -0.652 0.425)
			(stroke
				(width 0.15)
				(type solid)
			)
			(layer "B.Fab")
		)
		(fp_line
			(start -0.652 -0.423)
			(end 0.65 -0.423)
			(stroke
				(width 0.15)
				(type solid)
			)
			(layer "B.Fab")
		)
		(fp_text user "${REFERENCE}"
			(at -1.276 -3.499 90)
			(layer "B.Fab")
			(effects
				(font
					(size 0.7 0.7)
					(thickness 0.15)
				)
				(justify left bottom mirror)
			)
		)
		(fp_text user "License: Apache-2.0"
			(at -1.276 -5.9 90)
			(layer "B.Fab")
			(effects
				(font
					(size 0.7 0.7)
					(thickness 0.15)
				)
				(justify left bottom mirror)
			)
		)
		(fp_text user "Author: Antmicro"
			(at -1.276 -4.7 90)
			(layer "B.Fab")
			(effects
				(font
					(size 0.7 0.7)
					(thickness 0.15)
				)
				(justify left bottom mirror)
			)
		)
		(pad "1" smd roundrect
			(at -0.701 0 270)
			(size 0.5 0.6)
			(layers "B.Cu" "B.Mask" "B.Paste")
			(roundrect_rratio 0.25)
			(net 464 "Net-(D709-C)")
			(pinfunction "C")
			(pintype "passive")
		)
		(pad "2" smd roundrect
			(at 0.699 0 270)
			(size 0.5 0.6)
			(layers "B.Cu" "B.Mask" "B.Paste")
			(roundrect_rratio 0.25)
			(net 3 "GND")
			(pinfunction "A")
			(pintype "passive")
		)
	)
	(footprint "antmicro-footprints:R_0402_1005Metric"
		(layer "B.Cu")
		(at 65.242962 175.2915 180)
		(descr "Resistor SMD 0402")
		(tags "resistor SMD 0402")
		(property "Reference" "R808"
			(at -1.507038 1.2915 0)
			(layer "B.SilkS")
			(effects
				(font
					(size 0.7 0.7)
					(thickness 0.15)
				)
				(justify left top mirror)
			)
		)
		(property "Value" "R_2k2_0402"
			(at -1.011843 -1.772046 0)
			(layer "B.Fab")
			(effects
				(font
					(size 0.7 0.7)
					(thickness 0.15)
				)
				(justify left top mirror)
			)
		)
		(property "Datasheet" "https://www.bourns.com/docs/product-datasheets/cr.pdf"
			(at 0 0 0)
			(layer "B.Fab")
			(hide yes)
			(effects
				(font
					(size 1.27 1.27)
					(thickness 0.15)
				)
			)
		)
		(property "Description" "SMD Chip Resistor, 2.2 kohm, ± 1%, 62.5 mW, 0402 [1005 Metric], Thick Film, General Purpose"
			(at 0 0 0)
			(layer "B.Fab")
			(hide yes)
			(effects
				(font
					(size 1.27 1.27)
					(thickness 0.15)
				)
			)
		)
		(property "MPN" "CR0402-FX-2201GLF"
			(at 0 0 180)
			(unlocked yes)
			(layer "B.Fab")
			(hide yes)
			(effects
				(font
					(size 1 1)
					(thickness 0.15)
				)
				(justify mirror)
			)
		)
		(property "Manufacturer" "Bourns"
			(at 0 0 180)
			(unlocked yes)
			(layer "B.Fab")
			(hide yes)
			(effects
				(font
					(size 1 1)
					(thickness 0.15)
				)
				(justify mirror)
			)
		)
		(property "License" "Apache-2.0"
			(at 0 0 180)
			(unlocked yes)
			(layer "B.Fab")
			(hide yes)
			(effects
				(font
					(size 1 1)
					(thickness 0.15)
				)
				(justify mirror)
			)
		)
		(property "Author" "Antmicro"
			(at 0 0 180)
			(unlocked yes)
			(layer "B.Fab")
			(hide yes)
			(effects
				(font
					(size 1 1)
					(thickness 0.15)
				)
				(justify mirror)
			)
		)
		(property "Val" "2k2"
			(at 0 0 180)
			(unlocked yes)
			(layer "B.Fab")
			(hide yes)
			(effects
				(font
					(size 1 1)
					(thickness 0.15)
				)
				(justify mirror)
			)
		)
		(property "Tolerance" "1%"
			(at 0 0 180)
			(unlocked yes)
			(layer "B.Fab")
			(hide yes)
			(effects
				(font
					(size 1 1)
					(thickness 0.15)
				)
				(justify mirror)
			)
		)
		(sheetname "/Peripherals/")
		(sheetfile "peripherals.kicad_sch")
		(attr smd)
		(fp_poly
			(pts
				(xy -0.925 0.47) (xy 0.925 0.47) (xy 0.925 -0.47) (xy -0.925 -0.47)
			)
			(stroke
				(width 0.05)
				(type default)
			)
			(fill no)
			(layer "B.CrtYd")
		)
		(fp_poly
			(pts
				(xy -0.5 0.25) (xy 0.5 0.25) (xy 0.5 -0.25) (xy -0.5 -0.25)
			)
			(stroke
				(width 0.15)
				(type solid)
			)
			(fill no)
			(layer "B.Fab")
		)
		(fp_text user "License: Apache-2.0"
			(at -0.949999 -5.169 0)
			(layer "B.Fab")
			(effects
				(font
					(size 0.7 0.7)
					(thickness 0.15)
				)
				(justify left bottom mirror)
			)
		)
		(fp_text user "${REFERENCE}"
			(at -0.95 -3.168 0)
			(layer "B.Fab")
			(effects
				(font
					(size 0.7 0.7)
					(thickness 0.15)
				)
				(justify left bottom mirror)
			)
		)
		(fp_text user "Author: Antmicro"
			(at -0.95 -4.169 0)
			(layer "B.Fab")
			(effects
				(font
					(size 0.7 0.7)
					(thickness 0.15)
				)
				(justify left bottom mirror)
			)
		)
		(pad "1" smd roundrect
			(at -0.48 0 180)
			(size 0.59 0.64)
			(layers "B.Cu" "B.Mask" "B.Paste")
			(roundrect_rratio 0.25)
			(net 104 "Net-(C813-Pad2)")
			(pintype "passive")
		)
		(pad "2" smd roundrect
			(at 0.48 0 180)
			(size 0.59 0.64)
			(layers "B.Cu" "B.Mask" "B.Paste")
			(roundrect_rratio 0.25)
			(net 110 "Net-(C817-Pad1)")
			(pintype "passive")
		)
	)
	(footprint "antmicro-footprints:R_0402_1005Metric"
		(layer "B.Cu")
		(at 87.267962 163.7565)
		(descr "Resistor SMD 0402")
		(tags "resistor SMD 0402")
		(property "Reference" "R206"
			(at -1.77 -0.67 0)
			(layer "B.SilkS")
			(effects
				(font
					(size 0.7 0.7)
					(thickness 0.15)
				)
				(justify right bottom mirror)
			)
		)
		(property "Value" "R_0R_0402"
			(at -1.011843 -1.772047 0)
			(layer "B.Fab")
			(effects
				(font
					(size 0.7 0.7)
					(thickness 0.15)
				)
				(justify right bottom mirror)
			)
		)
		(property "Datasheet" "https://industrial.panasonic.com/cdbs/www-data/pdf/RDA0000/AOA0000C301.pdf"
			(at 0 0 0)
			(layer "B.Fab")
			(hide yes)
			(effects
				(font
					(size 1.27 1.27)
					(thickness 0.15)
				)
			)
		)
		(property "Manufacturer" "Panasonic"
			(at 0 0 0)
			(unlocked yes)
			(layer "B.Fab")
			(hide yes)
			(effects
				(font
					(size 1 1)
					(thickness 0.15)
				)
				(justify mirror)
			)
		)
		(property "MPN" "ERJ2GE0R00X"
			(at 0 0 0)
			(unlocked yes)
			(layer "B.Fab")
			(hide yes)
			(effects
				(font
					(size 1 1)
					(thickness 0.15)
				)
				(justify mirror)
			)
		)
		(property "Val" "0R"
			(at 0 0 0)
			(unlocked yes)
			(layer "B.Fab")
			(hide yes)
			(effects
				(font
					(size 1 1)
					(thickness 0.15)
				)
				(justify mirror)
			)
		)
		(property "License" "Apache-2.0"
			(at 0 0 0)
			(unlocked yes)
			(layer "B.Fab")
			(hide yes)
			(effects
				(font
					(size 1 1)
					(thickness 0.15)
				)
				(justify mirror)
			)
		)
		(property "Author" "Antmicro"
			(at 0 0 0)
			(unlocked yes)
			(layer "B.Fab")
			(hide yes)
			(effects
				(font
					(size 1 1)
					(thickness 0.15)
				)
				(justify mirror)
			)
		)
		(property "Tolerance" "~"
			(at 0 0 0)
			(unlocked yes)
			(layer "B.Fab")
			(hide yes)
			(effects
				(font
					(size 1 1)
					(thickness 0.15)
				)
				(justify mirror)
			)
		)
		(property "Current" "1A"
			(at 0 0 0)
			(unlocked yes)
			(layer "B.Fab")
			(hide yes)
			(effects
				(font
					(size 1 1)
					(thickness 0.15)
				)
				(justify mirror)
			)
		)
		(sheetname "/Compute module/")
		(sheetfile "compute-module.kicad_sch")
		(attr smd exclude_from_pos_files exclude_from_bom dnp)
		(fp_rect
			(start -0.925 0.47)
			(end 0.925 -0.47)
			(stroke
				(width 0.05)
				(type default)
			)
			(fill no)
			(layer "B.CrtYd")
		)
		(fp_rect
			(start -0.5 0.25)
			(end 0.5 -0.25)
			(stroke
				(width 0.15)
				(type solid)
			)
			(fill no)
			(layer "B.Fab")
		)
		(fp_text user "License: Apache-2.0"
			(at -0.95 -5.169 180)
			(layer "B.Fab")
			(effects
				(font
					(size 0.7 0.7)
					(thickness 0.15)
				)
				(justify left bottom mirror)
			)
		)
		(fp_text user "${REFERENCE}"
			(at -0.95 -3.168 180)
			(layer "B.Fab")
			(effects
				(font
					(size 0.7 0.7)
					(thickness 0.15)
				)
				(justify left bottom mirror)
			)
		)
		(fp_text user "Author: Antmicro"
			(at -0.95 -4.169 180)
			(layer "B.Fab")
			(effects
				(font
					(size 0.7 0.7)
					(thickness 0.15)
				)
				(justify left bottom mirror)
			)
		)
		(pad "1" smd roundrect
			(at -0.48 0)
			(size 0.59 0.64)
			(layers "B.Cu" "B.Mask" "B.Paste")
			(roundrect_rratio 0.25)
			(net 130 "Net-(J201-Pad76)")
			(pintype "passive")
		)
		(pad "2" smd roundrect
			(at 0.48 0)
			(size 0.59 0.64)
			(layers "B.Cu" "B.Mask" "B.Paste")
			(roundrect_rratio 0.25)
			(net 118 "/Compute module/SDIO.CD")
			(pintype "passive")
		)
	)
	(footprint "antmicro-footprints:C_0402_1005Metric"
		(layer "B.Cu")
		(at 112.967962 131.9865 180)
		(descr "Capacitor SMD 0402")
		(tags "capacitor SMD 0402")
		(property "Reference" "C308"
			(at -3.53 -0.395 0)
			(layer "B.SilkS")
			(effects
				(font
					(size 0.7 0.7)
					(thickness 0.15)
				)
				(justify left bottom mirror)
			)
		)
		(property "Value" "C_100n_0402"
			(at -1.022927 -2.155213 0)
			(layer "B.Fab")
			(effects
				(font
					(size 0.7 0.7)
					(thickness 0.15)
				)
				(justify left bottom mirror)
			)
		)
		(property "Datasheet" "https://www.murata.com/products/productdetail?partno=GRM155R61H104KE14%23"
			(at 0 0 180)
			(layer "B.Fab")
			(hide yes)
			(effects
				(font
					(size 1.27 1.27)
					(thickness 0.15)
				)
			)
		)
		(property "Manufacturer" "Murata"
			(at 0 0 180)
			(unlocked yes)
			(layer "B.Fab")
			(hide yes)
			(effects
				(font
					(size 1 1)
					(thickness 0.15)
				)
				(justify mirror)
			)
		)
		(property "MPN" "GRM155R61H104KE14D"
			(at 0 0 180)
			(unlocked yes)
			(layer "B.Fab")
			(hide yes)
			(effects
				(font
					(size 1 1)
					(thickness 0.15)
				)
				(justify mirror)
			)
		)
		(property "Val" "100n"
			(at 0 0 180)
			(unlocked yes)
			(layer "B.Fab")
			(hide yes)
			(effects
				(font
					(size 1 1)
					(thickness 0.15)
				)
				(justify mirror)
			)
		)
		(property "License" "Apache-2.0"
			(at 0 0 180)
			(unlocked yes)
			(layer "B.Fab")
			(hide yes)
			(effects
				(font
					(size 1 1)
					(thickness 0.15)
				)
				(justify mirror)
			)
		)
		(property "Author" "Antmicro"
			(at 0 0 180)
			(unlocked yes)
			(layer "B.Fab")
			(hide yes)
			(effects
				(font
					(size 1 1)
					(thickness 0.15)
				)
				(justify mirror)
			)
		)
		(property "Voltage" "50V"
			(at 0 0 180)
			(unlocked yes)
			(layer "B.Fab")
			(hide yes)
			(effects
				(font
					(size 1 1)
					(thickness 0.15)
				)
				(justify mirror)
			)
		)
		(property "Dielectric" "X5R"
			(at 0 0 180)
			(unlocked yes)
			(layer "B.Fab")
			(hide yes)
			(effects
				(font
					(size 1 1)
					(thickness 0.15)
				)
				(justify mirror)
			)
		)
		(sheetname "/Supply/")
		(sheetfile "supply.kicad_sch")
		(attr smd)
		(fp_rect
			(start -0.925 0.47)
			(end 0.925 -0.47)
			(stroke
				(width 0.05)
				(type default)
			)
			(fill no)
			(layer "B.CrtYd")
		)
		(fp_line
			(start 0.504 0.25)
			(end 0.504 -0.248)
			(stroke
				(width 0.15)
				(type solid)
			)
			(layer "B.Fab")
		)
		(fp_line
			(start 0.504 -0.248)
			(end -0.494 -0.248)
			(stroke
				(width 0.15)
				(type solid)
			)
			(layer "B.Fab")
		)
		(fp_line
			(start -0.494 0.25)
			(end 0.504 0.25)
			(stroke
				(width 0.15)
				(type solid)
			)
			(layer "B.Fab")
		)
		(fp_line
			(start -0.494 -0.248)
			(end -0.494 0.25)
			(stroke
				(width 0.15)
				(type solid)
			)
			(layer "B.Fab")
		)
		(fp_text user "Author: Antmicro"
			(at -0.939 -3.399 0)
			(layer "B.Fab")
			(effects
				(font
					(size 0.7 0.7)
					(thickness 0.15)
				)
				(justify left bottom mirror)
			)
		)
		(fp_text user "${REFERENCE}"
			(at -0.939 -4.599 0)
			(layer "B.Fab")
			(effects
				(font
					(size 0.7 0.7)
					(thickness 0.15)
				)
				(justify left bottom mirror)
			)
		)
		(fp_text user "License: Apache-2.0"
			(at -0.939 -5.799 0)
			(layer "B.Fab")
			(effects
				(font
					(size 0.7 0.7)
					(thickness 0.15)
				)
				(justify left bottom mirror)
			)
		)
		(pad "1" smd roundrect
			(at -0.48 0 180)
			(size 0.59 0.64)
			(layers "B.Cu" "B.Mask" "B.Paste")
			(roundrect_rratio 0.25)
			(net 45 "/Supply/SW_M2")
			(pintype "passive")
		)
		(pad "2" smd roundrect
			(at 0.48 0 180)
			(size 0.59 0.64)
			(layers "B.Cu" "B.Mask" "B.Paste")
			(roundrect_rratio 0.25)
			(net 48 "Net-(U301-BST)")
			(pintype "passive")
		)
	)
	(footprint "antmicro-footprints:SOD-523"
		(layer "B.Cu")
		(at 135.717962 148.6665 -90)
		(property "Reference" "D604"
			(at 1 -0.47 90)
			(layer "B.SilkS")
			(effects
				(font
					(size 0.7 0.7)
					(thickness 0.15)
				)
				(justify left bottom mirror)
			)
		)
		(property "Value" "PESD5Z5_0F"
			(at 0 -1.499 90)
			(layer "B.Fab")
			(effects
				(font
					(size 0.7 0.7)
					(thickness 0.15)
				)
				(justify left bottom mirror)
			)
		)
		(property "Datasheet" "https://assets.nexperia.com/documents/data-sheet/PESD5Z5_0.pdf"
			(at 0 0 270)
			(layer "B.Fab")
			(hide yes)
			(effects
				(font
					(size 1.27 1.27)
					(thickness 0.15)
				)
			)
		)
		(property "Manufacturer" "Nexperia"
			(at 0 0 270)
			(unlocked yes)
			(layer "B.Fab")
			(hide yes)
			(effects
				(font
					(size 1 1)
					(thickness 0.15)
				)
				(justify mirror)
			)
		)
		(property "MPN" "PESD5Z5.0F"
			(at 0 0 270)
			(unlocked yes)
			(layer "B.Fab")
			(hide yes)
			(effects
				(font
					(size 1 1)
					(thickness 0.15)
				)
				(justify mirror)
			)
		)
		(property "Author" "Antmicro"
			(at 0 0 270)
			(unlocked yes)
			(layer "B.Fab")
			(hide yes)
			(effects
				(font
					(size 1 1)
					(thickness 0.15)
				)
				(justify mirror)
			)
		)
		(property "License" "Apache-2.0"
			(at 0 0 270)
			(unlocked yes)
			(layer "B.Fab")
			(hide yes)
			(effects
				(font
					(size 1 1)
					(thickness 0.15)
				)
				(justify mirror)
			)
		)
		(sheetname "/CSI/")
		(sheetfile "csi.kicad_sch")
		(attr smd)
		(fp_line
			(start -0.35 0.5)
			(end -0.35 -0.5)
			(stroke
				(width 0.15)
				(type solid)
			)
			(layer "B.SilkS")
		)
		(fp_rect
			(start -1 0.6)
			(end 1 -0.6)
			(stroke
				(width 0.05)
				(type solid)
			)
			(fill no)
			(layer "B.CrtYd")
		)
		(fp_line
			(start -0.652 0.425)
			(end 0.65 0.425)
			(stroke
				(width 0.15)
				(type solid)
			)
			(layer "B.Fab")
		)
		(fp_line
			(start 0.65 0.425)
			(end 0.65 -0.423)
			(stroke
				(width 0.15)
				(type solid)
			)
			(layer "B.Fab")
		)
		(fp_line
			(start -0.35 0.4)
			(end -0.35 -0.4)
			(stroke
				(width 0.15)
				(type solid)
			)
			(layer "B.Fab")
		)
		(fp_line
			(start -0.652 -0.423)
			(end -0.652 0.425)
			(stroke
				(width 0.15)
				(type solid)
			)
			(layer "B.Fab")
		)
		(fp_line
			(start -0.652 -0.423)
			(end 0.65 -0.423)
			(stroke
				(width 0.15)
				(type solid)
			)
			(layer "B.Fab")
		)
		(fp_text user "License: Apache-2.0"
			(at -1.276 -5.9 90)
			(layer "B.Fab")
			(effects
				(font
					(size 0.7 0.7)
					(thickness 0.15)
				)
				(justify left bottom mirror)
			)
		)
		(fp_text user "Author: Antmicro"
			(at -1.276 -4.7 90)
			(layer "B.Fab")
			(effects
				(font
					(size 0.7 0.7)
					(thickness 0.15)
				)
				(justify left bottom mirror)
			)
		)
		(fp_text user "${REFERENCE}"
			(at -1.276 -3.499 90)
			(layer "B.Fab")
			(effects
				(font
					(size 0.7 0.7)
					(thickness 0.15)
				)
				(justify left bottom mirror)
			)
		)
		(pad "1" smd roundrect
			(at -0.701 0 270)
			(size 0.5 0.6)
			(layers "B.Cu" "B.Mask" "B.Paste")
			(roundrect_rratio 0.25)
			(net 20 "/CSI/CSI_5V")
			(pinfunction "C")
			(pintype "passive")
		)
		(pad "2" smd roundrect
			(at 0.699 0 270)
			(size 0.5 0.6)
			(layers "B.Cu" "B.Mask" "B.Paste")
			(roundrect_rratio 0.25)
			(net 3 "GND")
			(pinfunction "A")
			(pintype "passive")
		)
	)
	(footprint "antmicro-footprints:Nexperia_DFN-10_2.5x1mm_P0.5mm"
		(layer "B.Cu")
		(at 89.505962 175.1915 90)
		(property "Reference" "D701"
			(at -1.198 -1.908 90)
			(layer "B.SilkS")
			(effects
				(font
					(size 0.7 0.7)
					(thickness 0.15)
				)
				(justify right bottom mirror)
			)
		)
		(property "Value" "PUSB3F96X_PASS"
			(at -0.016 -1.705 90)
			(layer "B.Fab")
			(effects
				(font
					(size 0.7 0.7)
					(thickness 0.15)
				)
				(justify right bottom mirror)
			)
		)
		(property "Datasheet" "https://mouser.com/datasheet/2/916/PUSB3F96-1600324.pdf"
			(at 0 0 90)
			(layer "B.Fab")
			(hide yes)
			(effects
				(font
					(size 1.27 1.27)
					(thickness 0.15)
				)
			)
		)
		(property "Manufacturer" "Nexperia"
			(at 0 0 90)
			(unlocked yes)
			(layer "B.Fab")
			(hide yes)
			(effects
				(font
					(size 1 1)
					(thickness 0.15)
				)
				(justify mirror)
			)
		)
		(property "MPN" "PUSB3F96X"
			(at 0 0 90)
			(unlocked yes)
			(layer "B.Fab")
			(hide yes)
			(effects
				(font
					(size 1 1)
					(thickness 0.15)
				)
				(justify mirror)
			)
		)
		(property "Author" "Antmicro"
			(at 0 0 90)
			(unlocked yes)
			(layer "B.Fab")
			(hide yes)
			(effects
				(font
					(size 1 1)
					(thickness 0.15)
				)
				(justify mirror)
			)
		)
		(property "License" "Apache-2.0"
			(at 0 0 90)
			(unlocked yes)
			(layer "B.Fab")
			(hide yes)
			(effects
				(font
					(size 1 1)
					(thickness 0.15)
				)
				(justify mirror)
			)
		)
		(sheetname "/Display/")
		(sheetfile "display.kicad_sch")
		(attr smd)
		(fp_line
			(start 1.375 -0.4)
			(end 1.375 0.4)
			(stroke
				(width 0.15)
				(type solid)
			)
			(layer "B.SilkS")
		)
		(fp_line
			(start -1.375 0.4)
			(end -1.375 -0.4)
			(stroke
				(width 0.15)
				(type solid)
			)
			(layer "B.SilkS")
		)
		(fp_circle
			(center -1.4 -0.7)
			(end -1.349 -0.7)
			(stroke
				(width 0.15)
				(type solid)
			)
			(fill yes)
			(layer "B.SilkS")
		)
		(fp_rect
			(start -1.4 0.725)
			(end 1.4 -0.725)
			(stroke
				(width 0.05)
				(type solid)
			)
			(fill no)
			(layer "B.CrtYd")
		)
		(fp_line
			(start 1.25 -0.5)
			(end 1.25 0.5)
			(stroke
				(width 0.15)
				(type solid)
			)
			(layer "B.Fab")
		)
		(fp_line
			(start -0.9 -0.5)
			(end 1.25 -0.5)
			(stroke
				(width 0.15)
				(type solid)
			)
			(layer "B.Fab")
		)
		(fp_line
			(start -1.25 -0.15)
			(end -0.9 -0.5)
			(stroke
				(width 0.15)
				(type solid)
			)
			(layer "B.Fab")
		)
		(fp_line
			(start 1.25 0.5)
			(end -1.25 0.5)
			(stroke
				(width 0.15)
				(type solid)
			)
			(layer "B.Fab")
		)
		(fp_line
			(start -1.25 0.5)
			(end -1.25 -0.15)
			(stroke
				(width 0.15)
				(type solid)
			)
			(layer "B.Fab")
		)
		(fp_text user "License: Apache-2.0"
			(at -1.367 -6.105 270)
			(layer "B.Fab")
			(effects
				(font
					(size 0.7 0.7)
					(thickness 0.15)
				)
				(justify left bottom mirror)
			)
		)
		(fp_text user "${REFERENCE}"
			(at -1.367 -3.704 270)
			(layer "B.Fab")
			(effects
				(font
					(size 0.7 0.7)
					(thickness 0.15)
				)
				(justify left bottom mirror)
			)
		)
		(fp_text user "Author: Antmicro"
			(at -1.367 -4.905 270)
			(layer "B.Fab")
			(effects
				(font
					(size 0.7 0.7)
					(thickness 0.15)
				)
				(justify left bottom mirror)
			)
		)
		(pad "1" smd rect
			(at -1 -0.3875 90)
			(size 0.2 0.475)
			(layers "B.Cu" "B.Mask" "B.Paste")
			(net 96 "/Compute module/DSI.D3_N")
			(pinfunction "CH1")
			(pintype "passive")
			(solder_mask_margin 0.05)
		)
		(pad "2" smd rect
			(at -0.5 -0.3875 90)
			(size 0.2 0.475)
			(layers "B.Cu" "B.Mask" "B.Paste")
			(net 98 "/Compute module/DSI.D3_P")
			(pinfunction "CH2")
			(pintype "passive")
			(solder_mask_margin 0.05)
		)
		(pad "3" smd rect
			(at 0 -0.3875 90)
			(size 0.2 0.475)
			(layers "B.Cu" "B.Mask" "B.Paste")
			(net 3 "GND")
			(pinfunction "GND")
			(pintype "passive")
			(solder_mask_margin 0.05)
		)
		(pad "4" smd rect
			(at 0.5 -0.3875 90)
			(size 0.2 0.475)
			(layers "B.Cu" "B.Mask" "B.Paste")
			(net 87 "/Compute module/DSI.D2_N")
			(pinfunction "CH3")
			(pintype "passive")
			(solder_mask_margin 0.05)
		)
		(pad "5" smd rect
			(at 1 -0.3875 90)
			(size 0.2 0.475)
			(layers "B.Cu" "B.Mask" "B.Paste")
			(net 97 "/Compute module/DSI.D2_P")
			(pinfunction "CH4")
			(pintype "passive")
			(solder_mask_margin 0.05)
		)
		(pad "6" smd rect
			(at 1 0.3875 90)
			(size 0.2 0.475)
			(layers "B.Cu" "B.Mask" "B.Paste")
			(net 97 "/Compute module/DSI.D2_P")
			(pinfunction "CH4")
			(pintype "passive")
			(solder_mask_margin 0.05)
		)
		(pad "7" smd rect
			(at 0.5 0.3875 90)
			(size 0.2 0.475)
			(layers "B.Cu" "B.Mask" "B.Paste")
			(net 87 "/Compute module/DSI.D2_N")
			(pinfunction "CH3")
			(pintype "passive")
			(solder_mask_margin 0.05)
		)
		(pad "8" smd rect
			(at 0 0.3875 90)
			(size 0.2 0.475)
			(layers "B.Cu" "B.Mask" "B.Paste")
			(net 3 "GND")
			(pinfunction "GND")
			(pintype "passive")
			(solder_mask_margin 0.05)
		)
		(pad "9" smd rect
			(at -0.501 0.3875 90)
			(size 0.2 0.475)
			(layers "B.Cu" "B.Mask" "B.Paste")
			(net 98 "/Compute module/DSI.D3_P")
			(pinfunction "CH2")
			(pintype "passive")
			(solder_mask_margin 0.05)
		)
		(pad "10" smd rect
			(at -1 0.3875 90)
			(size 0.2 0.475)
			(layers "B.Cu" "B.Mask" "B.Paste")
			(net 96 "/Compute module/DSI.D3_N")
			(pinfunction "CH1")
			(pintype "passive")
			(solder_mask_margin 0.05)
		)
	)
	(footprint "antmicro-footprints:L_Bourns-SRP3212A"
		(layer "B.Cu")
		(at 69.512962 164.7115 -90)
		(property "Reference" "L302"
			(at 2.435 -1.875 90)
			(layer "B.SilkS")
			(effects
				(font
					(size 0.7 0.7)
					(thickness 0.15)
				)
				(justify left bottom mirror)
			)
		)
		(property "Value" "L_1u_5.5A_Bourns-SRP3212A"
			(at 0.05 -2.8 90)
			(layer "B.Fab")
			(effects
				(font
					(size 0.7 0.7)
					(thickness 0.15)
				)
				(justify left bottom mirror)
			)
		)
		(property "Datasheet" "https://www.mouser.com/datasheet/2/54/SRP3212A-3011944.pdf"
			(at 0 0 270)
			(layer "B.Fab")
			(hide yes)
			(effects
				(font
					(size 1.27 1.27)
					(thickness 0.15)
				)
			)
		)
		(property "Manufacturer" "Bourns"
			(at 0 0 270)
			(unlocked yes)
			(layer "B.Fab")
			(hide yes)
			(effects
				(font
					(size 1 1)
					(thickness 0.15)
				)
				(justify mirror)
			)
		)
		(property "MPN" "SRP3212A-1R0M"
			(at 0 0 270)
			(unlocked yes)
			(layer "B.Fab")
			(hide yes)
			(effects
				(font
					(size 1 1)
					(thickness 0.15)
				)
				(justify mirror)
			)
		)
		(property "Size" "3.2x2.5"
			(at 0 0 270)
			(unlocked yes)
			(layer "B.Fab")
			(hide yes)
			(effects
				(font
					(size 1 1)
					(thickness 0.15)
				)
				(justify mirror)
			)
		)
		(property "Val" "1u/5.5A"
			(at 0 0 270)
			(unlocked yes)
			(layer "B.Fab")
			(hide yes)
			(effects
				(font
					(size 1 1)
					(thickness 0.15)
				)
				(justify mirror)
			)
		)
		(property "Author" "Antmicro"
			(at 0 0 270)
			(unlocked yes)
			(layer "B.Fab")
			(hide yes)
			(effects
				(font
					(size 1 1)
					(thickness 0.15)
				)
				(justify mirror)
			)
		)
		(property "License" "Apache-2.0"
			(at 0 0 270)
			(unlocked yes)
			(layer "B.Fab")
			(hide yes)
			(effects
				(font
					(size 1 1)
					(thickness 0.15)
				)
				(justify mirror)
			)
		)
		(property "ISat" "6.5 A"
			(at 0 0 270)
			(unlocked yes)
			(layer "B.Fab")
			(hide yes)
			(effects
				(font
					(size 1 1)
					(thickness 0.15)
				)
				(justify mirror)
			)
		)
		(property "IMax" "5.5 A"
			(at 0 0 270)
			(unlocked yes)
			(layer "B.Fab")
			(hide yes)
			(effects
				(font
					(size 1 1)
					(thickness 0.15)
				)
				(justify mirror)
			)
		)
		(sheetname "/Supply/")
		(sheetfile "supply.kicad_sch")
		(attr smd)
		(fp_line
			(start -0.4 1.25)
			(end 0.399 1.25)
			(stroke
				(width 0.15)
				(type solid)
			)
			(layer "B.SilkS")
		)
		(fp_line
			(start -0.4 -1.249)
			(end 0.399 -1.249)
			(stroke
				(width 0.15)
				(type solid)
			)
			(layer "B.SilkS")
		)
		(fp_rect
			(start -2.1 1.65)
			(end 2.1 -1.65)
			(stroke
				(width 0.05)
				(type solid)
			)
			(fill no)
			(layer "B.CrtYd")
		)
		(fp_rect
			(start -1.609 1.26)
			(end 1.609 -1.26)
			(stroke
				(width 0.15)
				(type solid)
			)
			(fill no)
			(layer "B.Fab")
		)
		(fp_text user "Author: Antmicro"
			(at -2.1 -6 90)
			(layer "B.Fab")
			(effects
				(font
					(size 0.7 0.7)
					(thickness 0.15)
				)
				(justify left bottom mirror)
			)
		)
		(fp_text user "${REFERENCE}"
			(at -2.1 -4.8 90)
			(layer "B.Fab")
			(effects
				(font
					(size 0.7 0.7)
					(thickness 0.15)
				)
				(justify left bottom mirror)
			)
		)
		(fp_text user "License: Apache-2.0"
			(at -2.1 -7.2 90)
			(layer "B.Fab")
			(effects
				(font
					(size 0.7 0.7)
					(thickness 0.15)
				)
				(justify left bottom mirror)
			)
		)
		(pad "1" smd roundrect
			(at -1.175 0 270)
			(size 1.35 2.8)
			(layers "B.Cu" "B.Mask" "B.Paste")
			(roundrect_rratio 0.1)
			(net 49 "/Supply/SW_3V3")
			(pintype "passive")
		)
		(pad "2" smd roundrect
			(at 1.175 0 270)
			(size 1.35 2.8)
			(layers "B.Cu" "B.Mask" "B.Paste")
			(roundrect_rratio 0.1)
			(net 89 "/Supply/OUT_3V3")
			(pintype "passive")
		)
	)
	(footprint "antmicro-footprints:L_Bourns-SRP3212A"
		(layer "B.Cu")
		(at 113.627962 134.5615 -90)
		(property "Reference" "L301"
			(at 2.125 -1.95 90)
			(layer "B.SilkS")
			(effects
				(font
					(size 0.7 0.7)
					(thickness 0.15)
				)
				(justify left bottom mirror)
			)
		)
		(property "Value" "L_1u_5.5A_Bourns-SRP3212A"
			(at 0.05 -2.8 90)
			(layer "B.Fab")
			(effects
				(font
					(size 0.7 0.7)
					(thickness 0.15)
				)
				(justify left bottom mirror)
			)
		)
		(property "Datasheet" "https://www.mouser.com/datasheet/2/54/SRP3212A-3011944.pdf"
			(at 0 0 270)
			(layer "B.Fab")
			(hide yes)
			(effects
				(font
					(size 1.27 1.27)
					(thickness 0.15)
				)
			)
		)
		(property "Manufacturer" "Bourns"
			(at 0 0 270)
			(unlocked yes)
			(layer "B.Fab")
			(hide yes)
			(effects
				(font
					(size 1 1)
					(thickness 0.15)
				)
				(justify mirror)
			)
		)
		(property "MPN" "SRP3212A-1R0M"
			(at 0 0 270)
			(unlocked yes)
			(layer "B.Fab")
			(hide yes)
			(effects
				(font
					(size 1 1)
					(thickness 0.15)
				)
				(justify mirror)
			)
		)
		(property "Size" "3.2x2.5"
			(at 0 0 270)
			(unlocked yes)
			(layer "B.Fab")
			(hide yes)
			(effects
				(font
					(size 1 1)
					(thickness 0.15)
				)
				(justify mirror)
			)
		)
		(property "Val" "1u/5.5A"
			(at 0 0 270)
			(unlocked yes)
			(layer "B.Fab")
			(hide yes)
			(effects
				(font
					(size 1 1)
					(thickness 0.15)
				)
				(justify mirror)
			)
		)
		(property "Author" "Antmicro"
			(at 0 0 270)
			(unlocked yes)
			(layer "B.Fab")
			(hide yes)
			(effects
				(font
					(size 1 1)
					(thickness 0.15)
				)
				(justify mirror)
			)
		)
		(property "License" "Apache-2.0"
			(at 0 0 270)
			(unlocked yes)
			(layer "B.Fab")
			(hide yes)
			(effects
				(font
					(size 1 1)
					(thickness 0.15)
				)
				(justify mirror)
			)
		)
		(property "ISat" "6.5 A"
			(at 0 0 270)
			(unlocked yes)
			(layer "B.Fab")
			(hide yes)
			(effects
				(font
					(size 1 1)
					(thickness 0.15)
				)
				(justify mirror)
			)
		)
		(property "IMax" "5.5 A"
			(at 0 0 270)
			(unlocked yes)
			(layer "B.Fab")
			(hide yes)
			(effects
				(font
					(size 1 1)
					(thickness 0.15)
				)
				(justify mirror)
			)
		)
		(sheetname "/Supply/")
		(sheetfile "supply.kicad_sch")
		(attr smd)
		(fp_line
			(start -0.4 1.25)
			(end 0.399 1.25)
			(stroke
				(width 0.15)
				(type solid)
			)
			(layer "B.SilkS")
		)
		(fp_line
			(start -0.4 -1.249)
			(end 0.399 -1.249)
			(stroke
				(width 0.15)
				(type solid)
			)
			(layer "B.SilkS")
		)
		(fp_rect
			(start -2.1 1.65)
			(end 2.1 -1.65)
			(stroke
				(width 0.05)
				(type solid)
			)
			(fill no)
			(layer "B.CrtYd")
		)
		(fp_rect
			(start -1.609 1.26)
			(end 1.609 -1.26)
			(stroke
				(width 0.15)
				(type solid)
			)
			(fill no)
			(layer "B.Fab")
		)
		(fp_text user "${REFERENCE}"
			(at -2.1 -4.8 90)
			(layer "B.Fab")
			(effects
				(font
					(size 0.7 0.7)
					(thickness 0.15)
				)
				(justify left bottom mirror)
			)
		)
		(fp_text user "License: Apache-2.0"
			(at -2.1 -7.2 90)
			(layer "B.Fab")
			(effects
				(font
					(size 0.7 0.7)
					(thickness 0.15)
				)
				(justify left bottom mirror)
			)
		)
		(fp_text user "Author: Antmicro"
			(at -2.1 -6 90)
			(layer "B.Fab")
			(effects
				(font
					(size 0.7 0.7)
					(thickness 0.15)
				)
				(justify left bottom mirror)
			)
		)
		(pad "1" smd roundrect
			(at -1.175 0 270)
			(size 1.35 2.8)
			(layers "B.Cu" "B.Mask" "B.Paste")
			(roundrect_rratio 0.1)
			(net 45 "/Supply/SW_M2")
			(pintype "passive")
		)
		(pad "2" smd roundrect
			(at 1.175 0 270)
			(size 1.35 2.8)
			(layers "B.Cu" "B.Mask" "B.Paste")
			(roundrect_rratio 0.1)
			(net 78 "/Supply/OUT_M2")
			(pintype "passive")
		)
	)
	(footprint "antmicro-footprints:C_0805_2012Metric"
		(layer "B.Cu")
		(at 68.142962 167.7665 180)
		(descr "Capacitor SMD 0805")
		(tags "capacitor SMD 0805")
		(property "Reference" "C314"
			(at -1.575 -1.8 0)
			(layer "B.SilkS")
			(effects
				(font
					(size 0.7 0.7)
					(thickness 0.15)
				)
				(justify left bottom mirror)
			)
		)
		(property "Value" "C_22u_25V_0805"
			(at -2.055717 -1.963152 0)
			(layer "B.Fab")
			(effects
				(font
					(size 0.7 0.7)
					(thickness 0.15)
				)
				(justify left bottom mirror)
			)
		)
		(property "Datasheet" "https://product.samsungsem.com/mlcc/CL21A226MAYNNN.do"
			(at 0 0 180)
			(layer "B.Fab")
			(hide yes)
			(effects
				(font
					(size 1.27 1.27)
					(thickness 0.15)
				)
			)
		)
		(property "Manufacturer" "Samsung Electro-Mechanics"
			(at 0 0 180)
			(unlocked yes)
			(layer "B.Fab")
			(hide yes)
			(effects
				(font
					(size 1 1)
					(thickness 0.15)
				)
				(justify mirror)
			)
		)
		(property "MPN" "CL21A226MAYNNNE"
			(at 0 0 180)
			(unlocked yes)
			(layer "B.Fab")
			(hide yes)
			(effects
				(font
					(size 1 1)
					(thickness 0.15)
				)
				(justify mirror)
			)
		)
		(property "Val" "22u"
			(at 0 0 180)
			(unlocked yes)
			(layer "B.Fab")
			(hide yes)
			(effects
				(font
					(size 1 1)
					(thickness 0.15)
				)
				(justify mirror)
			)
		)
		(property "License" "Apache-2.0"
			(at 0 0 180)
			(unlocked yes)
			(layer "B.Fab")
			(hide yes)
			(effects
				(font
					(size 1 1)
					(thickness 0.15)
				)
				(justify mirror)
			)
		)
		(property "Author" "Antmicro"
			(at 0 0 180)
			(unlocked yes)
			(layer "B.Fab")
			(hide yes)
			(effects
				(font
					(size 1 1)
					(thickness 0.15)
				)
				(justify mirror)
			)
		)
		(property "Voltage" "25V"
			(at 0 0 180)
			(unlocked yes)
			(layer "B.Fab")
			(hide yes)
			(effects
				(font
					(size 1 1)
					(thickness 0.15)
				)
				(justify mirror)
			)
		)
		(property "Dielectric" "X5R"
			(at 0 0 180)
			(unlocked yes)
			(layer "B.Fab")
			(hide yes)
			(effects
				(font
					(size 1 1)
					(thickness 0.15)
				)
				(justify mirror)
			)
		)
		(property "Public" "False"
			(at 0 0 180)
			(unlocked yes)
			(layer "B.Fab")
			(hide yes)
			(effects
				(font
					(size 1 1)
					(thickness 0.15)
				)
				(justify mirror)
			)
		)
		(sheetname "/Supply/")
		(sheetfile "supply.kicad_sch")
		(attr smd)
		(fp_line
			(start -0.3 0.7)
			(end 0.3 0.7)
			(stroke
				(width 0.15)
				(type solid)
			)
			(layer "B.SilkS")
		)
		(fp_line
			(start -0.3 -0.7)
			(end 0.3 -0.7)
			(stroke
				(width 0.15)
				(type solid)
			)
			(layer "B.SilkS")
		)
		(fp_rect
			(start 1.95 0.9)
			(end -1.95 -0.9)
			(stroke
				(width 0.05)
				(type default)
			)
			(fill no)
			(layer "B.CrtYd")
		)
		(fp_rect
			(start -0.95 0.675)
			(end 0.95 -0.675)
			(stroke
				(width 0.15)
				(type solid)
			)
			(fill no)
			(layer "B.Fab")
		)
		(fp_text user "License: Apache-2.0"
			(at -1.9 -4.947 0)
			(layer "B.Fab")
			(effects
				(font
					(size 0.7 0.7)
					(thickness 0.15)
				)
				(justify left bottom mirror)
			)
		)
		(fp_text user "${REFERENCE}"
			(at -1.9 -3.947 0)
			(layer "B.Fab")
			(effects
				(font
					(size 0.7 0.7)
					(thickness 0.15)
				)
				(justify left bottom mirror)
			)
		)
		(fp_text user "Author: Antmicro"
			(at -1.9 -5.947 0)
			(layer "B.Fab")
			(effects
				(font
					(size 0.7 0.7)
					(thickness 0.15)
				)
				(justify left bottom mirror)
			)
		)
		(pad "1" smd roundrect
			(at -1.1 0 180)
			(size 1.2 1.3)
			(layers "B.Cu" "B.Mask" "B.Paste")
			(roundrect_rratio 0.25)
			(net 89 "/Supply/OUT_3V3")
			(pintype "passive")
		)
		(pad "2" smd roundrect
			(at 1.1 0 180)
			(size 1.2 1.3)
			(layers "B.Cu" "B.Mask" "B.Paste")
			(roundrect_rratio 0.25)
			(net 3 "GND")
			(pintype "passive")
		)
	)
	(footprint "antmicro-footprints:R_0402_1005Metric"
		(layer "B.Cu")
		(at 50.992962 169.9165 180)
		(descr "Resistor SMD 0402")
		(tags "resistor SMD 0402")
		(property "Reference" "R423"
			(at -0.165 -1.29 0)
			(layer "B.SilkS")
			(effects
				(font
					(size 0.7 0.7)
					(thickness 0.15)
				)
				(justify left bottom mirror)
			)
		)
		(property "Value" "R_0R_0402"
			(at -1.011843 -1.772047 0)
			(layer "B.Fab")
			(effects
				(font
					(size 0.7 0.7)
					(thickness 0.15)
				)
				(justify left bottom mirror)
			)
		)
		(property "Datasheet" "https://industrial.panasonic.com/cdbs/www-data/pdf/RDA0000/AOA0000C301.pdf"
			(at 0 0 180)
			(layer "B.Fab")
			(hide yes)
			(effects
				(font
					(size 1.27 1.27)
					(thickness 0.15)
				)
			)
		)
		(property "Manufacturer" "Panasonic"
			(at 0 0 180)
			(unlocked yes)
			(layer "B.Fab")
			(hide yes)
			(effects
				(font
					(size 1 1)
					(thickness 0.15)
				)
				(justify mirror)
			)
		)
		(property "MPN" "ERJ2GE0R00X"
			(at 0 0 180)
			(unlocked yes)
			(layer "B.Fab")
			(hide yes)
			(effects
				(font
					(size 1 1)
					(thickness 0.15)
				)
				(justify mirror)
			)
		)
		(property "Val" "0R"
			(at 0 0 180)
			(unlocked yes)
			(layer "B.Fab")
			(hide yes)
			(effects
				(font
					(size 1 1)
					(thickness 0.15)
				)
				(justify mirror)
			)
		)
		(property "License" "Apache-2.0"
			(at 0 0 180)
			(unlocked yes)
			(layer "B.Fab")
			(hide yes)
			(effects
				(font
					(size 1 1)
					(thickness 0.15)
				)
				(justify mirror)
			)
		)
		(property "Author" "Antmicro"
			(at 0 0 180)
			(unlocked yes)
			(layer "B.Fab")
			(hide yes)
			(effects
				(font
					(size 1 1)
					(thickness 0.15)
				)
				(justify mirror)
			)
		)
		(property "Tolerance" "~"
			(at 0 0 180)
			(unlocked yes)
			(layer "B.Fab")
			(hide yes)
			(effects
				(font
					(size 1 1)
					(thickness 0.15)
				)
				(justify mirror)
			)
		)
		(property "Current" "1A"
			(at 0 0 180)
			(unlocked yes)
			(layer "B.Fab")
			(hide yes)
			(effects
				(font
					(size 1 1)
					(thickness 0.15)
				)
				(justify mirror)
			)
		)
		(sheetname "/Ethernet/")
		(sheetfile "ethernet.kicad_sch")
		(attr smd exclude_from_pos_files exclude_from_bom dnp)
		(fp_rect
			(start -0.925 0.47)
			(end 0.925 -0.47)
			(stroke
				(width 0.05)
				(type default)
			)
			(fill no)
			(layer "B.CrtYd")
		)
		(fp_rect
			(start -0.5 0.25)
			(end 0.5 -0.25)
			(stroke
				(width 0.15)
				(type solid)
			)
			(fill no)
			(layer "B.Fab")
		)
		(fp_text user "Author: Antmicro"
			(at -0.95 -4.169 0)
			(layer "B.Fab")
			(effects
				(font
					(size 0.7 0.7)
					(thickness 0.15)
				)
				(justify left bottom mirror)
			)
		)
		(fp_text user "${REFERENCE}"
			(at -0.95 -3.168 0)
			(layer "B.Fab")
			(effects
				(font
					(size 0.7 0.7)
					(thickness 0.15)
				)
				(justify left bottom mirror)
			)
		)
		(fp_text user "License: Apache-2.0"
			(at -0.95 -5.169 0)
			(layer "B.Fab")
			(effects
				(font
					(size 0.7 0.7)
					(thickness 0.15)
				)
				(justify left bottom mirror)
			)
		)
		(pad "1" smd roundrect
			(at -0.48 0 180)
			(size 0.59 0.64)
			(layers "B.Cu" "B.Mask" "B.Paste")
			(roundrect_rratio 0.25)
			(net 368 "Net-(U403-TRIM)")
			(pintype "passive")
		)
		(pad "2" smd roundrect
			(at 0.48 0 180)
			(size 0.59 0.64)
			(layers "B.Cu" "B.Mask" "B.Paste")
			(roundrect_rratio 0.25)
			(net 3 "GND")
			(pintype "passive")
		)
	)
	(footprint "antmicro-footprints:C_0402_1005Metric"
		(layer "B.Cu")
		(at 52.146694 155.399922 -90)
		(descr "Capacitor SMD 0402")
		(tags "capacitor SMD 0402")
		(property "Reference" "C307"
			(at -4.1 1.34 90)
			(layer "B.SilkS")
			(effects
				(font
					(size 0.7 0.7)
					(thickness 0.15)
				)
				(justify left bottom mirror)
			)
		)
		(property "Value" "C_100n_0402"
			(at -1.022927 -2.155213 90)
			(layer "B.Fab")
			(effects
				(font
					(size 0.7 0.7)
					(thickness 0.15)
				)
				(justify left bottom mirror)
			)
		)
		(property "Datasheet" "https://www.murata.com/products/productdetail?partno=GRM155R61H104KE14%23"
			(at 0 0 270)
			(layer "B.Fab")
			(hide yes)
			(effects
				(font
					(size 1.27 1.27)
					(thickness 0.15)
				)
			)
		)
		(property "Manufacturer" "Murata"
			(at 0 0 270)
			(unlocked yes)
			(layer "B.Fab")
			(hide yes)
			(effects
				(font
					(size 1 1)
					(thickness 0.15)
				)
				(justify mirror)
			)
		)
		(property "MPN" "GRM155R61H104KE14D"
			(at 0 0 270)
			(unlocked yes)
			(layer "B.Fab")
			(hide yes)
			(effects
				(font
					(size 1 1)
					(thickness 0.15)
				)
				(justify mirror)
			)
		)
		(property "Val" "100n"
			(at 0 0 270)
			(unlocked yes)
			(layer "B.Fab")
			(hide yes)
			(effects
				(font
					(size 1 1)
					(thickness 0.15)
				)
				(justify mirror)
			)
		)
		(property "License" "Apache-2.0"
			(at 0 0 270)
			(unlocked yes)
			(layer "B.Fab")
			(hide yes)
			(effects
				(font
					(size 1 1)
					(thickness 0.15)
				)
				(justify mirror)
			)
		)
		(property "Author" "Antmicro"
			(at 0 0 270)
			(unlocked yes)
			(layer "B.Fab")
			(hide yes)
			(effects
				(font
					(size 1 1)
					(thickness 0.15)
				)
				(justify mirror)
			)
		)
		(property "Voltage" "50V"
			(at 0 0 270)
			(unlocked yes)
			(layer "B.Fab")
			(hide yes)
			(effects
				(font
					(size 1 1)
					(thickness 0.15)
				)
				(justify mirror)
			)
		)
		(property "Dielectric" "X5R"
			(at 0 0 270)
			(unlocked yes)
			(layer "B.Fab")
			(hide yes)
			(effects
				(font
					(size 1 1)
					(thickness 0.15)
				)
				(justify mirror)
			)
		)
		(sheetname "/Supply/")
		(sheetfile "supply.kicad_sch")
		(attr smd)
		(fp_rect
			(start -0.925 0.47)
			(end 0.925 -0.47)
			(stroke
				(width 0.05)
				(type default)
			)
			(fill no)
			(layer "B.CrtYd")
		)
		(fp_line
			(start -0.494 0.25)
			(end 0.504 0.25)
			(stroke
				(width 0.15)
				(type solid)
			)
			(layer "B.Fab")
		)
		(fp_line
			(start 0.504 0.25)
			(end 0.504 -0.248)
			(stroke
				(width 0.15)
				(type solid)
			)
			(layer "B.Fab")
		)
		(fp_line
			(start -0.494 -0.248)
			(end -0.494 0.25)
			(stroke
				(width 0.15)
				(type solid)
			)
			(layer "B.Fab")
		)
		(fp_line
			(start 0.504 -0.248)
			(end -0.494 -0.248)
			(stroke
				(width 0.15)
				(type solid)
			)
			(layer "B.Fab")
		)
		(fp_text user "Author: Antmicro"
			(at -0.939 -3.399 90)
			(layer "B.Fab")
			(effects
				(font
					(size 0.7 0.7)
					(thickness 0.15)
				)
				(justify left bottom mirror)
			)
		)
		(fp_text user "License: Apache-2.0"
			(at -0.939 -5.799 90)
			(layer "B.Fab")
			(effects
				(font
					(size 0.7 0.7)
					(thickness 0.15)
				)
				(justify left bottom mirror)
			)
		)
		(fp_text user "${REFERENCE}"
			(at -0.939 -4.599 90)
			(layer "B.Fab")
			(effects
				(font
					(size 0.7 0.7)
					(thickness 0.15)
				)
				(justify left bottom mirror)
			)
		)
		(pad "1" smd roundrect
			(at -0.48 0 270)
			(size 0.59 0.64)
			(layers "B.Cu" "B.Mask" "B.Paste")
			(roundrect_rratio 0.25)
			(net 43 "VCC")
			(pintype "passive")
		)
		(pad "2" smd roundrect
			(at 0.48 0 270)
			(size 0.59 0.64)
			(layers "B.Cu" "B.Mask" "B.Paste")
			(roundrect_rratio 0.25)
			(net 3 "GND")
			(pintype "passive")
		)
	)
	(footprint "antmicro-footprints:R_0402_1005Metric"
		(layer "B.Cu")
		(at 52.842962 159.3915)
		(descr "Resistor SMD 0402")
		(tags "resistor SMD 0402")
		(property "Reference" "R316"
			(at -4.215 0.955 0)
			(layer "B.SilkS")
			(effects
				(font
					(size 0.7 0.7)
					(thickness 0.15)
				)
				(justify right bottom mirror)
			)
		)
		(property "Value" "R_15k_0402"
			(at -1.011843 -1.772047 0)
			(layer "B.Fab")
			(effects
				(font
					(size 0.7 0.7)
					(thickness 0.15)
				)
				(justify right bottom mirror)
			)
		)
		(property "Datasheet" "https://www.bourns.com/docs/product-datasheets/cr.pdf"
			(at 0 0 0)
			(layer "B.Fab")
			(hide yes)
			(effects
				(font
					(size 1.27 1.27)
					(thickness 0.15)
				)
			)
		)
		(property "Manufacturer" "Bourns"
			(at 0 0 0)
			(unlocked yes)
			(layer "B.Fab")
			(hide yes)
			(effects
				(font
					(size 1 1)
					(thickness 0.15)
				)
				(justify mirror)
			)
		)
		(property "MPN" "CR0402-FX-1502GLF"
			(at 0 0 0)
			(unlocked yes)
			(layer "B.Fab")
			(hide yes)
			(effects
				(font
					(size 1 1)
					(thickness 0.15)
				)
				(justify mirror)
			)
		)
		(property "Val" "15k"
			(at 0 0 0)
			(unlocked yes)
			(layer "B.Fab")
			(hide yes)
			(effects
				(font
					(size 1 1)
					(thickness 0.15)
				)
				(justify mirror)
			)
		)
		(property "License" "Apache-2.0"
			(at 0 0 0)
			(unlocked yes)
			(layer "B.Fab")
			(hide yes)
			(effects
				(font
					(size 1 1)
					(thickness 0.15)
				)
				(justify mirror)
			)
		)
		(property "Author" "Antmicro"
			(at 0 0 0)
			(unlocked yes)
			(layer "B.Fab")
			(hide yes)
			(effects
				(font
					(size 1 1)
					(thickness 0.15)
				)
				(justify mirror)
			)
		)
		(property "Tolerance" "1%"
			(at 0 0 0)
			(unlocked yes)
			(layer "B.Fab")
			(hide yes)
			(effects
				(font
					(size 1 1)
					(thickness 0.15)
				)
				(justify mirror)
			)
		)
		(sheetname "/Supply/")
		(sheetfile "supply.kicad_sch")
		(attr smd)
		(fp_rect
			(start -0.925 0.47)
			(end 0.925 -0.47)
			(stroke
				(width 0.05)
				(type default)
			)
			(fill no)
			(layer "B.CrtYd")
		)
		(fp_rect
			(start -0.5 0.25)
			(end 0.5 -0.25)
			(stroke
				(width 0.15)
				(type solid)
			)
			(fill no)
			(layer "B.Fab")
		)
		(fp_text user "Author: Antmicro"
			(at -0.95 -4.169 180)
			(layer "B.Fab")
			(effects
				(font
					(size 0.7 0.7)
					(thickness 0.15)
				)
				(justify left bottom mirror)
			)
		)
		(fp_text user "${REFERENCE}"
			(at -0.95 -3.168 180)
			(layer "B.Fab")
			(effects
				(font
					(size 0.7 0.7)
					(thickness 0.15)
				)
				(justify left bottom mirror)
			)
		)
		(fp_text user "License: Apache-2.0"
			(at -0.95 -5.169 180)
			(layer "B.Fab")
			(effects
				(font
					(size 0.7 0.7)
					(thickness 0.15)
				)
				(justify left bottom mirror)
			)
		)
		(pad "1" smd roundrect
			(at -0.48 0)
			(size 0.59 0.64)
			(layers "B.Cu" "B.Mask" "B.Paste")
			(roundrect_rratio 0.25)
			(net 353 "/Supply/FB_5V")
			(pintype "passive")
		)
		(pad "2" smd roundrect
			(at 0.48 0)
			(size 0.59 0.64)
			(layers "B.Cu" "B.Mask" "B.Paste")
			(roundrect_rratio 0.25)
			(net 77 "/Supply/OUT_5V")
			(pintype "passive")
		)
	)
	(footprint "antmicro-footprints:SOD-523"
		(layer "B.Cu")
		(at 113.592962 119.4665 180)
		(property "Reference" "D712"
			(at -2.245 -5.65 0)
			(layer "B.SilkS")
			(effects
				(font
					(size 0.7 0.7)
					(thickness 0.15)
				)
				(justify left bottom mirror)
			)
		)
		(property "Value" "PESD5Z5_0F"
			(at 0 -1.499 0)
			(layer "B.Fab")
			(effects
				(font
					(size 0.7 0.7)
					(thickness 0.15)
				)
				(justify left bottom mirror)
			)
		)
		(property "Datasheet" "https://assets.nexperia.com/documents/data-sheet/PESD5Z5_0.pdf"
			(at 0 0 180)
			(layer "B.Fab")
			(hide yes)
			(effects
				(font
					(size 1.27 1.27)
					(thickness 0.15)
				)
			)
		)
		(property "Manufacturer" "Nexperia"
			(at 0 0 180)
			(unlocked yes)
			(layer "B.Fab")
			(hide yes)
			(effects
				(font
					(size 1 1)
					(thickness 0.15)
				)
				(justify mirror)
			)
		)
		(property "MPN" "PESD5Z5.0F"
			(at 0 0 180)
			(unlocked yes)
			(layer "B.Fab")
			(hide yes)
			(effects
				(font
					(size 1 1)
					(thickness 0.15)
				)
				(justify mirror)
			)
		)
		(property "Author" "Antmicro"
			(at 0 0 180)
			(unlocked yes)
			(layer "B.Fab")
			(hide yes)
			(effects
				(font
					(size 1 1)
					(thickness 0.15)
				)
				(justify mirror)
			)
		)
		(property "License" "Apache-2.0"
			(at 0 0 180)
			(unlocked yes)
			(layer "B.Fab")
			(hide yes)
			(effects
				(font
					(size 1 1)
					(thickness 0.15)
				)
				(justify mirror)
			)
		)
		(sheetname "/Display/")
		(sheetfile "display.kicad_sch")
		(attr smd)
		(fp_line
			(start -0.35 0.5)
			(end -0.35 -0.5)
			(stroke
				(width 0.15)
				(type solid)
			)
			(layer "B.SilkS")
		)
		(fp_rect
			(start -1 0.6)
			(end 1 -0.6)
			(stroke
				(width 0.05)
				(type solid)
			)
			(fill no)
			(layer "B.CrtYd")
		)
		(fp_line
			(start 0.65 0.425)
			(end 0.65 -0.423)
			(stroke
				(width 0.15)
				(type solid)
			)
			(layer "B.Fab")
		)
		(fp_line
			(start -0.35 0.4)
			(end -0.35 -0.4)
			(stroke
				(width 0.15)
				(type solid)
			)
			(layer "B.Fab")
		)
		(fp_line
			(start -0.652 0.425)
			(end 0.65 0.425)
			(stroke
				(width 0.15)
				(type solid)
			)
			(layer "B.Fab")
		)
		(fp_line
			(start -0.652 -0.423)
			(end 0.65 -0.423)
			(stroke
				(width 0.15)
				(type solid)
			)
			(layer "B.Fab")
		)
		(fp_line
			(start -0.652 -0.423)
			(end -0.652 0.425)
			(stroke
				(width 0.15)
				(type solid)
			)
			(layer "B.Fab")
		)
		(fp_text user "${REFERENCE}"
			(at -1.276 -3.499 0)
			(layer "B.Fab")
			(effects
				(font
					(size 0.7 0.7)
					(thickness 0.15)
				)
				(justify left bottom mirror)
			)
		)
		(fp_text user "Author: Antmicro"
			(at -1.276 -4.7 0)
			(layer "B.Fab")
			(effects
				(font
					(size 0.7 0.7)
					(thickness 0.15)
				)
				(justify left bottom mirror)
			)
		)
		(fp_text user "License: Apache-2.0"
			(at -1.276 -5.9 0)
			(layer "B.Fab")
			(effects
				(font
					(size 0.7 0.7)
					(thickness 0.15)
				)
				(justify left bottom mirror)
			)
		)
		(pad "1" smd roundrect
			(at -0.701 0 180)
			(size 0.5 0.6)
			(layers "B.Cu" "B.Mask" "B.Paste")
			(roundrect_rratio 0.25)
			(net 119 "Net-(D710-C)")
			(pinfunction "C")
			(pintype "passive")
		)
		(pad "2" smd roundrect
			(at 0.699 0 180)
			(size 0.5 0.6)
			(layers "B.Cu" "B.Mask" "B.Paste")
			(roundrect_rratio 0.25)
			(net 3 "GND")
			(pinfunction "A")
			(pintype "passive")
		)
	)
	(footprint "antmicro-footprints:C_0805_2012Metric"
		(layer "B.Cu")
		(at 50.742962 156.3665 -90)
		(descr "Capacitor SMD 0805")
		(tags "capacitor SMD 0805")
		(property "Reference" "C303"
			(at -5.09 0.875 90)
			(layer "B.SilkS")
			(effects
				(font
					(size 0.7 0.7)
					(thickness 0.15)
				)
				(justify left bottom mirror)
			)
		)
		(property "Value" "C_22u_25V_0805"
			(at -2.055717 -1.963152 90)
			(layer "B.Fab")
			(effects
				(font
					(size 0.7 0.7)
					(thickness 0.15)
				)
				(justify left bottom mirror)
			)
		)
		(property "Datasheet" "https://product.samsungsem.com/mlcc/CL21A226MAYNNN.do"
			(at 0 0 270)
			(layer "B.Fab")
			(hide yes)
			(effects
				(font
					(size 1.27 1.27)
					(thickness 0.15)
				)
			)
		)
		(property "Manufacturer" "Samsung Electro-Mechanics"
			(at 0 0 270)
			(unlocked yes)
			(layer "B.Fab")
			(hide yes)
			(effects
				(font
					(size 1 1)
					(thickness 0.15)
				)
				(justify mirror)
			)
		)
		(property "MPN" "CL21A226MAYNNNE"
			(at 0 0 270)
			(unlocked yes)
			(layer "B.Fab")
			(hide yes)
			(effects
				(font
					(size 1 1)
					(thickness 0.15)
				)
				(justify mirror)
			)
		)
		(property "Val" "22u"
			(at 0 0 270)
			(unlocked yes)
			(layer "B.Fab")
			(hide yes)
			(effects
				(font
					(size 1 1)
					(thickness 0.15)
				)
				(justify mirror)
			)
		)
		(property "License" "Apache-2.0"
			(at 0 0 270)
			(unlocked yes)
			(layer "B.Fab")
			(hide yes)
			(effects
				(font
					(size 1 1)
					(thickness 0.15)
				)
				(justify mirror)
			)
		)
		(property "Author" "Antmicro"
			(at 0 0 270)
			(unlocked yes)
			(layer "B.Fab")
			(hide yes)
			(effects
				(font
					(size 1 1)
					(thickness 0.15)
				)
				(justify mirror)
			)
		)
		(property "Voltage" "25V"
			(at 0 0 270)
			(unlocked yes)
			(layer "B.Fab")
			(hide yes)
			(effects
				(font
					(size 1 1)
					(thickness 0.15)
				)
				(justify mirror)
			)
		)
		(property "Dielectric" "X5R"
			(at 0 0 270)
			(unlocked yes)
			(layer "B.Fab")
			(hide yes)
			(effects
				(font
					(size 1 1)
					(thickness 0.15)
				)
				(justify mirror)
			)
		)
		(property "Public" "False"
			(at 0 0 270)
			(unlocked yes)
			(layer "B.Fab")
			(hide yes)
			(effects
				(font
					(size 1 1)
					(thickness 0.15)
				)
				(justify mirror)
			)
		)
		(sheetname "/Supply/")
		(sheetfile "supply.kicad_sch")
		(attr smd)
		(fp_line
			(start -0.3 0.7)
			(end 0.3 0.7)
			(stroke
				(width 0.15)
				(type solid)
			)
			(layer "B.SilkS")
		)
		(fp_line
			(start -0.3 -0.7)
			(end 0.3 -0.7)
			(stroke
				(width 0.15)
				(type solid)
			)
			(layer "B.SilkS")
		)
		(fp_rect
			(start 1.95 0.9)
			(end -1.95 -0.9)
			(stroke
				(width 0.05)
				(type default)
			)
			(fill no)
			(layer "B.CrtYd")
		)
		(fp_rect
			(start -0.95 0.675)
			(end 0.95 -0.675)
			(stroke
				(width 0.15)
				(type solid)
			)
			(fill no)
			(layer "B.Fab")
		)
		(fp_text user "${REFERENCE}"
			(at -1.9 -3.947 90)
			(layer "B.Fab")
			(effects
				(font
					(size 0.7 0.7)
					(thickness 0.15)
				)
				(justify left bottom mirror)
			)
		)
		(fp_text user "License: Apache-2.0"
			(at -1.9 -4.947 90)
			(layer "B.Fab")
			(effects
				(font
					(size 0.7 0.7)
					(thickness 0.15)
				)
				(justify left bottom mirror)
			)
		)
		(fp_text user "Author: Antmicro"
			(at -1.9 -5.947 90)
			(layer "B.Fab")
			(effects
				(font
					(size 0.7 0.7)
					(thickness 0.15)
				)
				(justify left bottom mirror)
			)
		)
		(pad "1" smd roundrect
			(at -1.1 0 270)
			(size 1.2 1.3)
			(layers "B.Cu" "B.Mask" "B.Paste")
			(roundrect_rratio 0.25)
			(net 43 "VCC")
			(pintype "passive")
		)
		(pad "2" smd roundrect
			(at 1.1 0 270)
			(size 1.2 1.3)
			(layers "B.Cu" "B.Mask" "B.Paste")
			(roundrect_rratio 0.25)
			(net 3 "GND")
			(pintype "passive")
		)
	)
	(footprint "antmicro-footprints:R_0603_1608Metric"
		(layer "B.Cu")
		(at 74.317962 165.8915)
		(descr "Resistor SMD 0603")
		(tags "resistor SMD 0603")
		(property "Reference" "R323"
			(at -1.45 1.505 0)
			(layer "B.SilkS")
			(effects
				(font
					(size 0.7 0.7)
					(thickness 0.15)
				)
				(justify right bottom mirror)
			)
		)
		(property "Value" "R_0R_22.4A_0603"
			(at 0 -1.6 0)
			(layer "B.Fab")
			(effects
				(font
					(size 0.7 0.7)
					(thickness 0.15)
				)
				(justify right bottom mirror)
			)
		)
		(property "Datasheet" "https://fscdn.rohm.com/en/products/databook/datasheet/passive/resistor/chip_resistor/pmr-jpw-e.pdf"
			(at 0 0 0)
			(layer "B.Fab")
			(hide yes)
			(effects
				(font
					(size 1.27 1.27)
					(thickness 0.15)
				)
			)
		)
		(property "Manufacturer" "ROHM Semiconductor"
			(at 0 0 0)
			(unlocked yes)
			(layer "B.Fab")
			(hide yes)
			(effects
				(font
					(size 1 1)
					(thickness 0.15)
				)
				(justify mirror)
			)
		)
		(property "MPN" "PMR03EZPJ000"
			(at 0 0 0)
			(unlocked yes)
			(layer "B.Fab")
			(hide yes)
			(effects
				(font
					(size 1 1)
					(thickness 0.15)
				)
				(justify mirror)
			)
		)
		(property "Val" "0R"
			(at 0 0 0)
			(unlocked yes)
			(layer "B.Fab")
			(hide yes)
			(effects
				(font
					(size 1 1)
					(thickness 0.15)
				)
				(justify mirror)
			)
		)
		(property "Author" "Antmicro"
			(at 0 0 0)
			(unlocked yes)
			(layer "B.Fab")
			(hide yes)
			(effects
				(font
					(size 1 1)
					(thickness 0.15)
				)
				(justify mirror)
			)
		)
		(property "License" "Apache-2.0"
			(at 0 0 0)
			(unlocked yes)
			(layer "B.Fab")
			(hide yes)
			(effects
				(font
					(size 1 1)
					(thickness 0.15)
				)
				(justify mirror)
			)
		)
		(property "Max. Curr." "22.4A"
			(at 0 0 0)
			(unlocked yes)
			(layer "B.Fab")
			(hide yes)
			(effects
				(font
					(size 1 1)
					(thickness 0.15)
				)
				(justify mirror)
			)
		)
		(property "Tolerance" "template_tolerance"
			(at 0 0 0)
			(unlocked yes)
			(layer "B.Fab")
			(hide yes)
			(effects
				(font
					(size 1 1)
					(thickness 0.15)
				)
				(justify mirror)
			)
		)
		(sheetname "/Supply/")
		(sheetfile "supply.kicad_sch")
		(attr smd)
		(fp_line
			(start -0.15 -0.4)
			(end 0.15 -0.4)
			(stroke
				(width 0.15)
				(type solid)
			)
			(layer "B.SilkS")
		)
		(fp_line
			(start -0.15 0.4)
			(end 0.15 0.4)
			(stroke
				(width 0.15)
				(type solid)
			)
			(layer "B.SilkS")
		)
		(fp_rect
			(start -1.25 0.65)
			(end 1.25 -0.65)
			(stroke
				(width 0.05)
				(type solid)
			)
			(fill no)
			(layer "B.CrtYd")
		)
		(fp_rect
			(start -0.8 0.4)
			(end 0.8 -0.4)
			(stroke
				(width 0.15)
				(type solid)
			)
			(fill no)
			(layer "B.Fab")
		)
		(fp_text user "Author: Antmicro"
			(at -1.25 -4.9 180)
			(layer "B.Fab")
			(effects
				(font
					(size 0.7 0.7)
					(thickness 0.15)
				)
				(justify left bottom mirror)
			)
		)
		(fp_text user "${REFERENCE}"
			(at -1.25 -3.898 180)
			(layer "B.Fab")
			(effects
				(font
					(size 0.7 0.7)
					(thickness 0.15)
				)
				(justify left bottom mirror)
			)
		)
		(fp_text user "License: Apache-2.0"
			(at -1.25 -5.9 180)
			(layer "B.Fab")
			(effects
				(font
					(size 0.7 0.7)
					(thickness 0.15)
				)
				(justify left bottom mirror)
			)
		)
		(pad "1" smd roundrect
			(at -0.7 0)
			(size 0.8 1)
			(layers "B.Cu" "B.Mask" "B.Paste")
			(roundrect_rratio 0.2)
			(net 89 "/Supply/OUT_3V3")
			(pintype "passive")
		)
		(pad "2" smd roundrect
			(at 0.7 0)
			(size 0.8 1)
			(layers "B.Cu" "B.Mask" "B.Paste")
			(roundrect_rratio 0.2)
			(net 9 "+3V3")
			(pintype "passive")
		)
	)
	(footprint "antmicro-footprints:C_0805_2012Metric"
		(layer "B.Cu")
		(at 72.117962 164.8415 90)
		(descr "Capacitor SMD 0805")
		(tags "capacitor SMD 0805")
		(property "Reference" "C317"
			(at -4.525 0.51 90)
			(layer "B.SilkS")
			(effects
				(font
					(size 0.7 0.7)
					(thickness 0.15)
				)
				(justify right bottom mirror)
			)
		)
		(property "Value" "C_22u_25V_0805"
			(at -2.055717 -1.963152 90)
			(layer "B.Fab")
			(effects
				(font
					(size 0.7 0.7)
					(thickness 0.15)
				)
				(justify right bottom mirror)
			)
		)
		(property "Datasheet" "https://product.samsungsem.com/mlcc/CL21A226MAYNNN.do"
			(at 0 0 90)
			(layer "B.Fab")
			(hide yes)
			(effects
				(font
					(size 1.27 1.27)
					(thickness 0.15)
				)
			)
		)
		(property "Manufacturer" "Samsung Electro-Mechanics"
			(at 0 0 90)
			(unlocked yes)
			(layer "B.Fab")
			(hide yes)
			(effects
				(font
					(size 1 1)
					(thickness 0.15)
				)
				(justify mirror)
			)
		)
		(property "MPN" "CL21A226MAYNNNE"
			(at 0 0 90)
			(unlocked yes)
			(layer "B.Fab")
			(hide yes)
			(effects
				(font
					(size 1 1)
					(thickness 0.15)
				)
				(justify mirror)
			)
		)
		(property "Val" "22u"
			(at 0 0 90)
			(unlocked yes)
			(layer "B.Fab")
			(hide yes)
			(effects
				(font
					(size 1 1)
					(thickness 0.15)
				)
				(justify mirror)
			)
		)
		(property "License" "Apache-2.0"
			(at 0 0 90)
			(unlocked yes)
			(layer "B.Fab")
			(hide yes)
			(effects
				(font
					(size 1 1)
					(thickness 0.15)
				)
				(justify mirror)
			)
		)
		(property "Author" "Antmicro"
			(at 0 0 90)
			(unlocked yes)
			(layer "B.Fab")
			(hide yes)
			(effects
				(font
					(size 1 1)
					(thickness 0.15)
				)
				(justify mirror)
			)
		)
		(property "Voltage" "25V"
			(at 0 0 90)
			(unlocked yes)
			(layer "B.Fab")
			(hide yes)
			(effects
				(font
					(size 1 1)
					(thickness 0.15)
				)
				(justify mirror)
			)
		)
		(property "Dielectric" "X5R"
			(at 0 0 90)
			(unlocked yes)
			(layer "B.Fab")
			(hide yes)
			(effects
				(font
					(size 1 1)
					(thickness 0.15)
				)
				(justify mirror)
			)
		)
		(property "Public" "False"
			(at 0 0 90)
			(unlocked yes)
			(layer "B.Fab")
			(hide yes)
			(effects
				(font
					(size 1 1)
					(thickness 0.15)
				)
				(justify mirror)
			)
		)
		(sheetname "/Supply/")
		(sheetfile "supply.kicad_sch")
		(attr smd)
		(fp_line
			(start -0.3 -0.7)
			(end 0.3 -0.7)
			(stroke
				(width 0.15)
				(type solid)
			)
			(layer "B.SilkS")
		)
		(fp_line
			(start -0.3 0.7)
			(end 0.3 0.7)
			(stroke
				(width 0.15)
				(type solid)
			)
			(layer "B.SilkS")
		)
		(fp_rect
			(start 1.95 0.9)
			(end -1.95 -0.9)
			(stroke
				(width 0.05)
				(type default)
			)
			(fill no)
			(layer "B.CrtYd")
		)
		(fp_rect
			(start -0.95 0.675)
			(end 0.95 -0.675)
			(stroke
				(width 0.15)
				(type solid)
			)
			(fill no)
			(layer "B.Fab")
		)
		(fp_text user "${REFERENCE}"
			(at -1.9 -3.947 270)
			(layer "B.Fab")
			(effects
				(font
					(size 0.7 0.7)
					(thickness 0.15)
				)
				(justify left bottom mirror)
			)
		)
		(fp_text user "License: Apache-2.0"
			(at -1.9 -4.947 270)
			(layer "B.Fab")
			(effects
				(font
					(size 0.7 0.7)
					(thickness 0.15)
				)
				(justify left bottom mirror)
			)
		)
		(fp_text user "Author: Antmicro"
			(at -1.9 -5.947 270)
			(layer "B.Fab")
			(effects
				(font
					(size 0.7 0.7)
					(thickness 0.15)
				)
				(justify left bottom mirror)
			)
		)
		(pad "1" smd roundrect
			(at -1.1 0 90)
			(size 1.2 1.3)
			(layers "B.Cu" "B.Mask" "B.Paste")
			(roundrect_rratio 0.25)
			(net 89 "/Supply/OUT_3V3")
			(pintype "passive")
		)
		(pad "2" smd roundrect
			(at 1.1 0 90)
			(size 1.2 1.3)
			(layers "B.Cu" "B.Mask" "B.Paste")
			(roundrect_rratio 0.25)
			(net 3 "GND")
			(pintype "passive")
		)
	)
	(footprint "antmicro-footprints:R_0402_1005Metric"
		(layer "B.Cu")
		(at 56.167962 153.4165 -90)
		(descr "Resistor SMD 0402")
		(tags "resistor SMD 0402")
		(property "Reference" "R315"
			(at -2.995 -2.3 90)
			(layer "B.SilkS")
			(effects
				(font
					(size 0.7 0.7)
					(thickness 0.15)
				)
				(justify left bottom mirror)
			)
		)
		(property "Value" "R_100k_0402"
			(at -1.011843 -1.772047 90)
			(layer "B.Fab")
			(effects
				(font
					(size 0.7 0.7)
					(thickness 0.15)
				)
				(justify left bottom mirror)
			)
		)
		(property "Datasheet" "https://www.bourns.com/docs/product-datasheets/cr.pdf"
			(at 0 0 270)
			(layer "B.Fab")
			(hide yes)
			(effects
				(font
					(size 1.27 1.27)
					(thickness 0.15)
				)
			)
		)
		(property "Manufacturer" "Bourns"
			(at 0 0 270)
			(unlocked yes)
			(layer "B.Fab")
			(hide yes)
			(effects
				(font
					(size 1 1)
					(thickness 0.15)
				)
				(justify mirror)
			)
		)
		(property "MPN" "CR0402-FX-1003GLF"
			(at 0 0 270)
			(unlocked yes)
			(layer "B.Fab")
			(hide yes)
			(effects
				(font
					(size 1 1)
					(thickness 0.15)
				)
				(justify mirror)
			)
		)
		(property "Val" "100k"
			(at 0 0 270)
			(unlocked yes)
			(layer "B.Fab")
			(hide yes)
			(effects
				(font
					(size 1 1)
					(thickness 0.15)
				)
				(justify mirror)
			)
		)
		(property "License" "Apache-2.0"
			(at 0 0 270)
			(unlocked yes)
			(layer "B.Fab")
			(hide yes)
			(effects
				(font
					(size 1 1)
					(thickness 0.15)
				)
				(justify mirror)
			)
		)
		(property "Author" "Antmicro"
			(at 0 0 270)
			(unlocked yes)
			(layer "B.Fab")
			(hide yes)
			(effects
				(font
					(size 1 1)
					(thickness 0.15)
				)
				(justify mirror)
			)
		)
		(property "Tolerance" "1%"
			(at 0 0 270)
			(unlocked yes)
			(layer "B.Fab")
			(hide yes)
			(effects
				(font
					(size 1 1)
					(thickness 0.15)
				)
				(justify mirror)
			)
		)
		(sheetname "/Supply/")
		(sheetfile "supply.kicad_sch")
		(attr smd)
		(fp_rect
			(start -0.925 0.47)
			(end 0.925 -0.47)
			(stroke
				(width 0.05)
				(type default)
			)
			(fill no)
			(layer "B.CrtYd")
		)
		(fp_rect
			(start -0.5 0.25)
			(end 0.5 -0.25)
			(stroke
				(width 0.15)
				(type solid)
			)
			(fill no)
			(layer "B.Fab")
		)
		(fp_text user "${REFERENCE}"
			(at -0.95 -3.168 90)
			(layer "B.Fab")
			(effects
				(font
					(size 0.7 0.7)
					(thickness 0.15)
				)
				(justify left bottom mirror)
			)
		)
		(fp_text user "Author: Antmicro"
			(at -0.95 -4.169 90)
			(layer "B.Fab")
			(effects
				(font
					(size 0.7 0.7)
					(thickness 0.15)
				)
				(justify left bottom mirror)
			)
		)
		(fp_text user "License: Apache-2.0"
			(at -0.95 -5.169 90)
			(layer "B.Fab")
			(effects
				(font
					(size 0.7 0.7)
					(thickness 0.15)
				)
				(justify left bottom mirror)
			)
		)
		(pad "1" smd roundrect
			(at -0.48 0 270)
			(size 0.59 0.64)
			(layers "B.Cu" "B.Mask" "B.Paste")
			(roundrect_rratio 0.25)
			(net 66 "/Supply/VCC_5V")
			(pintype "passive")
		)
		(pad "2" smd roundrect
			(at 0.48 0 270)
			(size 0.59 0.64)
			(layers "B.Cu" "B.Mask" "B.Paste")
			(roundrect_rratio 0.25)
			(net 352 "Net-(U303-PG)")
			(pintype "passive")
		)
	)
	(footprint "antmicro-footprints:C_0805_2012Metric"
		(layer "B.Cu")
		(at 67.717962 158.1165 90)
		(descr "Capacitor SMD 0805")
		(tags "capacitor SMD 0805")
		(property "Reference" "C315"
			(at 0.88 2.9 90)
			(layer "B.SilkS")
			(effects
				(font
					(size 0.7 0.7)
					(thickness 0.15)
				)
				(justify right bottom mirror)
			)
		)
		(property "Value" "C_22u_25V_0805"
			(at -2.055717 -1.963152 90)
			(layer "B.Fab")
			(effects
				(font
					(size 0.7 0.7)
					(thickness 0.15)
				)
				(justify right bottom mirror)
			)
		)
		(property "Datasheet" "https://product.samsungsem.com/mlcc/CL21A226MAYNNN.do"
			(at 0 0 90)
			(layer "B.Fab")
			(hide yes)
			(effects
				(font
					(size 1.27 1.27)
					(thickness 0.15)
				)
			)
		)
		(property "Manufacturer" "Samsung Electro-Mechanics"
			(at 0 0 90)
			(unlocked yes)
			(layer "B.Fab")
			(hide yes)
			(effects
				(font
					(size 1 1)
					(thickness 0.15)
				)
				(justify mirror)
			)
		)
		(property "MPN" "CL21A226MAYNNNE"
			(at 0 0 90)
			(unlocked yes)
			(layer "B.Fab")
			(hide yes)
			(effects
				(font
					(size 1 1)
					(thickness 0.15)
				)
				(justify mirror)
			)
		)
		(property "Val" "22u"
			(at 0 0 90)
			(unlocked yes)
			(layer "B.Fab")
			(hide yes)
			(effects
				(font
					(size 1 1)
					(thickness 0.15)
				)
				(justify mirror)
			)
		)
		(property "License" "Apache-2.0"
			(at 0 0 90)
			(unlocked yes)
			(layer "B.Fab")
			(hide yes)
			(effects
				(font
					(size 1 1)
					(thickness 0.15)
				)
				(justify mirror)
			)
		)
		(property "Author" "Antmicro"
			(at 0 0 90)
			(unlocked yes)
			(layer "B.Fab")
			(hide yes)
			(effects
				(font
					(size 1 1)
					(thickness 0.15)
				)
				(justify mirror)
			)
		)
		(property "Voltage" "25V"
			(at 0 0 90)
			(unlocked yes)
			(layer "B.Fab")
			(hide yes)
			(effects
				(font
					(size 1 1)
					(thickness 0.15)
				)
				(justify mirror)
			)
		)
		(property "Dielectric" "X5R"
			(at 0 0 90)
			(unlocked yes)
			(layer "B.Fab")
			(hide yes)
			(effects
				(font
					(size 1 1)
					(thickness 0.15)
				)
				(justify mirror)
			)
		)
		(property "Public" "False"
			(at 0 0 90)
			(unlocked yes)
			(layer "B.Fab")
			(hide yes)
			(effects
				(font
					(size 1 1)
					(thickness 0.15)
				)
				(justify mirror)
			)
		)
		(sheetname "/Supply/")
		(sheetfile "supply.kicad_sch")
		(attr smd)
		(fp_line
			(start -0.3 -0.7)
			(end 0.3 -0.7)
			(stroke
				(width 0.15)
				(type solid)
			)
			(layer "B.SilkS")
		)
		(fp_line
			(start -0.3 0.7)
			(end 0.3 0.7)
			(stroke
				(width 0.15)
				(type solid)
			)
			(layer "B.SilkS")
		)
		(fp_rect
			(start 1.95 0.9)
			(end -1.95 -0.9)
			(stroke
				(width 0.05)
				(type default)
			)
			(fill no)
			(layer "B.CrtYd")
		)
		(fp_rect
			(start -0.95 0.675)
			(end 0.95 -0.675)
			(stroke
				(width 0.15)
				(type solid)
			)
			(fill no)
			(layer "B.Fab")
		)
		(fp_text user "${REFERENCE}"
			(at -1.9 -3.947 270)
			(layer "B.Fab")
			(effects
				(font
					(size 0.7 0.7)
					(thickness 0.15)
				)
				(justify left bottom mirror)
			)
		)
		(fp_text user "License: Apache-2.0"
			(at -1.9 -4.947 270)
			(layer "B.Fab")
			(effects
				(font
					(size 0.7 0.7)
					(thickness 0.15)
				)
				(justify left bottom mirror)
			)
		)
		(fp_text user "Author: Antmicro"
			(at -1.9 -5.947 270)
			(layer "B.Fab")
			(effects
				(font
					(size 0.7 0.7)
					(thickness 0.15)
				)
				(justify left bottom mirror)
			)
		)
		(pad "1" smd roundrect
			(at -1.1 0 90)
			(size 1.2 1.3)
			(layers "B.Cu" "B.Mask" "B.Paste")
			(roundrect_rratio 0.25)
			(net 77 "/Supply/OUT_5V")
			(pintype "passive")
		)
		(pad "2" smd roundrect
			(at 1.1 0 90)
			(size 1.2 1.3)
			(layers "B.Cu" "B.Mask" "B.Paste")
			(roundrect_rratio 0.25)
			(net 3 "GND")
			(pintype "passive")
		)
	)
	(footprint "antmicro-footprints:R_0402_1005Metric"
		(layer "B.Cu")
		(at 63.792962 161.2165)
		(descr "Resistor SMD 0402")
		(tags "resistor SMD 0402")
		(property "Reference" "R321"
			(at 13.445 0.73 0)
			(layer "B.SilkS")
			(effects
				(font
					(size 0.7 0.7)
					(thickness 0.15)
				)
				(justify right bottom mirror)
			)
		)
		(property "Value" "R_2k2_0402"
			(at -1.011843 -1.772047 0)
			(layer "B.Fab")
			(effects
				(font
					(size 0.7 0.7)
					(thickness 0.15)
				)
				(justify right bottom mirror)
			)
		)
		(property "Datasheet" "https://www.bourns.com/docs/product-datasheets/cr.pdf"
			(at 0 0 0)
			(layer "B.Fab")
			(hide yes)
			(effects
				(font
					(size 1.27 1.27)
					(thickness 0.15)
				)
			)
		)
		(property "MPN" "CR0402-FX-2201GLF"
			(at 0 0 0)
			(unlocked yes)
			(layer "B.Fab")
			(hide yes)
			(effects
				(font
					(size 1 1)
					(thickness 0.15)
				)
				(justify mirror)
			)
		)
		(property "Manufacturer" "Bourns"
			(at 0 0 0)
			(unlocked yes)
			(layer "B.Fab")
			(hide yes)
			(effects
				(font
					(size 1 1)
					(thickness 0.15)
				)
				(justify mirror)
			)
		)
		(property "License" "Apache-2.0"
			(at 0 0 0)
			(unlocked yes)
			(layer "B.Fab")
			(hide yes)
			(effects
				(font
					(size 1 1)
					(thickness 0.15)
				)
				(justify mirror)
			)
		)
		(property "Author" "Antmicro"
			(at 0 0 0)
			(unlocked yes)
			(layer "B.Fab")
			(hide yes)
			(effects
				(font
					(size 1 1)
					(thickness 0.15)
				)
				(justify mirror)
			)
		)
		(property "Val" "2k2"
			(at 0 0 0)
			(unlocked yes)
			(layer "B.Fab")
			(hide yes)
			(effects
				(font
					(size 1 1)
					(thickness 0.15)
				)
				(justify mirror)
			)
		)
		(property "Tolerance" "1%"
			(at 0 0 0)
			(unlocked yes)
			(layer "B.Fab")
			(hide yes)
			(effects
				(font
					(size 1 1)
					(thickness 0.15)
				)
				(justify mirror)
			)
		)
		(sheetname "/Supply/")
		(sheetfile "supply.kicad_sch")
		(attr smd)
		(fp_rect
			(start -0.925 0.47)
			(end 0.925 -0.47)
			(stroke
				(width 0.05)
				(type default)
			)
			(fill no)
			(layer "B.CrtYd")
		)
		(fp_rect
			(start -0.5 0.25)
			(end 0.5 -0.25)
			(stroke
				(width 0.15)
				(type solid)
			)
			(fill no)
			(layer "B.Fab")
		)
		(fp_text user "${REFERENCE}"
			(at -0.95 -3.168 180)
			(layer "B.Fab")
			(effects
				(font
					(size 0.7 0.7)
					(thickness 0.15)
				)
				(justify left bottom mirror)
			)
		)
		(fp_text user "License: Apache-2.0"
			(at -0.95 -5.169 180)
			(layer "B.Fab")
			(effects
				(font
					(size 0.7 0.7)
					(thickness 0.15)
				)
				(justify left bottom mirror)
			)
		)
		(fp_text user "Author: Antmicro"
			(at -0.95 -4.169 180)
			(layer "B.Fab")
			(effects
				(font
					(size 0.7 0.7)
					(thickness 0.15)
				)
				(justify left bottom mirror)
			)
		)
		(pad "1" smd roundrect
			(at -0.48 0)
			(size 0.59 0.64)
			(layers "B.Cu" "B.Mask" "B.Paste")
			(roundrect_rratio 0.25)
			(net 3 "GND")
			(pintype "passive")
		)
		(pad "2" smd roundrect
			(at 0.48 0)
			(size 0.59 0.64)
			(layers "B.Cu" "B.Mask" "B.Paste")
			(roundrect_rratio 0.25)
			(net 355 "/Supply/FB_3V3")
			(pintype "passive")
		)
	)
	(footprint "antmicro-footprints:Resonator_SMD_MicroCrystal_CM7V-T1A_3.2x1.5x0.65mm"
		(layer "B.Cu")
		(at 125.73 175.006 -90)
		(property "Reference" "Y802"
			(at -1.905 -0.889 180)
			(layer "B.SilkS")
			(effects
				(font
					(size 0.7 0.7)
					(thickness 0.15)
				)
				(justify left bottom mirror)
			)
		)
		(property "Value" "Resonator_32.768kHz_CM7V-T1A"
			(at -2 -2 90)
			(layer "B.Fab")
			(effects
				(font
					(size 0.7 0.7)
					(thickness 0.15)
				)
				(justify left bottom mirror)
			)
		)
		(property "Datasheet" "https://www.microcrystal.com/fileadmin/Media/Products/32kHz/Datasheet/CM7V-T1A.pdf"
			(at 0 0 90)
			(layer "B.Fab")
			(hide yes)
			(effects
				(font
					(size 1.27 1.27)
					(thickness 0.15)
				)
				(justify mirror)
			)
		)
		(property "Description" "Crystal, 32.768 kHz, SMD, 3.2mm x 1.5mm, 12.5 pF, 20 ppm, CC7V-T1A"
			(at 0 0 90)
			(layer "B.Fab")
			(hide yes)
			(effects
				(font
					(size 1.27 1.27)
					(thickness 0.15)
				)
				(justify mirror)
			)
		)
		(property "MPN" "CM7V-T1A-32.768kHz-12.5pF-20PPM-TC-QA"
			(at 0 0 270)
			(unlocked yes)
			(layer "B.Fab")
			(hide yes)
			(effects
				(font
					(size 1 1)
					(thickness 0.15)
				)
				(justify mirror)
			)
		)
		(property "Manufacturer" "Micro Crystal"
			(at 0 0 270)
			(unlocked yes)
			(layer "B.Fab")
			(hide yes)
			(effects
				(font
					(size 1 1)
					(thickness 0.15)
				)
				(justify mirror)
			)
		)
		(property "Val" "32.768 kHz"
			(at 0 0 270)
			(unlocked yes)
			(layer "B.Fab")
			(hide yes)
			(effects
				(font
					(size 1 1)
					(thickness 0.15)
				)
				(justify mirror)
			)
		)
		(property "Author" "Antmicro"
			(at 0 0 270)
			(unlocked yes)
			(layer "B.Fab")
			(hide yes)
			(effects
				(font
					(size 1 1)
					(thickness 0.15)
				)
				(justify mirror)
			)
		)
		(property "License" "Apache-2.0"
			(at 0 0 270)
			(unlocked yes)
			(layer "B.Fab")
			(hide yes)
			(effects
				(font
					(size 1 1)
					(thickness 0.15)
				)
				(justify mirror)
			)
		)
		(sheetname "/Peripherals/")
		(sheetfile "peripherals.kicad_sch")
		(attr smd)
		(fp_rect
			(start -1.85 1)
			(end 1.85 -1)
			(stroke
				(width 0.05)
				(type solid)
			)
			(fill no)
			(layer "B.CrtYd")
		)
		(fp_line
			(start -1.3 0.75)
			(end -1.6 0.4)
			(stroke
				(width 0.15)
				(type solid)
			)
			(layer "B.Fab")
		)
		(fp_line
			(start 1.6 0.75)
			(end -1.3 0.75)
			(stroke
				(width 0.15)
				(type solid)
			)
			(layer "B.Fab")
		)
		(fp_line
			(start -1.601 -0.748)
			(end -1.6 0.4)
			(stroke
				(width 0.15)
				(type solid)
			)
			(layer "B.Fab")
		)
		(fp_line
			(start -1.601 -0.748)
			(end 1.6 -0.748)
			(stroke
				(width 0.15)
				(type solid)
			)
			(layer "B.Fab")
		)
		(fp_line
			(start 1.6 -0.748)
			(end 1.6 0.75)
			(stroke
				(width 0.15)
				(type solid)
			)
			(layer "B.Fab")
		)
		(fp_text user "Author: Antmicro"
			(at -2 -6.4 90)
			(layer "B.Fab")
			(effects
				(font
					(size 0.7 0.7)
					(thickness 0.15)
				)
				(justify left bottom mirror)
			)
		)
		(fp_text user "License: Apache-2.0"
			(at -2 -4 90)
			(layer "B.Fab")
			(effects
				(font
					(size 0.7 0.7)
					(thickness 0.15)
				)
				(justify left bottom mirror)
			)
		)
		(fp_text user "${REFERENCE}"
			(at -2 -5.2 90)
			(layer "B.Fab")
			(effects
				(font
					(size 0.7 0.7)
					(thickness 0.15)
				)
				(justify left bottom mirror)
			)
		)
		(pad "1" smd roundrect
			(at -1.25 0 270)
			(size 1 1.8)
			(layers "B.Cu" "B.Mask" "B.Paste")
			(roundrect_rratio 0.1)
			(net 505 "Net-(U802-X1)")
			(pintype "passive")
		)
		(pad "2" smd roundrect
			(at 1.25 0 270)
			(size 1 1.8)
			(layers "B.Cu" "B.Mask" "B.Paste")
			(roundrect_rratio 0.1)
			(net 506 "Net-(U802-X2)")
			(pintype "passive")
		)
	)
	(footprint "antmicro-footprints:R_0402_1005Metric"
		(layer "B.Cu")
		(at 78.617962 146.5165 -90)
		(descr "Resistor SMD 0402")
		(tags "resistor SMD 0402")
		(property "Reference" "R411"
			(at -3.79 -0.41 90)
			(layer "B.SilkS")
			(effects
				(font
					(size 0.7 0.7)
					(thickness 0.15)
				)
				(justify left bottom mirror)
			)
		)
		(property "Value" "R_200R_0402"
			(at -1.011843 -1.772047 90)
			(layer "B.Fab")
			(effects
				(font
					(size 0.7 0.7)
					(thickness 0.15)
				)
				(justify left bottom mirror)
			)
		)
		(property "Datasheet" "https://www.bourns.com/docs/product-datasheets/cr.pdf"
			(at 0 0 270)
			(layer "B.Fab")
			(hide yes)
			(effects
				(font
					(size 1.27 1.27)
					(thickness 0.15)
				)
			)
		)
		(property "Manufacturer" "Bourns"
			(at 0 0 270)
			(unlocked yes)
			(layer "B.Fab")
			(hide yes)
			(effects
				(font
					(size 1 1)
					(thickness 0.15)
				)
				(justify mirror)
			)
		)
		(property "MPN" "CR0402-FX-2000GLF"
			(at 0 0 270)
			(unlocked yes)
			(layer "B.Fab")
			(hide yes)
			(effects
				(font
					(size 1 1)
					(thickness 0.15)
				)
				(justify mirror)
			)
		)
		(property "Val" "200R"
			(at 0 0 270)
			(unlocked yes)
			(layer "B.Fab")
			(hide yes)
			(effects
				(font
					(size 1 1)
					(thickness 0.15)
				)
				(justify mirror)
			)
		)
		(property "License" "Apache-2.0"
			(at 0 0 270)
			(unlocked yes)
			(layer "B.Fab")
			(hide yes)
			(effects
				(font
					(size 1 1)
					(thickness 0.15)
				)
				(justify mirror)
			)
		)
		(property "Author" "Antmicro"
			(at 0 0 270)
			(unlocked yes)
			(layer "B.Fab")
			(hide yes)
			(effects
				(font
					(size 1 1)
					(thickness 0.15)
				)
				(justify mirror)
			)
		)
		(property "Tolerance" "1%"
			(at 0 0 270)
			(unlocked yes)
			(layer "B.Fab")
			(hide yes)
			(effects
				(font
					(size 1 1)
					(thickness 0.15)
				)
				(justify mirror)
			)
		)
		(sheetname "/Ethernet/")
		(sheetfile "ethernet.kicad_sch")
		(attr smd)
		(fp_rect
			(start -0.925 0.47)
			(end 0.925 -0.47)
			(stroke
				(width 0.05)
				(type default)
			)
			(fill no)
			(layer "B.CrtYd")
		)
		(fp_rect
			(start -0.5 0.25)
			(end 0.5 -0.25)
			(stroke
				(width 0.15)
				(type solid)
			)
			(fill no)
			(layer "B.Fab")
		)
		(fp_text user "Author: Antmicro"
			(at -0.95 -4.169 90)
			(layer "B.Fab")
			(effects
				(font
					(size 0.7 0.7)
					(thickness 0.15)
				)
				(justify left bottom mirror)
			)
		)
		(fp_text user "${REFERENCE}"
			(at -0.95 -3.168 90)
			(layer "B.Fab")
			(effects
				(font
					(size 0.7 0.7)
					(thickness 0.15)
				)
				(justify left bottom mirror)
			)
		)
		(fp_text user "License: Apache-2.0"
			(at -0.95 -5.169 90)
			(layer "B.Fab")
			(effects
				(font
					(size 0.7 0.7)
					(thickness 0.15)
				)
				(justify left bottom mirror)
			)
		)
		(pad "1" smd roundrect
			(at -0.48 0 270)
			(size 0.59 0.64)
			(layers "B.Cu" "B.Mask" "B.Paste")
			(roundrect_rratio 0.25)
			(net 175 "Net-(J401-LED_YEL-)")
			(pintype "passive")
		)
		(pad "2" smd roundrect
			(at 0.48 0 270)
			(size 0.59 0.64)
			(layers "B.Cu" "B.Mask" "B.Paste")
			(roundrect_rratio 0.25)
			(net 212 "/Compute module/ETHERNET.LED_ACT")
			(pintype "passive")
		)
	)
	(footprint "antmicro-footprints:R_0603_1608Metric"
		(layer "B.Cu")
		(at 40.1 162.7 90)
		(descr "Resistor SMD 0603")
		(tags "resistor SMD 0603")
		(property "Reference" "R328"
			(at -1.4 -0.7 90)
			(layer "B.SilkS")
			(effects
				(font
					(size 0.7 0.7)
					(thickness 0.15)
				)
				(justify right bottom mirror)
			)
		)
		(property "Value" "R_0R_22.4A_0603"
			(at 0 -1.6 90)
			(layer "B.Fab")
			(effects
				(font
					(size 0.7 0.7)
					(thickness 0.15)
				)
				(justify right bottom mirror)
			)
		)
		(property "Datasheet" "https://fscdn.rohm.com/en/products/databook/datasheet/passive/resistor/chip_resistor/pmr-jpw-e.pdf"
			(at 0 0 90)
			(layer "B.Fab")
			(hide yes)
			(effects
				(font
					(size 1.27 1.27)
					(thickness 0.15)
				)
			)
		)
		(property "Manufacturer" "ROHM Semiconductor"
			(at 0 0 90)
			(unlocked yes)
			(layer "B.Fab")
			(hide yes)
			(effects
				(font
					(size 1 1)
					(thickness 0.15)
				)
				(justify mirror)
			)
		)
		(property "MPN" "PMR03EZPJ000"
			(at 0 0 90)
			(unlocked yes)
			(layer "B.Fab")
			(hide yes)
			(effects
				(font
					(size 1 1)
					(thickness 0.15)
				)
				(justify mirror)
			)
		)
		(property "Val" "0R"
			(at 0 0 90)
			(unlocked yes)
			(layer "B.Fab")
			(hide yes)
			(effects
				(font
					(size 1 1)
					(thickness 0.15)
				)
				(justify mirror)
			)
		)
		(property "Author" "Antmicro"
			(at 0 0 90)
			(unlocked yes)
			(layer "B.Fab")
			(hide yes)
			(effects
				(font
					(size 1 1)
					(thickness 0.15)
				)
				(justify mirror)
			)
		)
		(property "License" "Apache-2.0"
			(at 0 0 90)
			(unlocked yes)
			(layer "B.Fab")
			(hide yes)
			(effects
				(font
					(size 1 1)
					(thickness 0.15)
				)
				(justify mirror)
			)
		)
		(property "Max. Curr." "22.4A"
			(at 0 0 90)
			(unlocked yes)
			(layer "B.Fab")
			(hide yes)
			(effects
				(font
					(size 1 1)
					(thickness 0.15)
				)
				(justify mirror)
			)
		)
		(property "Tolerance" "template_tolerance"
			(at 0 0 90)
			(unlocked yes)
			(layer "B.Fab")
			(hide yes)
			(effects
				(font
					(size 1 1)
					(thickness 0.15)
				)
				(justify mirror)
			)
		)
		(sheetname "/Supply/")
		(sheetfile "supply.kicad_sch")
		(attr smd exclude_from_pos_files exclude_from_bom dnp)
		(fp_line
			(start -0.15 -0.4)
			(end 0.15 -0.4)
			(stroke
				(width 0.15)
				(type solid)
			)
			(layer "B.SilkS")
		)
		(fp_line
			(start -0.15 0.4)
			(end 0.15 0.4)
			(stroke
				(width 0.15)
				(type solid)
			)
			(layer "B.SilkS")
		)
		(fp_rect
			(start -1.25 0.65)
			(end 1.25 -0.65)
			(stroke
				(width 0.05)
				(type solid)
			)
			(fill no)
			(layer "B.CrtYd")
		)
		(fp_rect
			(start -0.8 0.4)
			(end 0.8 -0.4)
			(stroke
				(width 0.15)
				(type solid)
			)
			(fill no)
			(layer "B.Fab")
		)
		(fp_text user "${REFERENCE}"
			(at -1.25 -3.898 270)
			(layer "B.Fab")
			(effects
				(font
					(size 0.7 0.7)
					(thickness 0.15)
				)
				(justify left bottom mirror)
			)
		)
		(fp_text user "License: Apache-2.0"
			(at -1.25 -5.9 270)
			(layer "B.Fab")
			(effects
				(font
					(size 0.7 0.7)
					(thickness 0.15)
				)
				(justify left bottom mirror)
			)
		)
		(fp_text user "Author: Antmicro"
			(at -1.25 -4.9 270)
			(layer "B.Fab")
			(effects
				(font
					(size 0.7 0.7)
					(thickness 0.15)
				)
				(justify left bottom mirror)
			)
		)
		(pad "1" smd roundrect
			(at -0.7 0 90)
			(size 0.8 1)
			(layers "B.Cu" "B.Mask" "B.Paste")
			(roundrect_rratio 0.2)
			(net 472 "Net-(D301-C)")
			(pintype "passive")
		)
		(pad "2" smd roundrect
			(at 0.7 0 90)
			(size 0.8 1)
			(layers "B.Cu" "B.Mask" "B.Paste")
			(roundrect_rratio 0.2)
			(net 21 "/Supply/VCC_IN")
			(pintype "passive")
		)
	)
	(footprint "antmicro-footprints:C_0402_1005Metric"
		(layer "B.Cu")
		(at 134.567962 146.4915 -90)
		(descr "Capacitor SMD 0402")
		(tags "capacitor SMD 0402")
		(property "Reference" "C603"
			(at -3.765 -0.16 90)
			(layer "B.SilkS")
			(effects
				(font
					(size 0.7 0.7)
					(thickness 0.15)
				)
				(justify left bottom mirror)
			)
		)
		(property "Value" "C_1u_0402"
			(at -1.022927 -2.155213 90)
			(layer "B.Fab")
			(effects
				(font
					(size 0.7 0.7)
					(thickness 0.15)
				)
				(justify left bottom mirror)
			)
		)
		(property "Datasheet" "https://product.tdk.com/en/search/capacitor/ceramic/mlcc/info?part_no=C1005X6S1A105K050BC"
			(at 0 0 270)
			(layer "B.Fab")
			(hide yes)
			(effects
				(font
					(size 1.27 1.27)
					(thickness 0.15)
				)
			)
		)
		(property "Manufacturer" "TDK"
			(at 0 0 270)
			(unlocked yes)
			(layer "B.Fab")
			(hide yes)
			(effects
				(font
					(size 1 1)
					(thickness 0.15)
				)
				(justify mirror)
			)
		)
		(property "MPN" "C1005X6S1A105K050BC"
			(at 0 0 270)
			(unlocked yes)
			(layer "B.Fab")
			(hide yes)
			(effects
				(font
					(size 1 1)
					(thickness 0.15)
				)
				(justify mirror)
			)
		)
		(property "Val" "1u"
			(at 0 0 270)
			(unlocked yes)
			(layer "B.Fab")
			(hide yes)
			(effects
				(font
					(size 1 1)
					(thickness 0.15)
				)
				(justify mirror)
			)
		)
		(property "License" "Apache-2.0"
			(at 0 0 270)
			(unlocked yes)
			(layer "B.Fab")
			(hide yes)
			(effects
				(font
					(size 1 1)
					(thickness 0.15)
				)
				(justify mirror)
			)
		)
		(property "Author" "Antmicro"
			(at 0 0 270)
			(unlocked yes)
			(layer "B.Fab")
			(hide yes)
			(effects
				(font
					(size 1 1)
					(thickness 0.15)
				)
				(justify mirror)
			)
		)
		(property "Voltage" ""
			(at 0 0 270)
			(unlocked yes)
			(layer "B.Fab")
			(hide yes)
			(effects
				(font
					(size 1 1)
					(thickness 0.15)
				)
				(justify mirror)
			)
		)
		(property "Dielectric" ""
			(at 0 0 270)
			(unlocked yes)
			(layer "B.Fab")
			(hide yes)
			(effects
				(font
					(size 1 1)
					(thickness 0.15)
				)
				(justify mirror)
			)
		)
		(sheetname "/CSI/")
		(sheetfile "csi.kicad_sch")
		(attr smd)
		(fp_rect
			(start -0.925 0.47)
			(end 0.925 -0.47)
			(stroke
				(width 0.05)
				(type default)
			)
			(fill no)
			(layer "B.CrtYd")
		)
		(fp_line
			(start -0.494 0.25)
			(end 0.504 0.25)
			(stroke
				(width 0.15)
				(type solid)
			)
			(layer "B.Fab")
		)
		(fp_line
			(start 0.504 0.25)
			(end 0.504 -0.248)
			(stroke
				(width 0.15)
				(type solid)
			)
			(layer "B.Fab")
		)
		(fp_line
			(start -0.494 -0.248)
			(end -0.494 0.25)
			(stroke
				(width 0.15)
				(type solid)
			)
			(layer "B.Fab")
		)
		(fp_line
			(start 0.504 -0.248)
			(end -0.494 -0.248)
			(stroke
				(width 0.15)
				(type solid)
			)
			(layer "B.Fab")
		)
		(fp_text user "License: Apache-2.0"
			(at -0.939 -5.799 90)
			(layer "B.Fab")
			(effects
				(font
					(size 0.7 0.7)
					(thickness 0.15)
				)
				(justify left bottom mirror)
			)
		)
		(fp_text user "${REFERENCE}"
			(at -0.939 -4.599 90)
			(layer "B.Fab")
			(effects
				(font
					(size 0.7 0.7)
					(thickness 0.15)
				)
				(justify left bottom mirror)
			)
		)
		(fp_text user "Author: Antmicro"
			(at -0.939 -3.399 90)
			(layer "B.Fab")
			(effects
				(font
					(size 0.7 0.7)
					(thickness 0.15)
				)
				(justify left bottom mirror)
			)
		)
		(pad "1" smd roundrect
			(at -0.48 0 270)
			(size 0.59 0.64)
			(layers "B.Cu" "B.Mask" "B.Paste")
			(roundrect_rratio 0.25)
			(net 3 "GND")
			(pintype "passive")
		)
		(pad "2" smd roundrect
			(at 0.48 0 270)
			(size 0.59 0.64)
			(layers "B.Cu" "B.Mask" "B.Paste")
			(roundrect_rratio 0.25)
			(net 19 "/CSI/CSI_3V3")
			(pintype "passive")
		)
	)
	(footprint "antmicro-footprints:R_0402_1005Metric"
		(layer "B.Cu")
		(at 86.842962 122.1665 180)
		(descr "Resistor SMD 0402")
		(tags "resistor SMD 0402")
		(property "Reference" "R909"
			(at 0.985 0.4 0)
			(layer "B.SilkS")
			(effects
				(font
					(size 0.7 0.7)
					(thickness 0.15)
				)
				(justify left bottom mirror)
			)
		)
		(property "Value" "R_10k_0402"
			(at -1.011843 -1.772047 0)
			(layer "B.Fab")
			(effects
				(font
					(size 0.7 0.7)
					(thickness 0.15)
				)
				(justify left bottom mirror)
			)
		)
		(property "Datasheet" "https://www.bourns.com/docs/product-datasheets/cr.pdf"
			(at 0 0 180)
			(layer "B.Fab")
			(hide yes)
			(effects
				(font
					(size 1.27 1.27)
					(thickness 0.15)
				)
			)
		)
		(property "Manufacturer" "Bourns"
			(at 0 0 180)
			(unlocked yes)
			(layer "B.Fab")
			(hide yes)
			(effects
				(font
					(size 1 1)
					(thickness 0.15)
				)
				(justify mirror)
			)
		)
		(property "MPN" "CR0402-FX-1002GLF"
			(at 0 0 180)
			(unlocked yes)
			(layer "B.Fab")
			(hide yes)
			(effects
				(font
					(size 1 1)
					(thickness 0.15)
				)
				(justify mirror)
			)
		)
		(property "Val" "10k"
			(at 0 0 180)
			(unlocked yes)
			(layer "B.Fab")
			(hide yes)
			(effects
				(font
					(size 1 1)
					(thickness 0.15)
				)
				(justify mirror)
			)
		)
		(property "License" "Apache-2.0"
			(at 0 0 180)
			(unlocked yes)
			(layer "B.Fab")
			(hide yes)
			(effects
				(font
					(size 1 1)
					(thickness 0.15)
				)
				(justify mirror)
			)
		)
		(property "Author" "Antmicro"
			(at 0 0 180)
			(unlocked yes)
			(layer "B.Fab")
			(hide yes)
			(effects
				(font
					(size 1 1)
					(thickness 0.15)
				)
				(justify mirror)
			)
		)
		(property "Tolerance" "1%"
			(at 0 0 180)
			(unlocked yes)
			(layer "B.Fab")
			(hide yes)
			(effects
				(font
					(size 1 1)
					(thickness 0.15)
				)
				(justify mirror)
			)
		)
		(sheetname "/USB/")
		(sheetfile "usb.kicad_sch")
		(attr smd)
		(fp_rect
			(start -0.925 0.47)
			(end 0.925 -0.47)
			(stroke
				(width 0.05)
				(type default)
			)
			(fill no)
			(layer "B.CrtYd")
		)
		(fp_rect
			(start -0.5 0.25)
			(end 0.5 -0.25)
			(stroke
				(width 0.15)
				(type solid)
			)
			(fill no)
			(layer "B.Fab")
		)
		(fp_text user "${REFERENCE}"
			(at -0.95 -3.168 0)
			(layer "B.Fab")
			(effects
				(font
					(size 0.7 0.7)
					(thickness 0.15)
				)
				(justify left bottom mirror)
			)
		)
		(fp_text user "Author: Antmicro"
			(at -0.95 -4.169 0)
			(layer "B.Fab")
			(effects
				(font
					(size 0.7 0.7)
					(thickness 0.15)
				)
				(justify left bottom mirror)
			)
		)
		(fp_text user "License: Apache-2.0"
			(at -0.95 -5.169 0)
			(layer "B.Fab")
			(effects
				(font
					(size 0.7 0.7)
					(thickness 0.15)
				)
				(justify left bottom mirror)
			)
		)
		(pad "1" smd roundrect
			(at -0.48 0 180)
			(size 0.59 0.64)
			(layers "B.Cu" "B.Mask" "B.Paste")
			(roundrect_rratio 0.25)
			(net 343 "/USB/EN_FTDI")
			(pintype "passive")
		)
		(pad "2" smd roundrect
			(at 0.48 0 180)
			(size 0.59 0.64)
			(layers "B.Cu" "B.Mask" "B.Paste")
			(roundrect_rratio 0.25)
			(net 26 "/USB/USBD_VBUS")
			(pintype "passive")
		)
	)
	(footprint "antmicro-footprints:FB_0603_1608Metric"
		(layer "B.Cu")
		(at 59.267962 116.4665 180)
		(property "Reference" "FB401"
			(at -1.7 -1.44 0)
			(layer "B.SilkS")
			(effects
				(font
					(size 0.7 0.7)
					(thickness 0.15)
				)
				(justify left bottom mirror)
			)
		)
		(property "Value" "FB_220Z_2.2A_TDK-MPZ_0603"
			(at 0 -1.5 0)
			(layer "B.Fab")
			(effects
				(font
					(size 0.7 0.7)
					(thickness 0.15)
				)
				(justify left bottom mirror)
			)
		)
		(property "Datasheet" "https://product.tdk.com/info/en/catalog/datasheets/beads_commercial_power_mpz1608_en.pdf"
			(at 0 0 180)
			(layer "B.Fab")
			(hide yes)
			(effects
				(font
					(size 1.27 1.27)
					(thickness 0.15)
				)
			)
		)
		(property "MPN" "MPZ1608S221ATA00"
			(at 0 0 180)
			(unlocked yes)
			(layer "B.Fab")
			(hide yes)
			(effects
				(font
					(size 1 1)
					(thickness 0.15)
				)
				(justify mirror)
			)
		)
		(property "Manufacturer" "TDK"
			(at 0 0 180)
			(unlocked yes)
			(layer "B.Fab")
			(hide yes)
			(effects
				(font
					(size 1 1)
					(thickness 0.15)
				)
				(justify mirror)
			)
		)
		(property "Author" "Antmicro"
			(at 0 0 180)
			(unlocked yes)
			(layer "B.Fab")
			(hide yes)
			(effects
				(font
					(size 1 1)
					(thickness 0.15)
				)
				(justify mirror)
			)
		)
		(property "License" "Apache-2.0"
			(at 0 0 180)
			(unlocked yes)
			(layer "B.Fab")
			(hide yes)
			(effects
				(font
					(size 1 1)
					(thickness 0.15)
				)
				(justify mirror)
			)
		)
		(property "Val" "220Z/2.2A"
			(at 0 0 180)
			(unlocked yes)
			(layer "B.Fab")
			(hide yes)
			(effects
				(font
					(size 1 1)
					(thickness 0.15)
				)
				(justify mirror)
			)
		)
		(property "Current" ""
			(at 0 0 180)
			(unlocked yes)
			(layer "B.Fab")
			(hide yes)
			(effects
				(font
					(size 1 1)
					(thickness 0.15)
				)
				(justify mirror)
			)
		)
		(sheetname "/Ethernet/")
		(sheetfile "ethernet.kicad_sch")
		(attr smd)
		(fp_line
			(start -0.15 0.4)
			(end 0.15 0.4)
			(stroke
				(width 0.15)
				(type solid)
			)
			(layer "B.SilkS")
		)
		(fp_line
			(start -0.15 -0.4)
			(end 0.15 -0.4)
			(stroke
				(width 0.15)
				(type solid)
			)
			(layer "B.SilkS")
		)
		(fp_rect
			(start -1.25 0.65)
			(end 1.25 -0.65)
			(stroke
				(width 0.05)
				(type solid)
			)
			(fill no)
			(layer "B.CrtYd")
		)
		(fp_line
			(start 0.8 0.408)
			(end 0.8 -0.406)
			(stroke
				(width 0.15)
				(type solid)
			)
			(layer "B.Fab")
		)
		(fp_line
			(start 0.8 0.408)
			(end -0.803 0.408)
			(stroke
				(width 0.15)
				(type solid)
			)
			(layer "B.Fab")
		)
		(fp_line
			(start 0.8 -0.406)
			(end -0.803 -0.406)
			(stroke
				(width 0.15)
				(type solid)
			)
			(layer "B.Fab")
		)
		(fp_line
			(start -0.803 -0.406)
			(end -0.803 0.408)
			(stroke
				(width 0.15)
				(type solid)
			)
			(layer "B.Fab")
		)
		(fp_text user "Author: Antmicro"
			(at -1.653 -3.162 0)
			(layer "B.Fab")
			(effects
				(font
					(size 0.7 0.7)
					(thickness 0.15)
				)
				(justify left bottom mirror)
			)
		)
		(fp_text user "License: Apache-2.0"
			(at -1.653 -5.9 0)
			(layer "B.Fab")
			(effects
				(font
					(size 0.7 0.7)
					(thickness 0.15)
				)
				(justify left bottom mirror)
			)
		)
		(fp_text user "${REFERENCE}"
			(at -1.653 -4.6 0)
			(layer "B.Fab")
			(effects
				(font
					(size 0.7 0.7)
					(thickness 0.15)
				)
				(justify left bottom mirror)
			)
		)
		(pad "1" smd roundrect
			(at -0.7 0 180)
			(size 0.8 1)
			(layers "B.Cu" "B.Mask" "B.Paste")
			(roundrect_rratio 0.2)
			(net 117 "Net-(D401-Pad2)")
			(pintype "passive")
		)
		(pad "2" smd roundrect
			(at 0.7 0 180)
			(size 0.8 1)
			(layers "B.Cu" "B.Mask" "B.Paste")
			(roundrect_rratio 0.2)
			(net 33 "/Ethernet/VDD")
			(pintype "passive")
		)
	)
	(footprint "antmicro-footprints:R_0402_1005Metric"
		(layer "B.Cu")
		(at 118.892962 120.0415 90)
		(descr "Resistor SMD 0402")
		(tags "resistor SMD 0402")
		(property "Reference" "R503"
			(at -2.895 -0.565 90)
			(layer "B.SilkS")
			(effects
				(font
					(size 0.7 0.7)
					(thickness 0.15)
				)
				(justify right bottom mirror)
			)
		)
		(property "Value" "R_10k_0402"
			(at -1.011843 -1.772047 90)
			(layer "B.Fab")
			(effects
				(font
					(size 0.7 0.7)
					(thickness 0.15)
				)
				(justify right bottom mirror)
			)
		)
		(property "Datasheet" "https://www.bourns.com/docs/product-datasheets/cr.pdf"
			(at 0 0 90)
			(layer "B.Fab")
			(hide yes)
			(effects
				(font
					(size 1.27 1.27)
					(thickness 0.15)
				)
			)
		)
		(property "Manufacturer" "Bourns"
			(at 0 0 90)
			(unlocked yes)
			(layer "B.Fab")
			(hide yes)
			(effects
				(font
					(size 1 1)
					(thickness 0.15)
				)
				(justify mirror)
			)
		)
		(property "MPN" "CR0402-FX-1002GLF"
			(at 0 0 90)
			(unlocked yes)
			(layer "B.Fab")
			(hide yes)
			(effects
				(font
					(size 1 1)
					(thickness 0.15)
				)
				(justify mirror)
			)
		)
		(property "Val" "10k"
			(at 0 0 90)
			(unlocked yes)
			(layer "B.Fab")
			(hide yes)
			(effects
				(font
					(size 1 1)
					(thickness 0.15)
				)
				(justify mirror)
			)
		)
		(property "License" "Apache-2.0"
			(at 0 0 90)
			(unlocked yes)
			(layer "B.Fab")
			(hide yes)
			(effects
				(font
					(size 1 1)
					(thickness 0.15)
				)
				(justify mirror)
			)
		)
		(property "Author" "Antmicro"
			(at 0 0 90)
			(unlocked yes)
			(layer "B.Fab")
			(hide yes)
			(effects
				(font
					(size 1 1)
					(thickness 0.15)
				)
				(justify mirror)
			)
		)
		(property "Tolerance" "1%"
			(at 0 0 90)
			(unlocked yes)
			(layer "B.Fab")
			(hide yes)
			(effects
				(font
					(size 1 1)
					(thickness 0.15)
				)
				(justify mirror)
			)
		)
		(sheetname "/NVMe & microSD/")
		(sheetfile "nvme-micro-sd.kicad_sch")
		(attr smd)
		(fp_rect
			(start -0.925 0.47)
			(end 0.925 -0.47)
			(stroke
				(width 0.05)
				(type default)
			)
			(fill no)
			(layer "B.CrtYd")
		)
		(fp_rect
			(start -0.5 0.25)
			(end 0.5 -0.25)
			(stroke
				(width 0.15)
				(type solid)
			)
			(fill no)
			(layer "B.Fab")
		)
		(fp_text user "License: Apache-2.0"
			(at -0.95 -5.169 270)
			(layer "B.Fab")
			(effects
				(font
					(size 0.7 0.7)
					(thickness 0.15)
				)
				(justify left bottom mirror)
			)
		)
		(fp_text user "${REFERENCE}"
			(at -0.95 -3.168 270)
			(layer "B.Fab")
			(effects
				(font
					(size 0.7 0.7)
					(thickness 0.15)
				)
				(justify left bottom mirror)
			)
		)
		(fp_text user "Author: Antmicro"
			(at -0.95 -4.169 270)
			(layer "B.Fab")
			(effects
				(font
					(size 0.7 0.7)
					(thickness 0.15)
				)
				(justify left bottom mirror)
			)
		)
		(pad "1" smd roundrect
			(at -0.48 0 90)
			(size 0.59 0.64)
			(layers "B.Cu" "B.Mask" "B.Paste")
			(roundrect_rratio 0.25)
			(net 182 "Net-(J501-~{PEWAKE})")
			(pintype "passive")
		)
		(pad "2" smd roundrect
			(at 0.48 0 90)
			(size 0.59 0.64)
			(layers "B.Cu" "B.Mask" "B.Paste")
			(roundrect_rratio 0.25)
			(net 65 "3V3_SSD")
			(pintype "passive")
		)
	)
	(footprint "antmicro-footprints:R_0402_1005Metric"
		(layer "B.Cu")
		(at 54.352962 153.2565 180)
		(descr "Resistor SMD 0402")
		(tags "resistor SMD 0402")
		(property "Reference" "R314"
			(at -0.555 0.415 0)
			(layer "B.SilkS")
			(effects
				(font
					(size 0.7 0.7)
					(thickness 0.15)
				)
				(justify left bottom mirror)
			)
		)
		(property "Value" "R_10k_0402"
			(at -1.011843 -1.772047 0)
			(layer "B.Fab")
			(effects
				(font
					(size 0.7 0.7)
					(thickness 0.15)
				)
				(justify left bottom mirror)
			)
		)
		(property "Datasheet" "https://www.bourns.com/docs/product-datasheets/cr.pdf"
			(at 0 0 180)
			(layer "B.Fab")
			(hide yes)
			(effects
				(font
					(size 1.27 1.27)
					(thickness 0.15)
				)
			)
		)
		(property "Manufacturer" "Bourns"
			(at 0 0 180)
			(unlocked yes)
			(layer "B.Fab")
			(hide yes)
			(effects
				(font
					(size 1 1)
					(thickness 0.15)
				)
				(justify mirror)
			)
		)
		(property "MPN" "CR0402-FX-1002GLF"
			(at 0 0 180)
			(unlocked yes)
			(layer "B.Fab")
			(hide yes)
			(effects
				(font
					(size 1 1)
					(thickness 0.15)
				)
				(justify mirror)
			)
		)
		(property "Val" "10k"
			(at 0 0 180)
			(unlocked yes)
			(layer "B.Fab")
			(hide yes)
			(effects
				(font
					(size 1 1)
					(thickness 0.15)
				)
				(justify mirror)
			)
		)
		(property "License" "Apache-2.0"
			(at 0 0 180)
			(unlocked yes)
			(layer "B.Fab")
			(hide yes)
			(effects
				(font
					(size 1 1)
					(thickness 0.15)
				)
				(justify mirror)
			)
		)
		(property "Author" "Antmicro"
			(at 0 0 180)
			(unlocked yes)
			(layer "B.Fab")
			(hide yes)
			(effects
				(font
					(size 1 1)
					(thickness 0.15)
				)
				(justify mirror)
			)
		)
		(property "Tolerance" "1%"
			(at 0 0 180)
			(unlocked yes)
			(layer "B.Fab")
			(hide yes)
			(effects
				(font
					(size 1 1)
					(thickness 0.15)
				)
				(justify mirror)
			)
		)
		(sheetname "/Supply/")
		(sheetfile "supply.kicad_sch")
		(attr smd)
		(fp_rect
			(start -0.925 0.47)
			(end 0.925 -0.47)
			(stroke
				(width 0.05)
				(type default)
			)
			(fill no)
			(layer "B.CrtYd")
		)
		(fp_rect
			(start -0.5 0.25)
			(end 0.5 -0.25)
			(stroke
				(width 0.15)
				(type solid)
			)
			(fill no)
			(layer "B.Fab")
		)
		(fp_text user "${REFERENCE}"
			(at -0.95 -3.168 0)
			(layer "B.Fab")
			(effects
				(font
					(size 0.7 0.7)
					(thickness 0.15)
				)
				(justify left bottom mirror)
			)
		)
		(fp_text user "License: Apache-2.0"
			(at -0.95 -5.169 0)
			(layer "B.Fab")
			(effects
				(font
					(size 0.7 0.7)
					(thickness 0.15)
				)
				(justify left bottom mirror)
			)
		)
		(fp_text user "Author: Antmicro"
			(at -0.95 -4.169 0)
			(layer "B.Fab")
			(effects
				(font
					(size 0.7 0.7)
					(thickness 0.15)
				)
				(justify left bottom mirror)
			)
		)
		(pad "1" smd roundrect
			(at -0.48 0 180)
			(size 0.59 0.64)
			(layers "B.Cu" "B.Mask" "B.Paste")
			(roundrect_rratio 0.25)
			(net 3 "GND")
			(pintype "passive")
		)
		(pad "2" smd roundrect
			(at 0.48 0 180)
			(size 0.59 0.64)
			(layers "B.Cu" "B.Mask" "B.Paste")
			(roundrect_rratio 0.25)
			(net 351 "/Supply/EN_5V")
			(pintype "passive")
		)
	)
	(footprint "antmicro-footprints:TSOT23-6"
		(layer "B.Cu")
		(at 110.267962 133.5865 90)
		(property "Reference" "U301"
			(at 2.25 -1.555 0)
			(layer "B.SilkS")
			(effects
				(font
					(size 0.7 0.7)
					(thickness 0.15)
				)
				(justify right bottom mirror)
			)
		)
		(property "Value" "AP62301_TSOT"
			(at 0 -2.6 90)
			(layer "B.Fab")
			(effects
				(font
					(size 0.7 0.7)
					(thickness 0.15)
				)
				(justify right bottom mirror)
			)
		)
		(property "Datasheet" "https://www.diodes.com/assets/Datasheets/AP62300_AP62301_AP62300T.pdf"
			(at 0 0 90)
			(layer "B.Fab")
			(hide yes)
			(effects
				(font
					(size 1.27 1.27)
					(thickness 0.15)
				)
			)
		)
		(property "MPN" "AP62301WU-7"
			(at 0 0 90)
			(unlocked yes)
			(layer "B.Fab")
			(hide yes)
			(effects
				(font
					(size 1 1)
					(thickness 0.15)
				)
				(justify mirror)
			)
		)
		(property "Manufacturer" "Diodes Incorporated"
			(at 0 0 90)
			(unlocked yes)
			(layer "B.Fab")
			(hide yes)
			(effects
				(font
					(size 1 1)
					(thickness 0.15)
				)
				(justify mirror)
			)
		)
		(property "Author" "Antmicro"
			(at 0 0 90)
			(unlocked yes)
			(layer "B.Fab")
			(hide yes)
			(effects
				(font
					(size 1 1)
					(thickness 0.15)
				)
				(justify mirror)
			)
		)
		(property "License" "Apache-2.0"
			(at 0 0 90)
			(unlocked yes)
			(layer "B.Fab")
			(hide yes)
			(effects
				(font
					(size 1 1)
					(thickness 0.15)
				)
				(justify mirror)
			)
		)
		(sheetname "/Supply/")
		(sheetfile "supply.kicad_sch")
		(attr smd)
		(fp_line
			(start 1 -1.55)
			(end -1 -1.55)
			(stroke
				(width 0.15)
				(type solid)
			)
			(layer "B.SilkS")
		)
		(fp_line
			(start 1 -1.55)
			(end 1 -1.4)
			(stroke
				(width 0.15)
				(type solid)
			)
			(layer "B.SilkS")
		)
		(fp_line
			(start -1 -1.55)
			(end -1 -1.4)
			(stroke
				(width 0.15)
				(type solid)
			)
			(layer "B.SilkS")
		)
		(fp_line
			(start 1 1.497)
			(end 1 1.375)
			(stroke
				(width 0.15)
				(type solid)
			)
			(layer "B.SilkS")
		)
		(fp_line
			(start 1 1.497)
			(end -1 1.5)
			(stroke
				(width 0.15)
				(type solid)
			)
			(layer "B.SilkS")
		)
		(fp_line
			(start -1 1.5)
			(end -1 1.375)
			(stroke
				(width 0.15)
				(type solid)
			)
			(layer "B.SilkS")
		)
		(fp_circle
			(center -1.44 1.5)
			(end -1.39 1.5)
			(stroke
				(width 0.15)
				(type solid)
			)
			(fill yes)
			(layer "B.SilkS")
		)
		(fp_rect
			(start 1.93 1.7)
			(end -1.93 -1.7)
			(stroke
				(width 0.05)
				(type solid)
			)
			(fill no)
			(layer "B.CrtYd")
		)
		(fp_line
			(start -0.45 1.521)
			(end -0.876 1.096)
			(stroke
				(width 0.15)
				(type solid)
			)
			(layer "B.Fab")
		)
		(fp_rect
			(start 0.875 -1.528)
			(end -0.875 1.525)
			(stroke
				(width 0.15)
				(type solid)
			)
			(fill no)
			(layer "B.Fab")
		)
		(fp_text user "Author: Antmicro"
			(at -1.93 -5 270)
			(layer "B.Fab")
			(effects
				(font
					(size 0.7 0.7)
					(thickness 0.15)
				)
				(justify left bottom mirror)
			)
		)
		(fp_text user "${REFERENCE}"
			(at -1.93 -3.8 270)
			(layer "B.Fab")
			(effects
				(font
					(size 0.7 0.7)
					(thickness 0.15)
				)
				(justify left bottom mirror)
			)
		)
		(fp_text user "License: Apache-2.0"
			(at -1.93 -6.199 270)
			(layer "B.Fab")
			(effects
				(font
					(size 0.7 0.7)
					(thickness 0.15)
				)
				(justify left bottom mirror)
			)
		)
		(pad "1" smd rect
			(at -1.301 0.947 180)
			(size 0.7 1.2)
			(layers "B.Cu" "B.Mask" "B.Paste")
			(net 3 "GND")
			(pinfunction "GND")
			(pintype "power_in")
		)
		(pad "2" smd rect
			(at -1.301 -0.004 180)
			(size 0.7 1.2)
			(layers "B.Cu" "B.Mask" "B.Paste")
			(net 45 "/Supply/SW_M2")
			(pinfunction "SW")
			(pintype "power_out")
		)
		(pad "3" smd rect
			(at -1.301 -0.954 180)
			(size 0.7 1.2)
			(layers "B.Cu" "B.Mask" "B.Paste")
			(net 43 "VCC")
			(pinfunction "VIN")
			(pintype "power_in")
		)
		(pad "4" smd rect
			(at 1.299 -0.954 180)
			(size 0.7 1.2)
			(layers "B.Cu" "B.Mask" "B.Paste")
			(net 354 "/Supply/FB_M2")
			(pinfunction "FB")
			(pintype "input")
		)
		(pad "5" smd rect
			(at 1.299 -0.004 180)
			(size 0.7 1.2)
			(layers "B.Cu" "B.Mask" "B.Paste")
			(net 380 "/Compute module/NVMe_EN")
			(pinfunction "EN")
			(pintype "input")
		)
		(pad "6" smd rect
			(at 1.299 0.947 180)
			(size 0.7 1.2)
			(layers "B.Cu" "B.Mask" "B.Paste")
			(net 48 "Net-(U301-BST)")
			(pinfunction "BST")
			(pintype "output")
		)
	)
	(footprint "antmicro-footprints:R_0402_1005Metric"
		(layer "B.Cu")
		(at 107.127962 133.0415 90)
		(descr "Resistor SMD 0402")
		(tags "resistor SMD 0402")
		(property "Reference" "R319"
			(at 0.825 0.32 90)
			(layer "B.SilkS")
			(effects
				(font
					(size 0.7 0.7)
					(thickness 0.15)
				)
				(justify right bottom mirror)
			)
		)
		(property "Value" "R_2k2_0402"
			(at -1.011843 -1.772047 90)
			(layer "B.Fab")
			(effects
				(font
					(size 0.7 0.7)
					(thickness 0.15)
				)
				(justify right bottom mirror)
			)
		)
		(property "Datasheet" "https://www.bourns.com/docs/product-datasheets/cr.pdf"
			(at 0 0 90)
			(layer "B.Fab")
			(hide yes)
			(effects
				(font
					(size 1.27 1.27)
					(thickness 0.15)
				)
			)
		)
		(property "MPN" "CR0402-FX-2201GLF"
			(at 0 0 90)
			(unlocked yes)
			(layer "B.Fab")
			(hide yes)
			(effects
				(font
					(size 1 1)
					(thickness 0.15)
				)
				(justify mirror)
			)
		)
		(property "Manufacturer" "Bourns"
			(at 0 0 90)
			(unlocked yes)
			(layer "B.Fab")
			(hide yes)
			(effects
				(font
					(size 1 1)
					(thickness 0.15)
				)
				(justify mirror)
			)
		)
		(property "License" "Apache-2.0"
			(at 0 0 90)
			(unlocked yes)
			(layer "B.Fab")
			(hide yes)
			(effects
				(font
					(size 1 1)
					(thickness 0.15)
				)
				(justify mirror)
			)
		)
		(property "Author" "Antmicro"
			(at 0 0 90)
			(unlocked yes)
			(layer "B.Fab")
			(hide yes)
			(effects
				(font
					(size 1 1)
					(thickness 0.15)
				)
				(justify mirror)
			)
		)
		(property "Val" "2k2"
			(at 0 0 90)
			(unlocked yes)
			(layer "B.Fab")
			(hide yes)
			(effects
				(font
					(size 1 1)
					(thickness 0.15)
				)
				(justify mirror)
			)
		)
		(property "Tolerance" "1%"
			(at 0 0 90)
			(unlocked yes)
			(layer "B.Fab")
			(hide yes)
			(effects
				(font
					(size 1 1)
					(thickness 0.15)
				)
				(justify mirror)
			)
		)
		(sheetname "/Supply/")
		(sheetfile "supply.kicad_sch")
		(attr smd)
		(fp_rect
			(start -0.925 0.47)
			(end 0.925 -0.47)
			(stroke
				(width 0.05)
				(type default)
			)
			(fill no)
			(layer "B.CrtYd")
		)
		(fp_rect
			(start -0.5 0.25)
			(end 0.5 -0.25)
			(stroke
				(width 0.15)
				(type solid)
			)
			(fill no)
			(layer "B.Fab")
		)
		(fp_text user "Author: Antmicro"
			(at -0.95 -4.169 270)
			(layer "B.Fab")
			(effects
				(font
					(size 0.7 0.7)
					(thickness 0.15)
				)
				(justify left bottom mirror)
			)
		)
		(fp_text user "${REFERENCE}"
			(at -0.95 -3.168 270)
			(layer "B.Fab")
			(effects
				(font
					(size 0.7 0.7)
					(thickness 0.15)
				)
				(justify left bottom mirror)
			)
		)
		(fp_text user "License: Apache-2.0"
			(at -0.95 -5.169 270)
			(layer "B.Fab")
			(effects
				(font
					(size 0.7 0.7)
					(thickness 0.15)
				)
				(justify left bottom mirror)
			)
		)
		(pad "1" smd roundrect
			(at -0.48 0 90)
			(size 0.59 0.64)
			(layers "B.Cu" "B.Mask" "B.Paste")
			(roundrect_rratio 0.25)
			(net 3 "GND")
			(pintype "passive")
		)
		(pad "2" smd roundrect
			(at 0.48 0 90)
			(size 0.59 0.64)
			(layers "B.Cu" "B.Mask" "B.Paste")
			(roundrect_rratio 0.25)
			(net 354 "/Supply/FB_M2")
			(pintype "passive")
		)
	)
	(footprint "antmicro-footprints:Spacer_Drill3.7mm_H2mm_9774020151R"
		(layer "B.Cu")
		(at 68.117962 151.7415 180)
		(descr "Spacer M=3 h=2mm fi=5.1mm")
		(property "Reference" "H701"
			(at 0 3.2 0)
			(layer "B.SilkS")
			(effects
				(font
					(size 0.7 0.7)
					(thickness 0.15)
				)
				(justify left bottom mirror)
			)
		)
		(property "Value" "Spacer_Drill3.7mm_H2mm_9774020151R"
			(at 0 -4 0)
			(layer "B.Fab")
			(effects
				(font
					(size 0.7 0.7)
					(thickness 0.15)
				)
				(justify left bottom mirror)
			)
		)
		(property "Datasheet" "https://www.we-online.com/components/products/datasheet/9774020151R.pdf"
			(at 0 0 180)
			(layer "B.Fab")
			(hide yes)
			(effects
				(font
					(size 1.27 1.27)
					(thickness 0.15)
				)
			)
		)
		(property "Manufacturer" "Würth Elektronik"
			(at 0 0 180)
			(unlocked yes)
			(layer "B.Fab")
			(hide yes)
			(effects
				(font
					(size 1 1)
					(thickness 0.15)
				)
				(justify mirror)
			)
		)
		(property "MPN" "9774020151R"
			(at 0 0 180)
			(unlocked yes)
			(layer "B.Fab")
			(hide yes)
			(effects
				(font
					(size 1 1)
					(thickness 0.15)
				)
				(justify mirror)
			)
		)
		(property "Author" "Antmicro"
			(at 0 0 180)
			(unlocked yes)
			(layer "B.Fab")
			(hide yes)
			(effects
				(font
					(size 1 1)
					(thickness 0.15)
				)
				(justify mirror)
			)
		)
		(property "License" "Apache-2.0"
			(at 0 0 180)
			(unlocked yes)
			(layer "B.Fab")
			(hide yes)
			(effects
				(font
					(size 1 1)
					(thickness 0.15)
				)
				(justify mirror)
			)
		)
		(sheetname "/Display/")
		(sheetfile "display.kicad_sch")
		(solder_paste_margin_ratio -1)
		(attr smd)
		(fp_circle
			(center 0 0)
			(end 3.05 0)
			(stroke
				(width 0.05)
				(type solid)
			)
			(fill no)
			(layer "B.CrtYd")
		)
		(fp_circle
			(center 0 0)
			(end 2.6 0)
			(stroke
				(width 0.15)
				(type solid)
			)
			(fill no)
			(layer "B.Fab")
		)
		(fp_text user "Author: Antmicro"
			(at -9.6 -7.7 0)
			(layer "B.Fab")
			(effects
				(font
					(size 0.7 0.7)
					(thickness 0.15)
				)
				(justify left bottom mirror)
			)
		)
		(fp_text user "License: Apache-2.0"
			(at -9.6 -8.9 0)
			(layer "B.Fab")
			(effects
				(font
					(size 0.7 0.7)
					(thickness 0.15)
				)
				(justify left bottom mirror)
			)
		)
		(fp_text user "${REFERENCE}"
			(at -9.6 -6.5 0)
			(layer "B.Fab")
			(effects
				(font
					(size 0.7 0.7)
					(thickness 0.15)
				)
				(justify left bottom mirror)
			)
		)
		(pad "" smd custom
			(at -1.7 -1.7 90)
			(size 0.62 0.62)
			(layers "B.Paste")
			(thermal_bridge_angle 90)
			(options
				(clearance outline)
				(anchor circle)
			)
			(primitives
				(gr_arc
					(start 1.266786 0.24747)
					(mid 0.285453 -0.29439)
					(end -0.250195 -1.279127)
					(width 0.2)
				)
				(gr_arc
					(start 1.259603 0.339191)
					(mid 0.218448 -0.232561)
					(end -0.34334 -1.279127)
					(width 0.2)
				)
				(gr_arc
					(start 1.255279 0.431435)
					(mid 0.152481 -0.169693)
					(end -0.436309 -1.279127)
					(width 0.2)
				)
				(gr_arc
					(start 1.253811 0.524161)
					(mid 0.087542 -0.105784)
					(end -0.529126 -1.279127)
					(width 0.2)
				)
				(gr_arc
					(start 1.275473 0.621136)
					(mid 0.0309 -0.033527)
					(end -0.621807 -1.279127)
					(width 0.2)
				)
				(gr_arc
					(start 1.263664 0.711602)
					(mid -0.037759 0.026651)
					(end -0.71437 -1.279127)
					(width 0.2)
				)
				(gr_arc
					(start 1.253435 0.802342)
					(mid -0.105837 0.087395)
					(end -0.806826 -1.279127)
					(width 0.2)
				)
				(gr_arc
					(start 1.267475 0.897258)
					(mid -0.165236 0.156885)
					(end -0.899187 -1.279127)
					(width 0.2)
				)
				(gr_arc
					(start 1.270645 0.990112)
					(mid -0.228522 0.222449)
					(end -0.991463 -1.279127)
					(width 0.2)
				)
				(gr_arc
					(start 1.266278 1.081674)
					(mid -0.294507 0.285313)
					(end -1.083663 -1.279127)
					(width 0.2)
				)
				(gr_line
					(start 1.279127 0.250195)
					(end 1.279127 1.083663)
					(width 0.2)
				)
				(gr_line
					(start -0.250195 -1.279127)
					(end -1.083663 -1.279127)
					(width 0.2)
				)
			)
		)
		(pad "" smd custom
			(at -1.7 1.7 180)
			(size 0.62 0.62)
			(layers "B.Paste")
			(thermal_bridge_angle 90)
			(options
				(clearance outline)
				(anchor circle)
			)
			(primitives
				(gr_arc
					(start 1.266786 0.24747)
					(mid 0.285453 -0.29439)
					(end -0.250195 -1.279127)
					(width 0.2)
				)
				(gr_arc
					(start 1.259603 0.339191)
					(mid 0.218448 -0.232561)
					(end -0.34334 -1.279127)
					(width 0.2)
				)
				(gr_arc
					(start 1.255279 0.431435)
					(mid 0.152481 -0.169693)
					(end -0.436309 -1.279127)
					(width 0.2)
				)
				(gr_arc
					(start 1.253811 0.524161)
					(mid 0.087542 -0.105784)
					(end -0.529126 -1.279127)
					(width 0.2)
				)
				(gr_arc
					(start 1.275473 0.621136)
					(mid 0.0309 -0.033527)
					(end -0.621807 -1.279127)
					(width 0.2)
				)
				(gr_arc
					(start 1.263664 0.711602)
					(mid -0.037759 0.026651)
					(end -0.71437 -1.279127)
					(width 0.2)
				)
				(gr_arc
					(start 1.253435 0.802342)
					(mid -0.105837 0.087395)
					(end -0.806826 -1.279127)
					(width 0.2)
				)
				(gr_arc
					(start 1.267475 0.897258)
					(mid -0.165236 0.156885)
					(end -0.899187 -1.279127)
					(width 0.2)
				)
				(gr_arc
					(start 1.270645 0.990112)
					(mid -0.228522 0.222449)
					(end -0.991463 -1.279127)
					(width 0.2)
				)
				(gr_arc
					(start 1.266278 1.081674)
					(mid -0.294507 0.285313)
					(end -1.083663 -1.279127)
					(width 0.2)
				)
				(gr_line
					(start 1.279127 0.250195)
					(end 1.279127 1.083663)
					(width 0.2)
				)
				(gr_line
					(start -0.250195 -1.279127)
					(end -1.083663 -1.279127)
					(width 0.2)
				)
			)
		)
		(pad "" smd custom
			(at 1.7 -1.7)
			(size 0.62 0.62)
			(layers "B.Paste")
			(thermal_bridge_angle 90)
			(options
				(clearance outline)
				(anchor circle)
			)
			(primitives
				(gr_arc
					(start 1.266786 0.24747)
					(mid 0.285453 -0.29439)
					(end -0.250195 -1.279127)
					(width 0.2)
				)
				(gr_arc
					(start 1.259603 0.339191)
					(mid 0.218448 -0.232561)
					(end -0.34334 -1.279127)
					(width 0.2)
				)
				(gr_arc
					(start 1.255279 0.431435)
					(mid 0.152481 -0.169693)
					(end -0.436309 -1.279127)
					(width 0.2)
				)
				(gr_arc
					(start 1.253811 0.524161)
					(mid 0.087542 -0.105784)
					(end -0.529126 -1.279127)
					(width 0.2)
				)
				(gr_arc
					(start 1.275473 0.621136)
					(mid 0.0309 -0.033527)
					(end -0.621807 -1.279127)
					(width 0.2)
				)
				(gr_arc
					(start 1.263664 0.711602)
					(mid -0.037759 0.026651)
					(end -0.71437 -1.279127)
					(width 0.2)
				)
				(gr_arc
					(start 1.253435 0.802342)
					(mid -0.105837 0.087395)
					(end -0.806826 -1.279127)
					(width 0.2)
				)
				(gr_arc
					(start 1.267475 0.897258)
					(mid -0.165236 0.156885)
					(end -0.899187 -1.279127)
					(width 0.2)
				)
				(gr_arc
					(start 1.270645 0.990112)
					(mid -0.228522 0.222449)
					(end -0.991463 -1.279127)
					(width 0.2)
				)
				(gr_arc
					(start 1.266278 1.081674)
					(mid -0.294507 0.285313)
					(end -1.083663 -1.279127)
					(width 0.2)
				)
				(gr_line
					(start 1.279127 0.250195)
					(end 1.279127 1.083663)
					(width 0.2)
				)
				(gr_line
					(start -0.250195 -1.279127)
					(end -1.083663 -1.279127)
					(width 0.2)
				)
			)
		)
		(pad "" smd custom
			(at 1.7 1.7 270)
			(size 0.62 0.62)
			(layers "B.Paste")
			(thermal_bridge_angle 90)
			(options
				(clearance outline)
				(anchor circle)
			)
			(primitives
				(gr_arc
					(start 1.266786 0.24747)
					(mid 0.285453 -0.29439)
					(end -0.250195 -1.279127)
					(width 0.2)
				)
				(gr_arc
					(start 1.259603 0.339191)
					(mid 0.218448 -0.232561)
					(end -0.34334 -1.279127)
					(width 0.2)
				)
				(gr_arc
					(start 1.255279 0.431435)
					(mid 0.152481 -0.169693)
					(end -0.436309 -1.279127)
					(width 0.2)
				)
				(gr_arc
					(start 1.253811 0.524161)
					(mid 0.087542 -0.105784)
					(end -0.529126 -1.279127)
					(width 0.2)
				)
				(gr_arc
					(start 1.275473 0.621136)
					(mid 0.0309 -0.033527)
					(end -0.621807 -1.279127)
					(width 0.2)
				)
				(gr_arc
					(start 1.263664 0.711602)
					(mid -0.037759 0.026651)
					(end -0.71437 -1.279127)
					(width 0.2)
				)
				(gr_arc
					(start 1.253435 0.802342)
					(mid -0.105837 0.087395)
					(end -0.806826 -1.279127)
					(width 0.2)
				)
				(gr_arc
					(start 1.267475 0.897258)
					(mid -0.165236 0.156885)
					(end -0.899187 -1.279127)
					(width 0.2)
				)
				(gr_arc
					(start 1.270645 0.990112)
					(mid -0.228522 0.222449)
					(end -0.991463 -1.279127)
					(width 0.2)
				)
				(gr_arc
					(start 1.266278 1.081674)
					(mid -0.294507 0.285313)
					(end -1.083663 -1.279127)
					(width 0.2)
				)
				(gr_line
					(start 1.279127 0.250195)
					(end 1.279127 1.083663)
					(width 0.2)
				)
				(gr_line
					(start -0.250195 -1.279127)
					(end -1.083663 -1.279127)
					(width 0.2)
				)
			)
		)
		(pad "1" thru_hole circle
			(at 0 0 180)
			(size 6 6)
			(drill 3.7)
			(layers "*.Cu" "*.Mask")
			(remove_unused_layers no)
			(net 3 "GND")
			(pintype "passive")
		)
	)
	(footprint "antmicro-footprints:C_0805_2012Metric"
		(layer "B.Cu")
		(at 65.817962 158.1165 90)
		(descr "Capacitor SMD 0805")
		(tags "capacitor SMD 0805")
		(property "Reference" "C318"
			(at 0.75 3.92 90)
			(layer "B.SilkS")
			(effects
				(font
					(size 0.7 0.7)
					(thickness 0.15)
				)
				(justify right bottom mirror)
			)
		)
		(property "Value" "C_22u_25V_0805"
			(at -2.055717 -1.963152 90)
			(layer "B.Fab")
			(effects
				(font
					(size 0.7 0.7)
					(thickness 0.15)
				)
				(justify right bottom mirror)
			)
		)
		(property "Datasheet" "https://product.samsungsem.com/mlcc/CL21A226MAYNNN.do"
			(at 0 0 90)
			(layer "B.Fab")
			(hide yes)
			(effects
				(font
					(size 1.27 1.27)
					(thickness 0.15)
				)
			)
		)
		(property "Manufacturer" "Samsung Electro-Mechanics"
			(at 0 0 90)
			(unlocked yes)
			(layer "B.Fab")
			(hide yes)
			(effects
				(font
					(size 1 1)
					(thickness 0.15)
				)
				(justify mirror)
			)
		)
		(property "MPN" "CL21A226MAYNNNE"
			(at 0 0 90)
			(unlocked yes)
			(layer "B.Fab")
			(hide yes)
			(effects
				(font
					(size 1 1)
					(thickness 0.15)
				)
				(justify mirror)
			)
		)
		(property "Val" "22u"
			(at 0 0 90)
			(unlocked yes)
			(layer "B.Fab")
			(hide yes)
			(effects
				(font
					(size 1 1)
					(thickness 0.15)
				)
				(justify mirror)
			)
		)
		(property "License" "Apache-2.0"
			(at 0 0 90)
			(unlocked yes)
			(layer "B.Fab")
			(hide yes)
			(effects
				(font
					(size 1 1)
					(thickness 0.15)
				)
				(justify mirror)
			)
		)
		(property "Author" "Antmicro"
			(at 0 0 90)
			(unlocked yes)
			(layer "B.Fab")
			(hide yes)
			(effects
				(font
					(size 1 1)
					(thickness 0.15)
				)
				(justify mirror)
			)
		)
		(property "Voltage" "25V"
			(at 0 0 90)
			(unlocked yes)
			(layer "B.Fab")
			(hide yes)
			(effects
				(font
					(size 1 1)
					(thickness 0.15)
				)
				(justify mirror)
			)
		)
		(property "Dielectric" "X5R"
			(at 0 0 90)
			(unlocked yes)
			(layer "B.Fab")
			(hide yes)
			(effects
				(font
					(size 1 1)
					(thickness 0.15)
				)
				(justify mirror)
			)
		)
		(property "Public" "False"
			(at 0 0 90)
			(unlocked yes)
			(layer "B.Fab")
			(hide yes)
			(effects
				(font
					(size 1 1)
					(thickness 0.15)
				)
				(justify mirror)
			)
		)
		(sheetname "/Supply/")
		(sheetfile "supply.kicad_sch")
		(attr smd)
		(fp_line
			(start -0.3 -0.7)
			(end 0.3 -0.7)
			(stroke
				(width 0.15)
				(type solid)
			)
			(layer "B.SilkS")
		)
		(fp_line
			(start -0.3 0.7)
			(end 0.3 0.7)
			(stroke
				(width 0.15)
				(type solid)
			)
			(layer "B.SilkS")
		)
		(fp_rect
			(start 1.95 0.9)
			(end -1.95 -0.9)
			(stroke
				(width 0.05)
				(type default)
			)
			(fill no)
			(layer "B.CrtYd")
		)
		(fp_rect
			(start -0.95 0.675)
			(end 0.95 -0.675)
			(stroke
				(width 0.15)
				(type solid)
			)
			(fill no)
			(layer "B.Fab")
		)
		(fp_text user "Author: Antmicro"
			(at -1.9 -5.947 270)
			(layer "B.Fab")
			(effects
				(font
					(size 0.7 0.7)
					(thickness 0.15)
				)
				(justify left bottom mirror)
			)
		)
		(fp_text user "${REFERENCE}"
			(at -1.9 -3.947 270)
			(layer "B.Fab")
			(effects
				(font
					(size 0.7 0.7)
					(thickness 0.15)
				)
				(justify left bottom mirror)
			)
		)
		(fp_text user "License: Apache-2.0"
			(at -1.9 -4.947 270)
			(layer "B.Fab")
			(effects
				(font
					(size 0.7 0.7)
					(thickness 0.15)
				)
				(justify left bottom mirror)
			)
		)
		(pad "1" smd roundrect
			(at -1.1 0 90)
			(size 1.2 1.3)
			(layers "B.Cu" "B.Mask" "B.Paste")
			(roundrect_rratio 0.25)
			(net 77 "/Supply/OUT_5V")
			(pintype "passive")
		)
		(pad "2" smd roundrect
			(at 1.1 0 90)
			(size 1.2 1.3)
			(layers "B.Cu" "B.Mask" "B.Paste")
			(roundrect_rratio 0.25)
			(net 3 "GND")
			(pintype "passive")
		)
	)
	(footprint "antmicro-footprints:R_0402_1005Metric"
		(layer "B.Cu")
		(at 80.342962 135.5415 90)
		(descr "Resistor SMD 0402")
		(tags "resistor SMD 0402")
		(property "Reference" "R907"
			(at -2.845 -0.335 90)
			(layer "B.SilkS")
			(effects
				(font
					(size 0.7 0.7)
					(thickness 0.15)
				)
				(justify right bottom mirror)
			)
		)
		(property "Value" "R_2k2_0402"
			(at -1.011843 -1.772047 90)
			(layer "B.Fab")
			(effects
				(font
					(size 0.7 0.7)
					(thickness 0.15)
				)
				(justify right bottom mirror)
			)
		)
		(property "Datasheet" "https://www.bourns.com/docs/product-datasheets/cr.pdf"
			(at 0 0 90)
			(layer "B.Fab")
			(hide yes)
			(effects
				(font
					(size 1.27 1.27)
					(thickness 0.15)
				)
			)
		)
		(property "Manufacturer" "Bourns"
			(at 0 0 90)
			(unlocked yes)
			(layer "B.Fab")
			(hide yes)
			(effects
				(font
					(size 1 1)
					(thickness 0.15)
				)
				(justify mirror)
			)
		)
		(property "MPN" "CR0402-FX-2201GLF"
			(at 0 0 90)
			(unlocked yes)
			(layer "B.Fab")
			(hide yes)
			(effects
				(font
					(size 1 1)
					(thickness 0.15)
				)
				(justify mirror)
			)
		)
		(property "Val" "2k2"
			(at 0 0 90)
			(unlocked yes)
			(layer "B.Fab")
			(hide yes)
			(effects
				(font
					(size 1 1)
					(thickness 0.15)
				)
				(justify mirror)
			)
		)
		(property "License" "Apache-2.0"
			(at 0 0 90)
			(unlocked yes)
			(layer "B.Fab")
			(hide yes)
			(effects
				(font
					(size 1 1)
					(thickness 0.15)
				)
				(justify mirror)
			)
		)
		(property "Author" "Antmicro"
			(at 0 0 90)
			(unlocked yes)
			(layer "B.Fab")
			(hide yes)
			(effects
				(font
					(size 1 1)
					(thickness 0.15)
				)
				(justify mirror)
			)
		)
		(property "Tolerance" "1%"
			(at 0 0 90)
			(unlocked yes)
			(layer "B.Fab")
			(hide yes)
			(effects
				(font
					(size 1 1)
					(thickness 0.15)
				)
				(justify mirror)
			)
		)
		(sheetname "/USB/")
		(sheetfile "usb.kicad_sch")
		(attr smd)
		(fp_rect
			(start -0.925 0.47)
			(end 0.925 -0.47)
			(stroke
				(width 0.05)
				(type default)
			)
			(fill no)
			(layer "B.CrtYd")
		)
		(fp_rect
			(start -0.5 0.25)
			(end 0.5 -0.25)
			(stroke
				(width 0.15)
				(type solid)
			)
			(fill no)
			(layer "B.Fab")
		)
		(fp_text user "${REFERENCE}"
			(at -0.95 -3.168 270)
			(layer "B.Fab")
			(effects
				(font
					(size 0.7 0.7)
					(thickness 0.15)
				)
				(justify left bottom mirror)
			)
		)
		(fp_text user "Author: Antmicro"
			(at -0.95 -4.169 270)
			(layer "B.Fab")
			(effects
				(font
					(size 0.7 0.7)
					(thickness 0.15)
				)
				(justify left bottom mirror)
			)
		)
		(fp_text user "License: Apache-2.0"
			(at -0.95 -5.169 270)
			(layer "B.Fab")
			(effects
				(font
					(size 0.7 0.7)
					(thickness 0.15)
				)
				(justify left bottom mirror)
			)
		)
		(pad "1" smd roundrect
			(at -0.48 0 90)
			(size 0.59 0.64)
			(layers "B.Cu" "B.Mask" "B.Paste")
			(roundrect_rratio 0.25)
			(net 377 "Net-(U902-DO)")
			(pintype "passive")
		)
		(pad "2" smd roundrect
			(at 0.48 0 90)
			(size 0.59 0.64)
			(layers "B.Cu" "B.Mask" "B.Paste")
			(roundrect_rratio 0.25)
			(net 281 "/USB/EEDATA")
			(pintype "passive")
		)
	)
	(footprint "antmicro-footprints:TP_SMD_0.75mm"
		(layer "B.Cu")
		(at 55.27 152.28 -90)
		(property "Reference" "TP304"
			(at -1.01 -2.43 180)
			(layer "B.SilkS")
			(effects
				(font
					(size 0.7 0.7)
					(thickness 0.15)
				)
				(justify left bottom mirror)
			)
		)
		(property "Value" "TP_0.75mm_SMD"
			(at 0 -1.2 90)
			(layer "B.Fab")
			(effects
				(font
					(size 0.7 0.7)
					(thickness 0.15)
				)
				(justify left bottom mirror)
			)
		)
		(property "Author" "Antmicro"
			(at 0 0 270)
			(unlocked yes)
			(layer "B.Fab")
			(hide yes)
			(effects
				(font
					(size 1 1)
					(thickness 0.15)
				)
				(justify mirror)
			)
		)
		(property "License" "Apache-2.0"
			(at 0 0 270)
			(unlocked yes)
			(layer "B.Fab")
			(hide yes)
			(effects
				(font
					(size 1 1)
					(thickness 0.15)
				)
				(justify mirror)
			)
		)
		(property "MPN" ""
			(at 0 0 270)
			(unlocked yes)
			(layer "B.Fab")
			(hide yes)
			(effects
				(font
					(size 1 1)
					(thickness 0.15)
				)
				(justify mirror)
			)
		)
		(property "Manufacturer" ""
			(at 0 0 270)
			(unlocked yes)
			(layer "B.Fab")
			(hide yes)
			(effects
				(font
					(size 1 1)
					(thickness 0.15)
				)
				(justify mirror)
			)
		)
		(sheetname "/Supply/")
		(sheetfile "supply.kicad_sch")
		(attr exclude_from_pos_files exclude_from_bom)
		(fp_circle
			(center 0 0)
			(end 0.475 0)
			(stroke
				(width 0.05)
				(type default)
			)
			(fill no)
			(layer "B.CrtYd")
		)
		(fp_text user "License: Apache-2.0"
			(at -0.4 -5.101 90)
			(layer "B.Fab")
			(effects
				(font
					(size 0.7 0.7)
					(thickness 0.15)
				)
				(justify left bottom mirror)
			)
		)
		(fp_text user "${REFERENCE}"
			(at -0.4 -2.7 90)
			(layer "B.Fab")
			(effects
				(font
					(size 0.7 0.7)
					(thickness 0.15)
				)
				(justify left bottom mirror)
			)
		)
		(fp_text user "Author: Antmicro"
			(at -0.4 -3.901 90)
			(layer "B.Fab")
			(effects
				(font
					(size 0.7 0.7)
					(thickness 0.15)
				)
				(justify left bottom mirror)
			)
		)
		(pad "1" smd circle
			(at 0 0 270)
			(size 0.75 0.75)
			(layers "B.Cu" "B.Mask")
			(net 352 "Net-(U303-PG)")
			(pinfunction "1")
			(pintype "passive")
		)
	)
	(footprint "antmicro-footprints:C_2220_5650Metric"
		(layer "B.Cu")
		(at 55.117962 145.6465 90)
		(descr "Capacitor SMD 2220")
		(tags "capacitor SMD 2220")
		(property "Reference" "C405"
			(at -4.405 -1.29 180)
			(layer "B.SilkS")
			(effects
				(font
					(size 0.7 0.7)
					(thickness 0.15)
				)
				(justify right bottom mirror)
			)
		)
		(property "Value" "C_22u_100V_2220"
			(at 0 -3.9 90)
			(layer "B.Fab")
			(effects
				(font
					(size 0.7 0.7)
					(thickness 0.15)
				)
				(justify right bottom mirror)
			)
		)
		(property "Datasheet" "https://product.tdk.com/en/search/capacitor/ceramic/mlcc/info?part_no=C5750X7S2A226M280KB"
			(at 0 0 90)
			(layer "B.Fab")
			(hide yes)
			(effects
				(font
					(size 1.27 1.27)
					(thickness 0.15)
				)
			)
		)
		(property "Manufacturer" "TDK"
			(at 0 0 90)
			(unlocked yes)
			(layer "B.Fab")
			(hide yes)
			(effects
				(font
					(size 1 1)
					(thickness 0.15)
				)
				(justify mirror)
			)
		)
		(property "MPN" "C5750X7S2A226M280KB"
			(at 0 0 90)
			(unlocked yes)
			(layer "B.Fab")
			(hide yes)
			(effects
				(font
					(size 1 1)
					(thickness 0.15)
				)
				(justify mirror)
			)
		)
		(property "Val" "22u"
			(at 0 0 90)
			(unlocked yes)
			(layer "B.Fab")
			(hide yes)
			(effects
				(font
					(size 1 1)
					(thickness 0.15)
				)
				(justify mirror)
			)
		)
		(property "License" "Apache-2.0"
			(at 0 0 90)
			(unlocked yes)
			(layer "B.Fab")
			(hide yes)
			(effects
				(font
					(size 1 1)
					(thickness 0.15)
				)
				(justify mirror)
			)
		)
		(property "Author" "Antmicro"
			(at 0 0 90)
			(unlocked yes)
			(layer "B.Fab")
			(hide yes)
			(effects
				(font
					(size 1 1)
					(thickness 0.15)
				)
				(justify mirror)
			)
		)
		(property "Voltage" "100V"
			(at 0 0 90)
			(unlocked yes)
			(layer "B.Fab")
			(hide yes)
			(effects
				(font
					(size 1 1)
					(thickness 0.15)
				)
				(justify mirror)
			)
		)
		(property "Dielectric" "X7S"
			(at 0 0 90)
			(unlocked yes)
			(layer "B.Fab")
			(hide yes)
			(effects
				(font
					(size 1 1)
					(thickness 0.15)
				)
				(justify mirror)
			)
		)
		(property "Public" "False"
			(at 0 0 90)
			(unlocked yes)
			(layer "B.Fab")
			(hide yes)
			(effects
				(font
					(size 1 1)
					(thickness 0.15)
				)
				(justify mirror)
			)
		)
		(sheetname "/Ethernet/")
		(sheetfile "ethernet.kicad_sch")
		(attr smd)
		(fp_line
			(start -1.415 -2.61)
			(end 1.415 -2.61)
			(stroke
				(width 0.15)
				(type solid)
			)
			(layer "B.SilkS")
		)
		(fp_line
			(start -1.415 2.61)
			(end 1.415 2.61)
			(stroke
				(width 0.15)
				(type solid)
			)
			(layer "B.SilkS")
		)
		(fp_rect
			(start -3.7 2.95)
			(end 3.7 -2.95)
			(stroke
				(width 0.05)
				(type solid)
			)
			(fill no)
			(layer "B.CrtYd")
		)
		(fp_rect
			(start -2.85 2.5)
			(end 2.85 -2.5)
			(stroke
				(width 0.15)
				(type solid)
			)
			(fill no)
			(layer "B.Fab")
		)
		(fp_text user "Author: Antmicro"
			(at -3.7 -7.9 270)
			(layer "B.Fab")
			(effects
				(font
					(size 0.7 0.7)
					(thickness 0.15)
				)
				(justify left bottom mirror)
			)
		)
		(fp_text user "${REFERENCE}"
			(at -3.7 -5.9 270)
			(layer "B.Fab")
			(effects
				(font
					(size 0.7 0.7)
					(thickness 0.15)
				)
				(justify left bottom mirror)
			)
		)
		(fp_text user "License: Apache-2.0"
			(at -3.7 -6.9 270)
			(layer "B.Fab")
			(effects
				(font
					(size 0.7 0.7)
					(thickness 0.15)
				)
				(justify left bottom mirror)
			)
		)
		(pad "1" smd roundrect
			(at -2.55 0 90)
			(size 1.8 5.4)
			(layers "B.Cu" "B.Mask" "B.Paste")
			(roundrect_rratio 0.138889)
			(net 1 "GNDD")
			(pintype "passive")
		)
		(pad "2" smd roundrect
			(at 2.55 0 90)
			(size 1.8 5.4)
			(layers "B.Cu" "B.Mask" "B.Paste")
			(roundrect_rratio 0.138889)
			(net 33 "/Ethernet/VDD")
			(pintype "passive")
		)
	)
	(footprint "antmicro-footprints:SOIC-4_4.55x2.6mm_P1.27mm"
		(layer "B.Cu")
		(at 56.792962 135.4665 180)
		(descr "ACPL-217-500E")
		(tags "Integrated Circuit")
		(property "Reference" "U402"
			(at -1.395 1.87 0)
			(layer "B.SilkS")
			(effects
				(font
					(size 0.7 0.7)
					(thickness 0.15)
				)
				(justify left bottom mirror)
			)
		)
		(property "Value" "ACPL-217-500E"
			(at -4.25 -2.75 0)
			(layer "B.Fab")
			(effects
				(font
					(size 0.7 0.7)
					(thickness 0.15)
				)
				(justify left bottom mirror)
			)
		)
		(property "Datasheet" "https://docs.broadcom.com/doc/AV02-0470EN"
			(at 0 0 180)
			(layer "B.Fab")
			(hide yes)
			(effects
				(font
					(size 1.27 1.27)
					(thickness 0.15)
				)
			)
		)
		(property "Description" "Broadcom ACPL-217-500E DC Input Transistor Output Optocoupler, Surface Mount, 4-Pin SO"
			(at 113.585924 270.933 0)
			(layer "B.Fab")
			(hide yes)
			(effects
				(font
					(size 1.27 1.27)
					(thickness 0.15)
				)
			)
		)
		(property "Manufacturer" "Broadcom"
			(at 0 0 180)
			(unlocked yes)
			(layer "B.Fab")
			(hide yes)
			(effects
				(font
					(size 1 1)
					(thickness 0.15)
				)
				(justify mirror)
			)
		)
		(property "MPN" "ACPL-217-500E"
			(at 0 0 180)
			(unlocked yes)
			(layer "B.Fab")
			(hide yes)
			(effects
				(font
					(size 1 1)
					(thickness 0.15)
				)
				(justify mirror)
			)
		)
		(property "Author" "Antmicro"
			(at 0 0 180)
			(unlocked yes)
			(layer "B.Fab")
			(hide yes)
			(effects
				(font
					(size 1 1)
					(thickness 0.15)
				)
				(justify mirror)
			)
		)
		(property "License" "Apache-2.0"
			(at 0 0 180)
			(unlocked yes)
			(layer "B.Fab")
			(hide yes)
			(effects
				(font
					(size 1 1)
					(thickness 0.15)
				)
				(justify mirror)
			)
		)
		(sheetname "/Ethernet/")
		(sheetfile "ethernet.kicad_sch")
		(attr smd)
		(fp_line
			(start 2.3 1.1)
			(end 2.3 1.4)
			(stroke
				(width 0.12)
				(type solid)
			)
			(layer "B.SilkS")
		)
		(fp_line
			(start 2.3 -1.1)
			(end 2.3 -1.4)
			(stroke
				(width 0.12)
				(type solid)
			)
			(layer "B.SilkS")
		)
		(fp_line
			(start 2.3 -1.4)
			(end 1.8 -1.4)
			(stroke
				(width 0.12)
				(type solid)
			)
			(layer "B.SilkS")
		)
		(fp_line
			(start 1.8 1.4)
			(end 2.3 1.4)
			(stroke
				(width 0.12)
				(type solid)
			)
			(layer "B.SilkS")
		)
		(fp_line
			(start -1.8 -1.4)
			(end -2.3 -1.4)
			(stroke
				(width 0.12)
				(type solid)
			)
			(layer "B.SilkS")
		)
		(fp_line
			(start -2.3 1.4)
			(end -1.8 1.4)
			(stroke
				(width 0.12)
				(type solid)
			)
			(layer "B.SilkS")
		)
		(fp_line
			(start -2.3 -1.1)
			(end -2.3 -1.4)
			(stroke
				(width 0.12)
				(type solid)
			)
			(layer "B.SilkS")
		)
		(fp_line
			(start 4.29 1.7)
			(end 4.29 -1.69)
			(stroke
				(width 0.05)
				(type solid)
			)
			(layer "B.CrtYd")
		)
		(fp_line
			(start 4.29 -1.69)
			(end -4.3 -1.69)
			(stroke
				(width 0.05)
				(type solid)
			)
			(layer "B.CrtYd")
		)
		(fp_line
			(start -4.3 1.7)
			(end 4.29 1.7)
			(stroke
				(width 0.05)
				(type solid)
			)
			(layer "B.CrtYd")
		)
		(fp_line
			(start -4.3 -1.69)
			(end -4.3 1.7)
			(stroke
				(width 0.05)
				(type solid)
			)
			(layer "B.CrtYd")
		)
		(fp_line
			(start 2.2 1.301)
			(end 2.2 -1.3)
			(stroke
				(width 0.15)
				(type solid)
			)
			(layer "B.Fab")
		)
		(fp_line
			(start 2.2 -1.3)
			(end -2.201 -1.3)
			(stroke
				(width 0.15)
				(type solid)
			)
			(layer "B.Fab")
		)
		(fp_line
			(start -2.201 1.301)
			(end 2.2 1.301)
			(stroke
				(width 0.15)
				(type solid)
			)
			(layer "B.Fab")
		)
		(fp_line
			(start -2.201 0.03)
			(end -0.931 1.301)
			(stroke
				(width 0.15)
				(type solid)
			)
			(layer "B.Fab")
		)
		(fp_line
			(start -2.201 -1.3)
			(end -2.201 1.301)
			(stroke
				(width 0.15)
				(type solid)
			)
			(layer "B.Fab")
		)
		(fp_text user "."
			(at -2.7 1.6 0)
			(layer "B.SilkS")
			(effects
				(font
					(size 1 1)
					(thickness 0.15)
				)
				(justify mirror)
			)
		)
		(fp_text user "License: Apache-2.0"
			(at -4.25 -7 0)
			(layer "B.Fab")
			(effects
				(font
					(size 0.7 0.7)
					(thickness 0.15)
				)
				(justify left bottom mirror)
			)
		)
		(fp_text user "Author: Antmicro"
			(at -4.3 -5.5 0)
			(layer "B.Fab")
			(effects
				(font
					(size 0.7 0.7)
					(thickness 0.15)
				)
				(justify left bottom mirror)
			)
		)
		(fp_text user "${REFERENCE}"
			(at -4.3 -4.25 0)
			(layer "B.Fab")
			(effects
				(font
					(size 0.7 0.7)
					(thickness 0.15)
				)
				(justify left bottom mirror)
			)
		)
		(pad "1" smd roundrect
			(at -3.125 0.635 90)
			(size 0.65 1.85)
			(layers "B.Cu" "B.Mask" "B.Paste")
			(roundrect_rratio 0.15)
			(net 386 "/Compute module/~{POE EN}")
			(pintype "passive")
		)
		(pad "2" smd roundrect
			(at -3.125 -0.634 90)
			(size 0.65 1.85)
			(layers "B.Cu" "B.Mask" "B.Paste")
			(roundrect_rratio 0.15)
			(net 367 "Net-(R421-Pad1)")
			(pintype "passive")
		)
		(pad "3" smd roundrect
			(at 3.124 -0.634 90)
			(size 0.65 1.85)
			(layers "B.Cu" "B.Mask" "B.Paste")
			(roundrect_rratio 0.15)
			(net 366 "Net-(R418-Pad2)")
			(pintype "passive")
		)
		(pad "4" smd roundrect
			(at 3.124 0.635 90)
			(size 0.65 1.85)
			(layers "B.Cu" "B.Mask" "B.Paste")
			(roundrect_rratio 0.15)
			(net 339 "/Ethernet/POE_ACTIVE")
			(pintype "passive")
		)
	)
	(footprint "antmicro-footprints:C_0402_1005Metric"
		(layer "B.Cu")
		(at 43.797962 158.6365)
		(descr "Capacitor SMD 0402")
		(tags "capacitor SMD 0402")
		(property "Reference" "C301"
			(at -1.13 1.34 0)
			(layer "B.SilkS")
			(effects
				(font
					(size 0.7 0.7)
					(thickness 0.15)
				)
				(justify right bottom mirror)
			)
		)
		(property "Value" "C_1u_25V_0402"
			(at -1.022927 -2.155213 0)
			(layer "B.Fab")
			(effects
				(font
					(size 0.7 0.7)
					(thickness 0.15)
				)
				(justify right bottom mirror)
			)
		)
		(property "Datasheet" "https://www.murata.com/products/productdetail?partno=GRM155R61E105KE11%23"
			(at 0 0 0)
			(layer "B.Fab")
			(hide yes)
			(effects
				(font
					(size 1.27 1.27)
					(thickness 0.15)
				)
			)
		)
		(property "MPN" "GRM155R61E105KE11J"
			(at 0 0 0)
			(unlocked yes)
			(layer "B.Fab")
			(hide yes)
			(effects
				(font
					(size 1 1)
					(thickness 0.15)
				)
				(justify mirror)
			)
		)
		(property "Manufacturer" "Murata"
			(at 0 0 0)
			(unlocked yes)
			(layer "B.Fab")
			(hide yes)
			(effects
				(font
					(size 1 1)
					(thickness 0.15)
				)
				(justify mirror)
			)
		)
		(property "License" "Apache-2.0"
			(at 0 0 0)
			(unlocked yes)
			(layer "B.Fab")
			(hide yes)
			(effects
				(font
					(size 1 1)
					(thickness 0.15)
				)
				(justify mirror)
			)
		)
		(property "Author" "Antmicro"
			(at 0 0 0)
			(unlocked yes)
			(layer "B.Fab")
			(hide yes)
			(effects
				(font
					(size 1 1)
					(thickness 0.15)
				)
				(justify mirror)
			)
		)
		(property "Val" "1u"
			(at 0 0 0)
			(unlocked yes)
			(layer "B.Fab")
			(hide yes)
			(effects
				(font
					(size 1 1)
					(thickness 0.15)
				)
				(justify mirror)
			)
		)
		(property "Voltage" "25V"
			(at 0 0 0)
			(unlocked yes)
			(layer "B.Fab")
			(hide yes)
			(effects
				(font
					(size 1 1)
					(thickness 0.15)
				)
				(justify mirror)
			)
		)
		(property "Dielectric" "X5R"
			(at 0 0 0)
			(unlocked yes)
			(layer "B.Fab")
			(hide yes)
			(effects
				(font
					(size 1 1)
					(thickness 0.15)
				)
				(justify mirror)
			)
		)
		(sheetname "/Supply/")
		(sheetfile "supply.kicad_sch")
		(attr smd)
		(fp_rect
			(start -0.925 0.47)
			(end 0.925 -0.47)
			(stroke
				(width 0.05)
				(type default)
			)
			(fill no)
			(layer "B.CrtYd")
		)
		(fp_line
			(start -0.494 -0.248)
			(end -0.494 0.25)
			(stroke
				(width 0.15)
				(type solid)
			)
			(layer "B.Fab")
		)
		(fp_line
			(start -0.494 0.25)
			(end 0.504 0.25)
			(stroke
				(width 0.15)
				(type solid)
			)
			(layer "B.Fab")
		)
		(fp_line
			(start 0.504 -0.248)
			(end -0.494 -0.248)
			(stroke
				(width 0.15)
				(type solid)
			)
			(layer "B.Fab")
		)
		(fp_line
			(start 0.504 0.25)
			(end 0.504 -0.248)
			(stroke
				(width 0.15)
				(type solid)
			)
			(layer "B.Fab")
		)
		(fp_text user "${REFERENCE}"
			(at -0.939 -4.599 180)
			(layer "B.Fab")
			(effects
				(font
					(size 0.7 0.7)
					(thickness 0.15)
				)
				(justify left bottom mirror)
			)
		)
		(fp_text user "Author: Antmicro"
			(at -0.939 -3.399 180)
			(layer "B.Fab")
			(effects
				(font
					(size 0.7 0.7)
					(thickness 0.15)
				)
				(justify left bottom mirror)
			)
		)
		(fp_text user "License: Apache-2.0"
			(at -0.939 -5.799 180)
			(layer "B.Fab")
			(effects
				(font
					(size 0.7 0.7)
					(thickness 0.15)
				)
				(justify left bottom mirror)
			)
		)
		(pad "1" smd roundrect
			(at -0.48 0)
			(size 0.59 0.64)
			(layers "B.Cu" "B.Mask" "B.Paste")
			(roundrect_rratio 0.25)
			(net 17 "Net-(Q307-G)")
			(pintype "passive")
		)
		(pad "2" smd roundrect
			(at 0.48 0)
			(size 0.59 0.64)
			(layers "B.Cu" "B.Mask" "B.Paste")
			(roundrect_rratio 0.25)
			(net 21 "/Supply/VCC_IN")
			(pintype "passive")
		)
	)
	(footprint "antmicro-footprints:R_0402_1005Metric"
		(layer "B.Cu")
		(at 78.767962 152.2165 180)
		(descr "Resistor SMD 0402")
		(tags "resistor SMD 0402")
		(property "Reference" "R243"
			(at -5.06 -1.86 0)
			(layer "B.SilkS")
			(effects
				(font
					(size 0.7 0.7)
					(thickness 0.15)
				)
				(justify left bottom mirror)
			)
		)
		(property "Value" "R_2k2_0402"
			(at -1.011843 -1.772047 0)
			(layer "B.Fab")
			(effects
				(font
					(size 0.7 0.7)
					(thickness 0.15)
				)
				(justify left bottom mirror)
			)
		)
		(property "Datasheet" "https://www.bourns.com/docs/product-datasheets/cr.pdf"
			(at 0 0 180)
			(layer "B.Fab")
			(hide yes)
			(effects
				(font
					(size 1.27 1.27)
					(thickness 0.15)
				)
			)
		)
		(property "MPN" "CR0402-FX-2201GLF"
			(at 0 0 180)
			(unlocked yes)
			(layer "B.Fab")
			(hide yes)
			(effects
				(font
					(size 1 1)
					(thickness 0.15)
				)
				(justify mirror)
			)
		)
		(property "Manufacturer" "Bourns"
			(at 0 0 180)
			(unlocked yes)
			(layer "B.Fab")
			(hide yes)
			(effects
				(font
					(size 1 1)
					(thickness 0.15)
				)
				(justify mirror)
			)
		)
		(property "License" "Apache-2.0"
			(at 0 0 180)
			(unlocked yes)
			(layer "B.Fab")
			(hide yes)
			(effects
				(font
					(size 1 1)
					(thickness 0.15)
				)
				(justify mirror)
			)
		)
		(property "Author" "Antmicro"
			(at 0 0 180)
			(unlocked yes)
			(layer "B.Fab")
			(hide yes)
			(effects
				(font
					(size 1 1)
					(thickness 0.15)
				)
				(justify mirror)
			)
		)
		(property "Val" "2k2"
			(at 0 0 180)
			(unlocked yes)
			(layer "B.Fab")
			(hide yes)
			(effects
				(font
					(size 1 1)
					(thickness 0.15)
				)
				(justify mirror)
			)
		)
		(property "Tolerance" "1%"
			(at 0 0 180)
			(unlocked yes)
			(layer "B.Fab")
			(hide yes)
			(effects
				(font
					(size 1 1)
					(thickness 0.15)
				)
				(justify mirror)
			)
		)
		(sheetname "/Compute module/")
		(sheetfile "compute-module.kicad_sch")
		(attr smd)
		(fp_rect
			(start -0.925 0.47)
			(end 0.925 -0.47)
			(stroke
				(width 0.05)
				(type default)
			)
			(fill no)
			(layer "B.CrtYd")
		)
		(fp_rect
			(start -0.5 0.25)
			(end 0.5 -0.25)
			(stroke
				(width 0.15)
				(type solid)
			)
			(fill no)
			(layer "B.Fab")
		)
		(fp_text user "Author: Antmicro"
			(at -0.95 -4.169 0)
			(layer "B.Fab")
			(effects
				(font
					(size 0.7 0.7)
					(thickness 0.15)
				)
				(justify left bottom mirror)
			)
		)
		(fp_text user "${REFERENCE}"
			(at -0.95 -3.168 0)
			(layer "B.Fab")
			(effects
				(font
					(size 0.7 0.7)
					(thickness 0.15)
				)
				(justify left bottom mirror)
			)
		)
		(fp_text user "License: Apache-2.0"
			(at -0.95 -5.169 0)
			(layer "B.Fab")
			(effects
				(font
					(size 0.7 0.7)
					(thickness 0.15)
				)
				(justify left bottom mirror)
			)
		)
		(pad "1" smd roundrect
			(at -0.48 0 180)
			(size 0.59 0.64)
			(layers "B.Cu" "B.Mask" "B.Paste")
			(roundrect_rratio 0.25)
			(net 447 "/Compute module/GPIO.0{slash}SDA0")
			(pintype "passive")
		)
		(pad "2" smd roundrect
			(at 0.48 0 180)
			(size 0.59 0.64)
			(layers "B.Cu" "B.Mask" "B.Paste")
			(roundrect_rratio 0.25)
			(net 18 "V_{IO}")
			(pintype "passive")
		)
	)
	(footprint "antmicro-footprints:SOD-523"
		(layer "B.Cu")
		(at 135.767962 146.2415 90)
		(property "Reference" "D603"
			(at 1.145 0.43 90)
			(layer "B.SilkS")
			(effects
				(font
					(size 0.7 0.7)
					(thickness 0.15)
				)
				(justify right bottom mirror)
			)
		)
		(property "Value" "PESD5Z5_0F"
			(at 0 -1.499 90)
			(layer "B.Fab")
			(effects
				(font
					(size 0.7 0.7)
					(thickness 0.15)
				)
				(justify right bottom mirror)
			)
		)
		(property "Datasheet" "https://assets.nexperia.com/documents/data-sheet/PESD5Z5_0.pdf"
			(at 0 0 90)
			(layer "B.Fab")
			(hide yes)
			(effects
				(font
					(size 1.27 1.27)
					(thickness 0.15)
				)
			)
		)
		(property "Manufacturer" "Nexperia"
			(at 0 0 90)
			(unlocked yes)
			(layer "B.Fab")
			(hide yes)
			(effects
				(font
					(size 1 1)
					(thickness 0.15)
				)
				(justify mirror)
			)
		)
		(property "MPN" "PESD5Z5.0F"
			(at 0 0 90)
			(unlocked yes)
			(layer "B.Fab")
			(hide yes)
			(effects
				(font
					(size 1 1)
					(thickness 0.15)
				)
				(justify mirror)
			)
		)
		(property "Author" "Antmicro"
			(at 0 0 90)
			(unlocked yes)
			(layer "B.Fab")
			(hide yes)
			(effects
				(font
					(size 1 1)
					(thickness 0.15)
				)
				(justify mirror)
			)
		)
		(property "License" "Apache-2.0"
			(at 0 0 90)
			(unlocked yes)
			(layer "B.Fab")
			(hide yes)
			(effects
				(font
					(size 1 1)
					(thickness 0.15)
				)
				(justify mirror)
			)
		)
		(sheetname "/CSI/")
		(sheetfile "csi.kicad_sch")
		(attr smd)
		(fp_line
			(start -0.35 0.5)
			(end -0.35 -0.5)
			(stroke
				(width 0.15)
				(type solid)
			)
			(layer "B.SilkS")
		)
		(fp_rect
			(start -1 0.6)
			(end 1 -0.6)
			(stroke
				(width 0.05)
				(type solid)
			)
			(fill no)
			(layer "B.CrtYd")
		)
		(fp_line
			(start -0.652 -0.423)
			(end 0.65 -0.423)
			(stroke
				(width 0.15)
				(type solid)
			)
			(layer "B.Fab")
		)
		(fp_line
			(start -0.652 -0.423)
			(end -0.652 0.425)
			(stroke
				(width 0.15)
				(type solid)
			)
			(layer "B.Fab")
		)
		(fp_line
			(start -0.35 0.4)
			(end -0.35 -0.4)
			(stroke
				(width 0.15)
				(type solid)
			)
			(layer "B.Fab")
		)
		(fp_line
			(start 0.65 0.425)
			(end 0.65 -0.423)
			(stroke
				(width 0.15)
				(type solid)
			)
			(layer "B.Fab")
		)
		(fp_line
			(start -0.652 0.425)
			(end 0.65 0.425)
			(stroke
				(width 0.15)
				(type solid)
			)
			(layer "B.Fab")
		)
		(fp_text user "Author: Antmicro"
			(at -1.276 -4.7 270)
			(layer "B.Fab")
			(effects
				(font
					(size 0.7 0.7)
					(thickness 0.15)
				)
				(justify left bottom mirror)
			)
		)
		(fp_text user "${REFERENCE}"
			(at -1.276 -3.499 270)
			(layer "B.Fab")
			(effects
				(font
					(size 0.7 0.7)
					(thickness 0.15)
				)
				(justify left bottom mirror)
			)
		)
		(fp_text user "License: Apache-2.0"
			(at -1.276 -5.9 270)
			(layer "B.Fab")
			(effects
				(font
					(size 0.7 0.7)
					(thickness 0.15)
				)
				(justify left bottom mirror)
			)
		)
		(pad "1" smd roundrect
			(at -0.701 0 90)
			(size 0.5 0.6)
			(layers "B.Cu" "B.Mask" "B.Paste")
			(roundrect_rratio 0.25)
			(net 19 "/CSI/CSI_3V3")
			(pinfunction "C")
			(pintype "passive")
		)
		(pad "2" smd roundrect
			(at 0.699 0 90)
			(size 0.5 0.6)
			(layers "B.Cu" "B.Mask" "B.Paste")
			(roundrect_rratio 0.25)
			(net 3 "GND")
			(pinfunction "A")
			(pintype "passive")
		)
	)
	(footprint "antmicro-footprints:C_0805_2012Metric"
		(layer "B.Cu")
		(at 48.867962 156.3665 -90)
		(descr "Capacitor SMD 0805")
		(tags "capacitor SMD 0805")
		(property "Reference" "C304"
			(at -5.04 -0.04 90)
			(layer "B.SilkS")
			(effects
				(font
					(size 0.7 0.7)
					(thickness 0.15)
				)
				(justify left bottom mirror)
			)
		)
		(property "Value" "C_22u_25V_0805"
			(at -2.055717 -1.963152 90)
			(layer "B.Fab")
			(effects
				(font
					(size 0.7 0.7)
					(thickness 0.15)
				)
				(justify left bottom mirror)
			)
		)
		(property "Datasheet" "https://product.samsungsem.com/mlcc/CL21A226MAYNNN.do"
			(at 0 0 270)
			(layer "B.Fab")
			(hide yes)
			(effects
				(font
					(size 1.27 1.27)
					(thickness 0.15)
				)
			)
		)
		(property "Manufacturer" "Samsung Electro-Mechanics"
			(at 0 0 270)
			(unlocked yes)
			(layer "B.Fab")
			(hide yes)
			(effects
				(font
					(size 1 1)
					(thickness 0.15)
				)
				(justify mirror)
			)
		)
		(property "MPN" "CL21A226MAYNNNE"
			(at 0 0 270)
			(unlocked yes)
			(layer "B.Fab")
			(hide yes)
			(effects
				(font
					(size 1 1)
					(thickness 0.15)
				)
				(justify mirror)
			)
		)
		(property "Val" "22u"
			(at 0 0 270)
			(unlocked yes)
			(layer "B.Fab")
			(hide yes)
			(effects
				(font
					(size 1 1)
					(thickness 0.15)
				)
				(justify mirror)
			)
		)
		(property "License" "Apache-2.0"
			(at 0 0 270)
			(unlocked yes)
			(layer "B.Fab")
			(hide yes)
			(effects
				(font
					(size 1 1)
					(thickness 0.15)
				)
				(justify mirror)
			)
		)
		(property "Author" "Antmicro"
			(at 0 0 270)
			(unlocked yes)
			(layer "B.Fab")
			(hide yes)
			(effects
				(font
					(size 1 1)
					(thickness 0.15)
				)
				(justify mirror)
			)
		)
		(property "Voltage" "25V"
			(at 0 0 270)
			(unlocked yes)
			(layer "B.Fab")
			(hide yes)
			(effects
				(font
					(size 1 1)
					(thickness 0.15)
				)
				(justify mirror)
			)
		)
		(property "Dielectric" "X5R"
			(at 0 0 270)
			(unlocked yes)
			(layer "B.Fab")
			(hide yes)
			(effects
				(font
					(size 1 1)
					(thickness 0.15)
				)
				(justify mirror)
			)
		)
		(property "Public" "False"
			(at 0 0 270)
			(unlocked yes)
			(layer "B.Fab")
			(hide yes)
			(effects
				(font
					(size 1 1)
					(thickness 0.15)
				)
				(justify mirror)
			)
		)
		(sheetname "/Supply/")
		(sheetfile "supply.kicad_sch")
		(attr smd)
		(fp_line
			(start -0.3 0.7)
			(end 0.3 0.7)
			(stroke
				(width 0.15)
				(type solid)
			)
			(layer "B.SilkS")
		)
		(fp_line
			(start -0.3 -0.7)
			(end 0.3 -0.7)
			(stroke
				(width 0.15)
				(type solid)
			)
			(layer "B.SilkS")
		)
		(fp_rect
			(start 1.95 0.9)
			(end -1.95 -0.9)
			(stroke
				(width 0.05)
				(type default)
			)
			(fill no)
			(layer "B.CrtYd")
		)
		(fp_rect
			(start -0.95 0.675)
			(end 0.95 -0.675)
			(stroke
				(width 0.15)
				(type solid)
			)
			(fill no)
			(layer "B.Fab")
		)
		(fp_text user "License: Apache-2.0"
			(at -1.9 -4.947 90)
			(layer "B.Fab")
			(effects
				(font
					(size 0.7 0.7)
					(thickness 0.15)
				)
				(justify left bottom mirror)
			)
		)
		(fp_text user "${REFERENCE}"
			(at -1.9 -3.947 90)
			(layer "B.Fab")
			(effects
				(font
					(size 0.7 0.7)
					(thickness 0.15)
				)
				(justify left bottom mirror)
			)
		)
		(fp_text user "Author: Antmicro"
			(at -1.9 -5.947 90)
			(layer "B.Fab")
			(effects
				(font
					(size 0.7 0.7)
					(thickness 0.15)
				)
				(justify left bottom mirror)
			)
		)
		(pad "1" smd roundrect
			(at -1.1 0 270)
			(size 1.2 1.3)
			(layers "B.Cu" "B.Mask" "B.Paste")
			(roundrect_rratio 0.25)
			(net 43 "VCC")
			(pintype "passive")
		)
		(pad "2" smd roundrect
			(at 1.1 0 270)
			(size 1.2 1.3)
			(layers "B.Cu" "B.Mask" "B.Paste")
			(roundrect_rratio 0.25)
			(net 3 "GND")
			(pintype "passive")
		)
	)
	(footprint "antmicro-footprints:R_0402_1005Metric"
		(layer "B.Cu")
		(at 45.332962 161.8375 180)
		(descr "Resistor SMD 0402")
		(tags "resistor SMD 0402")
		(property "Reference" "R304"
			(at -1.475 0.521 0)
			(layer "B.SilkS")
			(effects
				(font
					(size 0.7 0.7)
					(thickness 0.15)
				)
				(justify left bottom mirror)
			)
		)
		(property "Value" "R_470k_0402"
			(at -1.011843 -1.772047 0)
			(layer "B.Fab")
			(effects
				(font
					(size 0.7 0.7)
					(thickness 0.15)
				)
				(justify left bottom mirror)
			)
		)
		(property "Datasheet" "https://www.bourns.com/docs/product-datasheets/cr.pdf"
			(at 0 0 180)
			(layer "B.Fab")
			(hide yes)
			(effects
				(font
					(size 1.27 1.27)
					(thickness 0.15)
				)
			)
		)
		(property "MPN" "CR0402-FX-4703GLF"
			(at 0 0 180)
			(unlocked yes)
			(layer "B.Fab")
			(hide yes)
			(effects
				(font
					(size 1 1)
					(thickness 0.15)
				)
				(justify mirror)
			)
		)
		(property "Manufacturer" "Bourns"
			(at 0 0 180)
			(unlocked yes)
			(layer "B.Fab")
			(hide yes)
			(effects
				(font
					(size 1 1)
					(thickness 0.15)
				)
				(justify mirror)
			)
		)
		(property "License" "Apache-2.0"
			(at 0 0 180)
			(unlocked yes)
			(layer "B.Fab")
			(hide yes)
			(effects
				(font
					(size 1 1)
					(thickness 0.15)
				)
				(justify mirror)
			)
		)
		(property "Author" "Antmicro"
			(at 0 0 180)
			(unlocked yes)
			(layer "B.Fab")
			(hide yes)
			(effects
				(font
					(size 1 1)
					(thickness 0.15)
				)
				(justify mirror)
			)
		)
		(property "Val" "470k"
			(at 0 0 180)
			(unlocked yes)
			(layer "B.Fab")
			(hide yes)
			(effects
				(font
					(size 1 1)
					(thickness 0.15)
				)
				(justify mirror)
			)
		)
		(property "Tolerance" "1%"
			(at 0 0 180)
			(unlocked yes)
			(layer "B.Fab")
			(hide yes)
			(effects
				(font
					(size 1 1)
					(thickness 0.15)
				)
				(justify mirror)
			)
		)
		(sheetname "/Supply/")
		(sheetfile "supply.kicad_sch")
		(attr smd)
		(fp_rect
			(start -0.925 0.47)
			(end 0.925 -0.47)
			(stroke
				(width 0.05)
				(type default)
			)
			(fill no)
			(layer "B.CrtYd")
		)
		(fp_rect
			(start -0.5 0.25)
			(end 0.5 -0.25)
			(stroke
				(width 0.15)
				(type solid)
			)
			(fill no)
			(layer "B.Fab")
		)
		(fp_text user "${REFERENCE}"
			(at -0.95 -3.168 0)
			(layer "B.Fab")
			(effects
				(font
					(size 0.7 0.7)
					(thickness 0.15)
				)
				(justify left bottom mirror)
			)
		)
		(fp_text user "Author: Antmicro"
			(at -0.95 -4.169 0)
			(layer "B.Fab")
			(effects
				(font
					(size 0.7 0.7)
					(thickness 0.15)
				)
				(justify left bottom mirror)
			)
		)
		(fp_text user "License: Apache-2.0"
			(at -0.95 -5.169 0)
			(layer "B.Fab")
			(effects
				(font
					(size 0.7 0.7)
					(thickness 0.15)
				)
				(justify left bottom mirror)
			)
		)
		(pad "1" smd roundrect
			(at -0.48 0 180)
			(size 0.59 0.64)
			(layers "B.Cu" "B.Mask" "B.Paste")
			(roundrect_rratio 0.25)
			(net 3 "GND")
			(pintype "passive")
		)
		(pad "2" smd roundrect
			(at 0.48 0 180)
			(size 0.59 0.64)
			(layers "B.Cu" "B.Mask" "B.Paste")
			(roundrect_rratio 0.25)
			(net 333 "Net-(Q301-BIAS)")
			(pintype "passive")
		)
	)
	(footprint "antmicro-footprints:D_SOD-123F"
		(layer "B.Cu")
		(at 56.767962 115.1915 90)
		(property "Reference" "D403"
			(at -1.205 -1.16 90)
			(layer "B.SilkS")
			(effects
				(font
					(size 0.7 0.7)
					(thickness 0.15)
				)
				(justify right bottom mirror)
			)
		)
		(property "Value" "PTVS58VS1UR,115"
			(at 0 -2.1 90)
			(layer "B.Fab")
			(effects
				(font
					(size 0.7 0.7)
					(thickness 0.15)
				)
				(justify right bottom mirror)
			)
		)
		(property "Datasheet" "https://assets.nexperia.com/documents/data-sheet/PTVSXS1UR_SER.pdf"
			(at 0 0 90)
			(layer "B.Fab")
			(hide yes)
			(effects
				(font
					(size 1.27 1.27)
					(thickness 0.15)
				)
			)
		)
		(property "MPN" "PTVS58VS1UR,115"
			(at 0 0 90)
			(unlocked yes)
			(layer "B.Fab")
			(hide yes)
			(effects
				(font
					(size 1 1)
					(thickness 0.15)
				)
				(justify mirror)
			)
		)
		(property "Manufacturer" "Nexperia"
			(at 0 0 90)
			(unlocked yes)
			(layer "B.Fab")
			(hide yes)
			(effects
				(font
					(size 1 1)
					(thickness 0.15)
				)
				(justify mirror)
			)
		)
		(property "Author" "Antmicro"
			(at 0 0 90)
			(unlocked yes)
			(layer "B.Fab")
			(hide yes)
			(effects
				(font
					(size 1 1)
					(thickness 0.15)
				)
				(justify mirror)
			)
		)
		(property "License" "Apache-2.0"
			(at 0 0 90)
			(unlocked yes)
			(layer "B.Fab")
			(hide yes)
			(effects
				(font
					(size 1 1)
					(thickness 0.15)
				)
				(justify mirror)
			)
		)
		(sheetname "/Ethernet/")
		(sheetfile "ethernet.kicad_sch")
		(attr smd)
		(fp_line
			(start -0.65 0.6)
			(end -0.65 -0.6)
			(stroke
				(width 0.15)
				(type solid)
			)
			(layer "B.SilkS")
		)
		(fp_line
			(start 2.2 -1.1)
			(end -2.21 -1.1)
			(stroke
				(width 0.05)
				(type solid)
			)
			(layer "B.CrtYd")
		)
		(fp_line
			(start -2.21 -1.1)
			(end -2.21 1.1)
			(stroke
				(width 0.05)
				(type solid)
			)
			(layer "B.CrtYd")
		)
		(fp_line
			(start 2.2 1.1)
			(end 2.2 -1.1)
			(stroke
				(width 0.05)
				(type solid)
			)
			(layer "B.CrtYd")
		)
		(fp_line
			(start 2.2 1.1)
			(end -2.21 1.1)
			(stroke
				(width 0.05)
				(type solid)
			)
			(layer "B.CrtYd")
		)
		(fp_line
			(start -0.8 0.8)
			(end -0.8 -0.8)
			(stroke
				(width 0.1)
				(type solid)
			)
			(layer "B.Fab")
		)
		(fp_rect
			(start -1.75 0.802)
			(end 1.749 -0.8)
			(stroke
				(width 0.1)
				(type solid)
			)
			(fill no)
			(layer "B.Fab")
		)
		(fp_text user "Author: Antmicro"
			(at -2.202 -4.998 270)
			(layer "B.Fab")
			(effects
				(font
					(size 0.7 0.7)
					(thickness 0.15)
				)
				(justify left bottom mirror)
			)
		)
		(fp_text user "License: Apache-2.0"
			(at -2.202 -6.2 270)
			(layer "B.Fab")
			(effects
				(font
					(size 0.7 0.7)
					(thickness 0.15)
				)
				(justify left bottom mirror)
			)
		)
		(fp_text user "${REFERENCE}"
			(at -2.202 -3.798 270)
			(layer "B.Fab")
			(effects
				(font
					(size 0.7 0.7)
					(thickness 0.15)
				)
				(justify left bottom mirror)
			)
		)
		(pad "1" smd roundrect
			(at -1.401 0 90)
			(size 1.2 1.2)
			(layers "B.Cu" "B.Mask" "B.Paste")
			(roundrect_rratio 0.25)
			(net 33 "/Ethernet/VDD")
			(pinfunction "C")
			(pintype "passive")
		)
		(pad "2" smd roundrect
			(at 1.398 0 90)
			(size 1.2 1.2)
			(layers "B.Cu" "B.Mask" "B.Paste")
			(roundrect_rratio 0.25)
			(net 90 "/Ethernet/VSS")
			(pinfunction "A")
			(pintype "passive")
		)
	)
	(footprint "antmicro-footprints:R_0402_1005Metric"
		(layer "B.Cu")
		(at 84.667962 124.6665)
		(descr "Resistor SMD 0402")
		(tags "resistor SMD 0402")
		(property "Reference" "R913"
			(at -4.25 0.39 0)
			(layer "B.SilkS")
			(effects
				(font
					(size 0.7 0.7)
					(thickness 0.15)
				)
				(justify right bottom mirror)
			)
		)
		(property "Value" "R_2k2_0402"
			(at -1.011843 -1.772047 0)
			(layer "B.Fab")
			(effects
				(font
					(size 0.7 0.7)
					(thickness 0.15)
				)
				(justify right bottom mirror)
			)
		)
		(property "Datasheet" "https://www.bourns.com/docs/product-datasheets/cr.pdf"
			(at 0 0 0)
			(layer "B.Fab")
			(hide yes)
			(effects
				(font
					(size 1.27 1.27)
					(thickness 0.15)
				)
			)
		)
		(property "MPN" "CR0402-FX-2201GLF"
			(at 0 0 0)
			(unlocked yes)
			(layer "B.Fab")
			(hide yes)
			(effects
				(font
					(size 1 1)
					(thickness 0.15)
				)
				(justify mirror)
			)
		)
		(property "Manufacturer" "Bourns"
			(at 0 0 0)
			(unlocked yes)
			(layer "B.Fab")
			(hide yes)
			(effects
				(font
					(size 1 1)
					(thickness 0.15)
				)
				(justify mirror)
			)
		)
		(property "License" "Apache-2.0"
			(at 0 0 0)
			(unlocked yes)
			(layer "B.Fab")
			(hide yes)
			(effects
				(font
					(size 1 1)
					(thickness 0.15)
				)
				(justify mirror)
			)
		)
		(property "Author" "Antmicro"
			(at 0 0 0)
			(unlocked yes)
			(layer "B.Fab")
			(hide yes)
			(effects
				(font
					(size 1 1)
					(thickness 0.15)
				)
				(justify mirror)
			)
		)
		(property "Val" "2k2"
			(at 0 0 0)
			(unlocked yes)
			(layer "B.Fab")
			(hide yes)
			(effects
				(font
					(size 1 1)
					(thickness 0.15)
				)
				(justify mirror)
			)
		)
		(property "Tolerance" "1%"
			(at 0 0 0)
			(unlocked yes)
			(layer "B.Fab")
			(hide yes)
			(effects
				(font
					(size 1 1)
					(thickness 0.15)
				)
				(justify mirror)
			)
		)
		(sheetname "/USB/")
		(sheetfile "usb.kicad_sch")
		(attr smd)
		(fp_rect
			(start -0.925 0.47)
			(end 0.925 -0.47)
			(stroke
				(width 0.05)
				(type default)
			)
			(fill no)
			(layer "B.CrtYd")
		)
		(fp_rect
			(start -0.5 0.25)
			(end 0.5 -0.25)
			(stroke
				(width 0.15)
				(type solid)
			)
			(fill no)
			(layer "B.Fab")
		)
		(fp_text user "Author: Antmicro"
			(at -0.95 -4.169 180)
			(layer "B.Fab")
			(effects
				(font
					(size 0.7 0.7)
					(thickness 0.15)
				)
				(justify left bottom mirror)
			)
		)
		(fp_text user "${REFERENCE}"
			(at -0.95 -3.168 180)
			(layer "B.Fab")
			(effects
				(font
					(size 0.7 0.7)
					(thickness 0.15)
				)
				(justify left bottom mirror)
			)
		)
		(fp_text user "License: Apache-2.0"
			(at -0.95 -5.169 180)
			(layer "B.Fab")
			(effects
				(font
					(size 0.7 0.7)
					(thickness 0.15)
				)
				(justify left bottom mirror)
			)
		)
		(pad "1" smd roundrect
			(at -0.48 0)
			(size 0.59 0.64)
			(layers "B.Cu" "B.Mask" "B.Paste")
			(roundrect_rratio 0.25)
			(net 3 "GND")
			(pintype "passive")
		)
		(pad "2" smd roundrect
			(at 0.48 0)
			(size 0.59 0.64)
			(layers "B.Cu" "B.Mask" "B.Paste")
			(roundrect_rratio 0.25)
			(net 344 "/USB/FB_FTDI")
			(pintype "passive")
		)
	)
	(footprint "antmicro-footprints:Spacer_Drill3.7mm_H6mm_9774060151R"
		(layer "B.Cu")
		(at 41.917962 174.7165)
		(descr "Spacer M=3 h=36mm fi=5.1mm")
		(property "Reference" "H104"
			(at 1.34 4.02 180)
			(layer "B.SilkS")
			(effects
				(font
					(size 0.7 0.7)
					(thickness 0.15)
				)
				(justify left bottom mirror)
			)
		)
		(property "Value" "Spacer_Drill3.7mm_H6mm_9774060151R"
			(at 0 -4 180)
			(layer "B.Fab")
			(effects
				(font
					(size 0.7 0.7)
					(thickness 0.15)
				)
				(justify left bottom mirror)
			)
		)
		(property "Datasheet" "https://www.we-online.com/components/products/datasheet/9774060151R.pdf"
			(at 0 0 0)
			(layer "B.Fab")
			(hide yes)
			(effects
				(font
					(size 1.27 1.27)
					(thickness 0.15)
				)
			)
		)
		(property "Manufacturer" "Würth Elektronik"
			(at 0 0 0)
			(unlocked yes)
			(layer "B.Fab")
			(hide yes)
			(effects
				(font
					(size 1 1)
					(thickness 0.15)
				)
				(justify mirror)
			)
		)
		(property "MPN" "9774060151R"
			(at 0 0 0)
			(unlocked yes)
			(layer "B.Fab")
			(hide yes)
			(effects
				(font
					(size 1 1)
					(thickness 0.15)
				)
				(justify mirror)
			)
		)
		(property "Author" "Antmicro"
			(at 0 0 0)
			(unlocked yes)
			(layer "B.Fab")
			(hide yes)
			(effects
				(font
					(size 1 1)
					(thickness 0.15)
				)
				(justify mirror)
			)
		)
		(property "License" "Apache-2.0"
			(at 0 0 0)
			(unlocked yes)
			(layer "B.Fab")
			(hide yes)
			(effects
				(font
					(size 1 1)
					(thickness 0.15)
				)
				(justify mirror)
			)
		)
		(sheetname "/")
		(sheetfile "cm4-baseboard.kicad_sch")
		(solder_paste_margin_ratio -1)
		(attr smd)
		(fp_circle
			(center 0 0)
			(end 3.05 0)
			(stroke
				(width 0.05)
				(type solid)
			)
			(fill no)
			(layer "B.CrtYd")
		)
		(fp_circle
			(center 0 0)
			(end 2.6 0)
			(stroke
				(width 0.15)
				(type solid)
			)
			(fill no)
			(layer "B.Fab")
		)
		(fp_text user "${REFERENCE}"
			(at -9.6 -6.5 180)
			(layer "B.Fab")
			(effects
				(font
					(size 0.7 0.7)
					(thickness 0.15)
				)
				(justify left bottom mirror)
			)
		)
		(fp_text user "License: Apache-2.0"
			(at -9.6 -8.9 180)
			(layer "B.Fab")
			(effects
				(font
					(size 0.7 0.7)
					(thickness 0.15)
				)
				(justify left bottom mirror)
			)
		)
		(fp_text user "Author: Antmicro"
			(at -9.6 -7.7 180)
			(layer "B.Fab")
			(effects
				(font
					(size 0.7 0.7)
					(thickness 0.15)
				)
				(justify left bottom mirror)
			)
		)
		(pad "" smd custom
			(at -1.7 -1.7 270)
			(size 0.62 0.62)
			(layers "B.Paste")
			(thermal_bridge_angle 90)
			(options
				(clearance outline)
				(anchor circle)
			)
			(primitives
				(gr_arc
					(start 1.266786 0.24747)
					(mid 0.285453 -0.29439)
					(end -0.250195 -1.279127)
					(width 0.2)
				)
				(gr_arc
					(start 1.259603 0.339191)
					(mid 0.218448 -0.232561)
					(end -0.34334 -1.279127)
					(width 0.2)
				)
				(gr_arc
					(start 1.255279 0.431435)
					(mid 0.152481 -0.169693)
					(end -0.436309 -1.279127)
					(width 0.2)
				)
				(gr_arc
					(start 1.253811 0.524161)
					(mid 0.087542 -0.105784)
					(end -0.529126 -1.279127)
					(width 0.2)
				)
				(gr_arc
					(start 1.275473 0.621136)
					(mid 0.0309 -0.033527)
					(end -0.621807 -1.279127)
					(width 0.2)
				)
				(gr_arc
					(start 1.263664 0.711602)
					(mid -0.037759 0.026651)
					(end -0.71437 -1.279127)
					(width 0.2)
				)
				(gr_arc
					(start 1.253435 0.802342)
					(mid -0.105837 0.087395)
					(end -0.806826 -1.279127)
					(width 0.2)
				)
				(gr_arc
					(start 1.267475 0.897258)
					(mid -0.165236 0.156885)
					(end -0.899187 -1.279127)
					(width 0.2)
				)
				(gr_arc
					(start 1.270645 0.990112)
					(mid -0.228522 0.222449)
					(end -0.991463 -1.279127)
					(width 0.2)
				)
				(gr_arc
					(start 1.266278 1.081674)
					(mid -0.294507 0.285313)
					(end -1.083663 -1.279127)
					(width 0.2)
				)
				(gr_line
					(start 1.279127 0.250195)
					(end 1.279127 1.083663)
					(width 0.2)
				)
				(gr_line
					(start -0.250195 -1.279127)
					(end -1.083663 -1.279127)
					(width 0.2)
				)
			)
		)
		(pad "" smd custom
			(at -1.7 1.7)
			(size 0.62 0.62)
			(layers "B.Paste")
			(thermal_bridge_angle 90)
			(options
				(clearance outline)
				(anchor circle)
			)
			(primitives
				(gr_arc
					(start 1.266786 0.24747)
					(mid 0.285453 -0.29439)
					(end -0.250195 -1.279127)
					(width 0.2)
				)
				(gr_arc
					(start 1.259603 0.339191)
					(mid 0.218448 -0.232561)
					(end -0.34334 -1.279127)
					(width 0.2)
				)
				(gr_arc
					(start 1.255279 0.431435)
					(mid 0.152481 -0.169693)
					(end -0.436309 -1.279127)
					(width 0.2)
				)
				(gr_arc
					(start 1.253811 0.524161)
					(mid 0.087542 -0.105784)
					(end -0.529126 -1.279127)
					(width 0.2)
				)
				(gr_arc
					(start 1.275473 0.621136)
					(mid 0.0309 -0.033527)
					(end -0.621807 -1.279127)
					(width 0.2)
				)
				(gr_arc
					(start 1.263664 0.711602)
					(mid -0.037759 0.026651)
					(end -0.71437 -1.279127)
					(width 0.2)
				)
				(gr_arc
					(start 1.253435 0.802342)
					(mid -0.105837 0.087395)
					(end -0.806826 -1.279127)
					(width 0.2)
				)
				(gr_arc
					(start 1.267475 0.897258)
					(mid -0.165236 0.156885)
					(end -0.899187 -1.279127)
					(width 0.2)
				)
				(gr_arc
					(start 1.270645 0.990112)
					(mid -0.228522 0.222449)
					(end -0.991463 -1.279127)
					(width 0.2)
				)
				(gr_arc
					(start 1.266278 1.081674)
					(mid -0.294507 0.285313)
					(end -1.083663 -1.279127)
					(width 0.2)
				)
				(gr_line
					(start 1.279127 0.250195)
					(end 1.279127 1.083663)
					(width 0.2)
				)
				(gr_line
					(start -0.250195 -1.279127)
					(end -1.083663 -1.279127)
					(width 0.2)
				)
			)
		)
		(pad "" smd custom
			(at 1.7 -1.7 180)
			(size 0.62 0.62)
			(layers "B.Paste")
			(thermal_bridge_angle 90)
			(options
				(clearance outline)
				(anchor circle)
			)
			(primitives
				(gr_arc
					(start 1.266786 0.24747)
					(mid 0.285453 -0.29439)
					(end -0.250195 -1.279127)
					(width 0.2)
				)
				(gr_arc
					(start 1.259603 0.339191)
					(mid 0.218448 -0.232561)
					(end -0.34334 -1.279127)
					(width 0.2)
				)
				(gr_arc
					(start 1.255279 0.431435)
					(mid 0.152481 -0.169693)
					(end -0.436309 -1.279127)
					(width 0.2)
				)
				(gr_arc
					(start 1.253811 0.524161)
					(mid 0.087542 -0.105784)
					(end -0.529126 -1.279127)
					(width 0.2)
				)
				(gr_arc
					(start 1.275473 0.621136)
					(mid 0.0309 -0.033527)
					(end -0.621807 -1.279127)
					(width 0.2)
				)
				(gr_arc
					(start 1.263664 0.711602)
					(mid -0.037759 0.026651)
					(end -0.71437 -1.279127)
					(width 0.2)
				)
				(gr_arc
					(start 1.253435 0.802342)
					(mid -0.105837 0.087395)
					(end -0.806826 -1.279127)
					(width 0.2)
				)
				(gr_arc
					(start 1.267475 0.897258)
					(mid -0.165236 0.156885)
					(end -0.899187 -1.279127)
					(width 0.2)
				)
				(gr_arc
					(start 1.270645 0.990112)
					(mid -0.228522 0.222449)
					(end -0.991463 -1.279127)
					(width 0.2)
				)
				(gr_arc
					(start 1.266278 1.081674)
					(mid -0.294507 0.285313)
					(end -1.083663 -1.279127)
					(width 0.2)
				)
				(gr_line
					(start 1.279127 0.250195)
					(end 1.279127 1.083663)
					(width 0.2)
				)
				(gr_line
					(start -0.250195 -1.279127)
					(end -1.083663 -1.279127)
					(width 0.2)
				)
			)
		)
		(pad "" smd custom
			(at 1.7 1.7 90)
			(size 0.62 0.62)
			(layers "B.Paste")
			(thermal_bridge_angle 90)
			(options
				(clearance outline)
				(anchor circle)
			)
			(primitives
				(gr_arc
					(start 1.266786 0.24747)
					(mid 0.285453 -0.29439)
					(end -0.250195 -1.279127)
					(width 0.2)
				)
				(gr_arc
					(start 1.259603 0.339191)
					(mid 0.218448 -0.232561)
					(end -0.34334 -1.279127)
					(width 0.2)
				)
				(gr_arc
					(start 1.255279 0.431435)
					(mid 0.152481 -0.169693)
					(end -0.436309 -1.279127)
					(width 0.2)
				)
				(gr_arc
					(start 1.253811 0.524161)
					(mid 0.087542 -0.105784)
					(end -0.529126 -1.279127)
					(width 0.2)
				)
				(gr_arc
					(start 1.275473 0.621136)
					(mid 0.0309 -0.033527)
					(end -0.621807 -1.279127)
					(width 0.2)
				)
				(gr_arc
					(start 1.263664 0.711602)
					(mid -0.037759 0.026651)
					(end -0.71437 -1.279127)
					(width 0.2)
				)
				(gr_arc
					(start 1.253435 0.802342)
					(mid -0.105837 0.087395)
					(end -0.806826 -1.279127)
					(width 0.2)
				)
				(gr_arc
					(start 1.267475 0.897258)
					(mid -0.165236 0.156885)
					(end -0.899187 -1.279127)
					(width 0.2)
				)
				(gr_arc
					(start 1.270645 0.990112)
					(mid -0.228522 0.222449)
					(end -0.991463 -1.279127)
					(width 0.2)
				)
				(gr_arc
					(start 1.266278 1.081674)
					(mid -0.294507 0.285313)
					(end -1.083663 -1.279127)
					(width 0.2)
				)
				(gr_line
					(start 1.279127 0.250195)
					(end 1.279127 1.083663)
					(width 0.2)
				)
				(gr_line
					(start -0.250195 -1.279127)
					(end -1.083663 -1.279127)
					(width 0.2)
				)
			)
		)
		(pad "1" thru_hole circle
			(at 0 0)
			(size 6 6)
			(drill 3.7)
			(layers "*.Cu" "*.Mask")
			(remove_unused_layers no)
			(net 3 "GND")
			(pintype "passive")
		)
	)
	(footprint "antmicro-footprints:Spacer_Drill3.7mm_H6mm_9774060151R"
		(layer "B.Cu")
		(at 138.917962 116.7165 180)
		(descr "Spacer M=3 h=36mm fi=5.1mm")
		(property "Reference" "H101"
			(at 0 3.2 0)
			(layer "B.SilkS")
			(effects
				(font
					(size 0.7 0.7)
					(thickness 0.15)
				)
				(justify left bottom mirror)
			)
		)
		(property "Value" "Spacer_Drill3.7mm_H6mm_9774060151R"
			(at 0 -4 0)
			(layer "B.Fab")
			(effects
				(font
					(size 0.7 0.7)
					(thickness 0.15)
				)
				(justify left bottom mirror)
			)
		)
		(property "Datasheet" "https://www.we-online.com/components/products/datasheet/9774060151R.pdf"
			(at 0 0 180)
			(layer "B.Fab")
			(hide yes)
			(effects
				(font
					(size 1.27 1.27)
					(thickness 0.15)
				)
			)
		)
		(property "Manufacturer" "Würth Elektronik"
			(at 0 0 180)
			(unlocked yes)
			(layer "B.Fab")
			(hide yes)
			(effects
				(font
					(size 1 1)
					(thickness 0.15)
				)
				(justify mirror)
			)
		)
		(property "MPN" "9774060151R"
			(at 0 0 180)
			(unlocked yes)
			(layer "B.Fab")
			(hide yes)
			(effects
				(font
					(size 1 1)
					(thickness 0.15)
				)
				(justify mirror)
			)
		)
		(property "Author" "Antmicro"
			(at 0 0 180)
			(unlocked yes)
			(layer "B.Fab")
			(hide yes)
			(effects
				(font
					(size 1 1)
					(thickness 0.15)
				)
				(justify mirror)
			)
		)
		(property "License" "Apache-2.0"
			(at 0 0 180)
			(unlocked yes)
			(layer "B.Fab")
			(hide yes)
			(effects
				(font
					(size 1 1)
					(thickness 0.15)
				)
				(justify mirror)
			)
		)
		(sheetname "/")
		(sheetfile "cm4-baseboard.kicad_sch")
		(solder_paste_margin_ratio -1)
		(attr smd)
		(fp_circle
			(center 0 0)
			(end 3.05 0)
			(stroke
				(width 0.05)
				(type solid)
			)
			(fill no)
			(layer "B.CrtYd")
		)
		(fp_circle
			(center 0 0)
			(end 2.6 0)
			(stroke
				(width 0.15)
				(type solid)
			)
			(fill no)
			(layer "B.Fab")
		)
		(fp_text user "Author: Antmicro"
			(at -9.6 -7.7 0)
			(layer "B.Fab")
			(effects
				(font
					(size 0.7 0.7)
					(thickness 0.15)
				)
				(justify left bottom mirror)
			)
		)
		(fp_text user "License: Apache-2.0"
			(at -9.6 -8.9 0)
			(layer "B.Fab")
			(effects
				(font
					(size 0.7 0.7)
					(thickness 0.15)
				)
				(justify left bottom mirror)
			)
		)
		(fp_text user "${REFERENCE}"
			(at -9.6 -6.5 0)
			(layer "B.Fab")
			(effects
				(font
					(size 0.7 0.7)
					(thickness 0.15)
				)
				(justify left bottom mirror)
			)
		)
		(pad "" smd custom
			(at -1.7 -1.7 90)
			(size 0.62 0.62)
			(layers "B.Paste")
			(thermal_bridge_angle 90)
			(options
				(clearance outline)
				(anchor circle)
			)
			(primitives
				(gr_arc
					(start 1.266786 0.24747)
					(mid 0.285453 -0.29439)
					(end -0.250195 -1.279127)
					(width 0.2)
				)
				(gr_arc
					(start 1.259603 0.339191)
					(mid 0.218448 -0.232561)
					(end -0.34334 -1.279127)
					(width 0.2)
				)
				(gr_arc
					(start 1.255279 0.431435)
					(mid 0.152481 -0.169693)
					(end -0.436309 -1.279127)
					(width 0.2)
				)
				(gr_arc
					(start 1.253811 0.524161)
					(mid 0.087542 -0.105784)
					(end -0.529126 -1.279127)
					(width 0.2)
				)
				(gr_arc
					(start 1.275473 0.621136)
					(mid 0.0309 -0.033527)
					(end -0.621807 -1.279127)
					(width 0.2)
				)
				(gr_arc
					(start 1.263664 0.711602)
					(mid -0.037759 0.026651)
					(end -0.71437 -1.279127)
					(width 0.2)
				)
				(gr_arc
					(start 1.253435 0.802342)
					(mid -0.105837 0.087395)
					(end -0.806826 -1.279127)
					(width 0.2)
				)
				(gr_arc
					(start 1.267475 0.897258)
					(mid -0.165236 0.156885)
					(end -0.899187 -1.279127)
					(width 0.2)
				)
				(gr_arc
					(start 1.270645 0.990112)
					(mid -0.228522 0.222449)
					(end -0.991463 -1.279127)
					(width 0.2)
				)
				(gr_arc
					(start 1.266278 1.081674)
					(mid -0.294507 0.285313)
					(end -1.083663 -1.279127)
					(width 0.2)
				)
				(gr_line
					(start 1.279127 0.250195)
					(end 1.279127 1.083663)
					(width 0.2)
				)
				(gr_line
					(start -0.250195 -1.279127)
					(end -1.083663 -1.279127)
					(width 0.2)
				)
			)
		)
		(pad "" smd custom
			(at -1.7 1.7 180)
			(size 0.62 0.62)
			(layers "B.Paste")
			(thermal_bridge_angle 90)
			(options
				(clearance outline)
				(anchor circle)
			)
			(primitives
				(gr_arc
					(start 1.266786 0.24747)
					(mid 0.285453 -0.29439)
					(end -0.250195 -1.279127)
					(width 0.2)
				)
				(gr_arc
					(start 1.259603 0.339191)
					(mid 0.218448 -0.232561)
					(end -0.34334 -1.279127)
					(width 0.2)
				)
				(gr_arc
					(start 1.255279 0.431435)
					(mid 0.152481 -0.169693)
					(end -0.436309 -1.279127)
					(width 0.2)
				)
				(gr_arc
					(start 1.253811 0.524161)
					(mid 0.087542 -0.105784)
					(end -0.529126 -1.279127)
					(width 0.2)
				)
				(gr_arc
					(start 1.275473 0.621136)
					(mid 0.0309 -0.033527)
					(end -0.621807 -1.279127)
					(width 0.2)
				)
				(gr_arc
					(start 1.263664 0.711602)
					(mid -0.037759 0.026651)
					(end -0.71437 -1.279127)
					(width 0.2)
				)
				(gr_arc
					(start 1.253435 0.802342)
					(mid -0.105837 0.087395)
					(end -0.806826 -1.279127)
					(width 0.2)
				)
				(gr_arc
					(start 1.267475 0.897258)
					(mid -0.165236 0.156885)
					(end -0.899187 -1.279127)
					(width 0.2)
				)
				(gr_arc
					(start 1.270645 0.990112)
					(mid -0.228522 0.222449)
					(end -0.991463 -1.279127)
					(width 0.2)
				)
				(gr_arc
					(start 1.266278 1.081674)
					(mid -0.294507 0.285313)
					(end -1.083663 -1.279127)
					(width 0.2)
				)
				(gr_line
					(start 1.279127 0.250195)
					(end 1.279127 1.083663)
					(width 0.2)
				)
				(gr_line
					(start -0.250195 -1.279127)
					(end -1.083663 -1.279127)
					(width 0.2)
				)
			)
		)
		(pad "" smd custom
			(at 1.7 -1.7)
			(size 0.62 0.62)
			(layers "B.Paste")
			(thermal_bridge_angle 90)
			(options
				(clearance outline)
				(anchor circle)
			)
			(primitives
				(gr_arc
					(start 1.266786 0.24747)
					(mid 0.285453 -0.29439)
					(end -0.250195 -1.279127)
					(width 0.2)
				)
				(gr_arc
					(start 1.259603 0.339191)
					(mid 0.218448 -0.232561)
					(end -0.34334 -1.279127)
					(width 0.2)
				)
				(gr_arc
					(start 1.255279 0.431435)
					(mid 0.152481 -0.169693)
					(end -0.436309 -1.279127)
					(width 0.2)
				)
				(gr_arc
					(start 1.253811 0.524161)
					(mid 0.087542 -0.105784)
					(end -0.529126 -1.279127)
					(width 0.2)
				)
				(gr_arc
					(start 1.275473 0.621136)
					(mid 0.0309 -0.033527)
					(end -0.621807 -1.279127)
					(width 0.2)
				)
				(gr_arc
					(start 1.263664 0.711602)
					(mid -0.037759 0.026651)
					(end -0.71437 -1.279127)
					(width 0.2)
				)
				(gr_arc
					(start 1.253435 0.802342)
					(mid -0.105837 0.087395)
					(end -0.806826 -1.279127)
					(width 0.2)
				)
				(gr_arc
					(start 1.267475 0.897258)
					(mid -0.165236 0.156885)
					(end -0.899187 -1.279127)
					(width 0.2)
				)
				(gr_arc
					(start 1.270645 0.990112)
					(mid -0.228522 0.222449)
					(end -0.991463 -1.279127)
					(width 0.2)
				)
				(gr_arc
					(start 1.266278 1.081674)
					(mid -0.294507 0.285313)
					(end -1.083663 -1.279127)
					(width 0.2)
				)
				(gr_line
					(start 1.279127 0.250195)
					(end 1.279127 1.083663)
					(width 0.2)
				)
				(gr_line
					(start -0.250195 -1.279127)
					(end -1.083663 -1.279127)
					(width 0.2)
				)
			)
		)
		(pad "" smd custom
			(at 1.7 1.7 270)
			(size 0.62 0.62)
			(layers "B.Paste")
			(thermal_bridge_angle 90)
			(options
				(clearance outline)
				(anchor circle)
			)
			(primitives
				(gr_arc
					(start 1.266786 0.24747)
					(mid 0.285453 -0.29439)
					(end -0.250195 -1.279127)
					(width 0.2)
				)
				(gr_arc
					(start 1.259603 0.339191)
					(mid 0.218448 -0.232561)
					(end -0.34334 -1.279127)
					(width 0.2)
				)
				(gr_arc
					(start 1.255279 0.431435)
					(mid 0.152481 -0.169693)
					(end -0.436309 -1.279127)
					(width 0.2)
				)
				(gr_arc
					(start 1.253811 0.524161)
					(mid 0.087542 -0.105784)
					(end -0.529126 -1.279127)
					(width 0.2)
				)
				(gr_arc
					(start 1.275473 0.621136)
					(mid 0.0309 -0.033527)
					(end -0.621807 -1.279127)
					(width 0.2)
				)
				(gr_arc
					(start 1.263664 0.711602)
					(mid -0.037759 0.026651)
					(end -0.71437 -1.279127)
					(width 0.2)
				)
				(gr_arc
					(start 1.253435 0.802342)
					(mid -0.105837 0.087395)
					(end -0.806826 -1.279127)
					(width 0.2)
				)
				(gr_arc
					(start 1.267475 0.897258)
					(mid -0.165236 0.156885)
					(end -0.899187 -1.279127)
					(width 0.2)
				)
				(gr_arc
					(start 1.270645 0.990112)
					(mid -0.228522 0.222449)
					(end -0.991463 -1.279127)
					(width 0.2)
				)
				(gr_arc
					(start 1.266278 1.081674)
					(mid -0.294507 0.285313)
					(end -1.083663 -1.279127)
					(width 0.2)
				)
				(gr_line
					(start 1.279127 0.250195)
					(end 1.279127 1.083663)
					(width 0.2)
				)
				(gr_line
					(start -0.250195 -1.279127)
					(end -1.083663 -1.279127)
					(width 0.2)
				)
			)
		)
		(pad "1" thru_hole circle
			(at 0 0 180)
			(size 6 6)
			(drill 3.7)
			(layers "*.Cu" "*.Mask")
			(remove_unused_layers no)
			(net 3 "GND")
			(pintype "passive")
		)
	)
	(footprint "antmicro-footprints:R_0603_1608Metric"
		(layer "B.Cu")
		(at 117.867962 135.0415 90)
		(descr "Resistor SMD 0603")
		(tags "resistor SMD 0603")
		(property "Reference" "R322"
			(at -4.015 0.14 90)
			(layer "B.SilkS")
			(effects
				(font
					(size 0.7 0.7)
					(thickness 0.15)
				)
				(justify right bottom mirror)
			)
		)
		(property "Value" "R_0R_22.4A_0603"
			(at 0 -1.6 90)
			(layer "B.Fab")
			(effects
				(font
					(size 0.7 0.7)
					(thickness 0.15)
				)
				(justify right bottom mirror)
			)
		)
		(property "Datasheet" "https://fscdn.rohm.com/en/products/databook/datasheet/passive/resistor/chip_resistor/pmr-jpw-e.pdf"
			(at 0 0 90)
			(layer "B.Fab")
			(hide yes)
			(effects
				(font
					(size 1.27 1.27)
					(thickness 0.15)
				)
			)
		)
		(property "Manufacturer" "ROHM Semiconductor"
			(at 0 0 90)
			(unlocked yes)
			(layer "B.Fab")
			(hide yes)
			(effects
				(font
					(size 1 1)
					(thickness 0.15)
				)
				(justify mirror)
			)
		)
		(property "MPN" "PMR03EZPJ000"
			(at 0 0 90)
			(unlocked yes)
			(layer "B.Fab")
			(hide yes)
			(effects
				(font
					(size 1 1)
					(thickness 0.15)
				)
				(justify mirror)
			)
		)
		(property "Val" "0R"
			(at 0 0 90)
			(unlocked yes)
			(layer "B.Fab")
			(hide yes)
			(effects
				(font
					(size 1 1)
					(thickness 0.15)
				)
				(justify mirror)
			)
		)
		(property "Author" "Antmicro"
			(at 0 0 90)
			(unlocked yes)
			(layer "B.Fab")
			(hide yes)
			(effects
				(font
					(size 1 1)
					(thickness 0.15)
				)
				(justify mirror)
			)
		)
		(property "License" "Apache-2.0"
			(at 0 0 90)
			(unlocked yes)
			(layer "B.Fab")
			(hide yes)
			(effects
				(font
					(size 1 1)
					(thickness 0.15)
				)
				(justify mirror)
			)
		)
		(property "Max. Curr." "22.4A"
			(at 0 0 90)
			(unlocked yes)
			(layer "B.Fab")
			(hide yes)
			(effects
				(font
					(size 1 1)
					(thickness 0.15)
				)
				(justify mirror)
			)
		)
		(property "Tolerance" "template_tolerance"
			(at 0 0 90)
			(unlocked yes)
			(layer "B.Fab")
			(hide yes)
			(effects
				(font
					(size 1 1)
					(thickness 0.15)
				)
				(justify mirror)
			)
		)
		(sheetname "/Supply/")
		(sheetfile "supply.kicad_sch")
		(attr smd)
		(fp_line
			(start -0.15 -0.4)
			(end 0.15 -0.4)
			(stroke
				(width 0.15)
				(type solid)
			)
			(layer "B.SilkS")
		)
		(fp_line
			(start -0.15 0.4)
			(end 0.15 0.4)
			(stroke
				(width 0.15)
				(type solid)
			)
			(layer "B.SilkS")
		)
		(fp_rect
			(start -1.25 0.65)
			(end 1.25 -0.65)
			(stroke
				(width 0.05)
				(type solid)
			)
			(fill no)
			(layer "B.CrtYd")
		)
		(fp_rect
			(start -0.8 0.4)
			(end 0.8 -0.4)
			(stroke
				(width 0.15)
				(type solid)
			)
			(fill no)
			(layer "B.Fab")
		)
		(fp_text user "License: Apache-2.0"
			(at -1.25 -5.9 270)
			(layer "B.Fab")
			(effects
				(font
					(size 0.7 0.7)
					(thickness 0.15)
				)
				(justify left bottom mirror)
			)
		)
		(fp_text user "Author: Antmicro"
			(at -1.25 -4.9 270)
			(layer "B.Fab")
			(effects
				(font
					(size 0.7 0.7)
					(thickness 0.15)
				)
				(justify left bottom mirror)
			)
		)
		(fp_text user "${REFERENCE}"
			(at -1.25 -3.898 270)
			(layer "B.Fab")
			(effects
				(font
					(size 0.7 0.7)
					(thickness 0.15)
				)
				(justify left bottom mirror)
			)
		)
		(pad "1" smd roundrect
			(at -0.7 0 90)
			(size 0.8 1)
			(layers "B.Cu" "B.Mask" "B.Paste")
			(roundrect_rratio 0.2)
			(net 78 "/Supply/OUT_M2")
			(pintype "passive")
		)
		(pad "2" smd roundrect
			(at 0.7 0 90)
			(size 0.8 1)
			(layers "B.Cu" "B.Mask" "B.Paste")
			(roundrect_rratio 0.2)
			(net 65 "3V3_SSD")
			(pintype "passive")
		)
	)
	(footprint "antmicro-footprints:Conn_FFC_WE_68715014x22"
		(layer "B.Cu")
		(at 139.617962 135.7165 -90)
		(property "Reference" "J601"
			(at -12.64 3.31 90)
			(layer "B.SilkS")
			(effects
				(font
					(size 0.7 0.7)
					(thickness 0.15)
				)
				(justify left bottom mirror)
			)
		)
		(property "Value" "Conn_FFC_WE_68715014522"
			(at 0 -4.5 90)
			(layer "B.Fab")
			(effects
				(font
					(size 0.7 0.7)
					(thickness 0.15)
				)
				(justify left bottom mirror)
			)
		)
		(property "Datasheet" "https://www.we-online.com/components/products/datasheet/68715014522.pdf"
			(at 0 0 270)
			(layer "B.Fab")
			(hide yes)
			(effects
				(font
					(size 1.27 1.27)
					(thickness 0.15)
				)
			)
		)
		(property "MPN" "68715014522"
			(at 0 0 270)
			(unlocked yes)
			(layer "B.Fab")
			(hide yes)
			(effects
				(font
					(size 1 1)
					(thickness 0.15)
				)
				(justify mirror)
			)
		)
		(property "Manufacturer" "Würth Elektronik"
			(at 0 0 270)
			(unlocked yes)
			(layer "B.Fab")
			(hide yes)
			(effects
				(font
					(size 1 1)
					(thickness 0.15)
				)
				(justify mirror)
			)
		)
		(property "Author" "Antmicro"
			(at 0 0 270)
			(unlocked yes)
			(layer "B.Fab")
			(hide yes)
			(effects
				(font
					(size 1 1)
					(thickness 0.15)
				)
				(justify mirror)
			)
		)
		(property "License" "Apache-2.0"
			(at 0 0 270)
			(unlocked yes)
			(layer "B.Fab")
			(hide yes)
			(effects
				(font
					(size 1 1)
					(thickness 0.15)
				)
				(justify mirror)
			)
		)
		(sheetname "/CSI/")
		(sheetfile "csi.kicad_sch")
		(attr smd)
		(fp_line
			(start -12.5 2.976)
			(end 12.499 2.976)
			(stroke
				(width 0.15)
				(type solid)
			)
			(layer "B.SilkS")
		)
		(fp_line
			(start -15.85 2.15)
			(end -12.5 2.15)
			(stroke
				(width 0.15)
				(type solid)
			)
			(layer "B.SilkS")
		)
		(fp_line
			(start -12.5 2.15)
			(end -12.5 2.976)
			(stroke
				(width 0.15)
				(type solid)
			)
			(layer "B.SilkS")
		)
		(fp_line
			(start 12.499 2.15)
			(end 12.499 2.976)
			(stroke
				(width 0.15)
				(type solid)
			)
			(layer "B.SilkS")
		)
		(fp_line
			(start 15.85 2.15)
			(end 12.499 2.15)
			(stroke
				(width 0.15)
				(type solid)
			)
			(layer "B.SilkS")
		)
		(fp_line
			(start -15.85 -2.7)
			(end -15.85 2.15)
			(stroke
				(width 0.15)
				(type solid)
			)
			(layer "B.SilkS")
		)
		(fp_line
			(start 15.85 -2.7)
			(end 15.85 2.15)
			(stroke
				(width 0.15)
				(type solid)
			)
			(layer "B.SilkS")
		)
		(fp_line
			(start 15.85 -2.7)
			(end -15.85 -2.7)
			(stroke
				(width 0.15)
				(type solid)
			)
			(layer "B.SilkS")
		)
		(fp_circle
			(center -12.9 2.9)
			(end -12.85 2.85)
			(stroke
				(width 0.15)
				(type solid)
			)
			(fill yes)
			(layer "B.SilkS")
		)
		(fp_rect
			(start -16.2 3.25)
			(end 16.2 -3.55)
			(stroke
				(width 0.05)
				(type solid)
			)
			(fill no)
			(layer "B.CrtYd")
		)
		(fp_text user "${REFERENCE}"
			(at -16.2 -5.9 90)
			(layer "B.Fab")
			(effects
				(font
					(size 0.7 0.7)
					(thickness 0.15)
				)
				(justify left bottom mirror)
			)
		)
		(fp_text user "Author: Antmicro"
			(at -16.2 -6.9 90)
			(layer "B.Fab")
			(effects
				(font
					(size 0.7 0.7)
					(thickness 0.15)
				)
				(justify left bottom mirror)
			)
		)
		(fp_text user "License: Apache-2.0"
			(at -16.2 -7.9 90)
			(layer "B.Fab")
			(effects
				(font
					(size 0.7 0.7)
					(thickness 0.15)
				)
				(justify left bottom mirror)
			)
		)
		(pad "1" smd roundrect
			(at -12.25 2.15 270)
			(size 0.3 1.2)
			(layers "B.Cu" "B.Mask" "B.Paste")
			(roundrect_rratio 0.25)
			(net 269 "unconnected-(J601-Pad1)")
			(pintype "passive+no_connect")
		)
		(pad "2" smd roundrect
			(at -11.75 2.15 270)
			(size 0.3 1.2)
			(layers "B.Cu" "B.Mask" "B.Paste")
			(roundrect_rratio 0.25)
			(net 270 "unconnected-(J601-Pad2)")
			(pintype "passive+no_connect")
		)
		(pad "3" smd roundrect
			(at -11.25 2.15 270)
			(size 0.3 1.2)
			(layers "B.Cu" "B.Mask" "B.Paste")
			(roundrect_rratio 0.25)
			(net 271 "unconnected-(J601-Pad3)")
			(pintype "passive+no_connect")
		)
		(pad "4" smd roundrect
			(at -10.75 2.15 270)
			(size 0.3 1.2)
			(layers "B.Cu" "B.Mask" "B.Paste")
			(roundrect_rratio 0.25)
			(net 272 "unconnected-(J601-Pad4)")
			(pintype "passive+no_connect")
		)
		(pad "5" smd roundrect
			(at -10.25 2.15 270)
			(size 0.3 1.2)
			(layers "B.Cu" "B.Mask" "B.Paste")
			(roundrect_rratio 0.25)
			(net 57 "/CSI/CSI0.D1_N")
			(pintype "passive")
		)
		(pad "6" smd roundrect
			(at -9.75 2.15 270)
			(size 0.3 1.2)
			(layers "B.Cu" "B.Mask" "B.Paste")
			(roundrect_rratio 0.25)
			(net 67 "/CSI/CSI0.D1_P")
			(pintype "passive")
		)
		(pad "7" smd roundrect
			(at -9.25 2.15 270)
			(size 0.3 1.2)
			(layers "B.Cu" "B.Mask" "B.Paste")
			(roundrect_rratio 0.25)
			(net 53 "/CSI/CSI0.D0_N")
			(pintype "passive")
		)
		(pad "8" smd roundrect
			(at -8.75 2.15 270)
			(size 0.3 1.2)
			(layers "B.Cu" "B.Mask" "B.Paste")
			(roundrect_rratio 0.25)
			(net 55 "/CSI/CSI0.D0_P")
			(pintype "passive")
		)
		(pad "9" smd roundrect
			(at -8.25 2.15 270)
			(size 0.3 1.2)
			(layers "B.Cu" "B.Mask" "B.Paste")
			(roundrect_rratio 0.25)
			(net 3 "GND")
			(pintype "passive")
		)
		(pad "10" smd roundrect
			(at -7.75 2.15 270)
			(size 0.3 1.2)
			(layers "B.Cu" "B.Mask" "B.Paste")
			(roundrect_rratio 0.25)
			(net 69 "/CSI/CSI0.CLK_N")
			(pintype "passive")
		)
		(pad "11" smd roundrect
			(at -7.25 2.15 270)
			(size 0.3 1.2)
			(layers "B.Cu" "B.Mask" "B.Paste")
			(roundrect_rratio 0.25)
			(net 71 "/CSI/CSI0.CLK_P")
			(pintype "passive")
		)
		(pad "12" smd roundrect
			(at -6.75 2.15 270)
			(size 0.3 1.2)
			(layers "B.Cu" "B.Mask" "B.Paste")
			(roundrect_rratio 0.25)
			(net 3 "GND")
			(pintype "passive")
		)
		(pad "13" smd roundrect
			(at -6.25 2.15 270)
			(size 0.3 1.2)
			(layers "B.Cu" "B.Mask" "B.Paste")
			(roundrect_rratio 0.25)
			(net 273 "unconnected-(J601-Pad13)")
			(pintype "passive+no_connect")
		)
		(pad "14" smd roundrect
			(at -5.75 2.15 270)
			(size 0.3 1.2)
			(layers "B.Cu" "B.Mask" "B.Paste")
			(roundrect_rratio 0.25)
			(net 280 "unconnected-(J601-Pad14)")
			(pintype "passive+no_connect")
		)
		(pad "15" smd roundrect
			(at -5.25 2.15 270)
			(size 0.3 1.2)
			(layers "B.Cu" "B.Mask" "B.Paste")
			(roundrect_rratio 0.25)
			(net 3 "GND")
			(pintype "passive")
		)
		(pad "16" smd roundrect
			(at -4.75 2.15 270)
			(size 0.3 1.2)
			(layers "B.Cu" "B.Mask" "B.Paste")
			(roundrect_rratio 0.25)
			(net 289 "unconnected-(J601-Pad16)")
			(pintype "passive+no_connect")
		)
		(pad "17" smd roundrect
			(at -4.25 2.15 270)
			(size 0.3 1.2)
			(layers "B.Cu" "B.Mask" "B.Paste")
			(roundrect_rratio 0.25)
			(net 290 "unconnected-(J601-Pad17)")
			(pintype "passive+no_connect")
		)
		(pad "18" smd roundrect
			(at -3.75 2.15 270)
			(size 0.3 1.2)
			(layers "B.Cu" "B.Mask" "B.Paste")
			(roundrect_rratio 0.25)
			(net 3 "GND")
			(pintype "passive")
		)
		(pad "19" smd roundrect
			(at -3.25 2.15 270)
			(size 0.3 1.2)
			(layers "B.Cu" "B.Mask" "B.Paste")
			(roundrect_rratio 0.25)
			(net 68 "/CSI/CSI1.D3_N")
			(pintype "passive")
		)
		(pad "20" smd roundrect
			(at -2.75 2.15 270)
			(size 0.3 1.2)
			(layers "B.Cu" "B.Mask" "B.Paste")
			(roundrect_rratio 0.25)
			(net 70 "/CSI/CSI1.D3_P")
			(pintype "passive")
		)
		(pad "21" smd roundrect
			(at -2.25 2.15 270)
			(size 0.3 1.2)
			(layers "B.Cu" "B.Mask" "B.Paste")
			(roundrect_rratio 0.25)
			(net 56 "/CSI/CSI1.D2_N")
			(pintype "passive")
		)
		(pad "22" smd roundrect
			(at -1.75 2.15 270)
			(size 0.3 1.2)
			(layers "B.Cu" "B.Mask" "B.Paste")
			(roundrect_rratio 0.25)
			(net 58 "/CSI/CSI1.D2_P")
			(pintype "passive")
		)
		(pad "23" smd roundrect
			(at -1.25 2.15 270)
			(size 0.3 1.2)
			(layers "B.Cu" "B.Mask" "B.Paste")
			(roundrect_rratio 0.25)
			(net 46 "/CSI/CSI1.D1_N")
			(pintype "passive")
		)
		(pad "24" smd roundrect
			(at -0.75 2.15 270)
			(size 0.3 1.2)
			(layers "B.Cu" "B.Mask" "B.Paste")
			(roundrect_rratio 0.25)
			(net 50 "/CSI/CSI1.D1_P")
			(pintype "passive")
		)
		(pad "25" smd roundrect
			(at -0.25 2.15 270)
			(size 0.3 1.2)
			(layers "B.Cu" "B.Mask" "B.Paste")
			(roundrect_rratio 0.25)
			(net 42 "/CSI/CSI1.D0_N")
			(pintype "passive")
		)
		(pad "26" smd roundrect
			(at 0.248 2.15 270)
			(size 0.3 1.2)
			(layers "B.Cu" "B.Mask" "B.Paste")
			(roundrect_rratio 0.25)
			(net 44 "/CSI/CSI1.D0_P")
			(pintype "passive")
		)
		(pad "27" smd roundrect
			(at 0.748 2.15 270)
			(size 0.3 1.2)
			(layers "B.Cu" "B.Mask" "B.Paste")
			(roundrect_rratio 0.25)
			(net 3 "GND")
			(pintype "passive")
		)
		(pad "28" smd roundrect
			(at 1.249 2.15 270)
			(size 0.3 1.2)
			(layers "B.Cu" "B.Mask" "B.Paste")
			(roundrect_rratio 0.25)
			(net 52 "/CSI/CSI1.CLK_N")
			(pintype "passive")
		)
		(pad "29" smd roundrect
			(at 1.749 2.15 270)
			(size 0.3 1.2)
			(layers "B.Cu" "B.Mask" "B.Paste")
			(roundrect_rratio 0.25)
			(net 54 "/CSI/CSI1.CLK_P")
			(pintype "passive")
		)
		(pad "30" smd roundrect
			(at 2.249 2.15 270)
			(size 0.3 1.2)
			(layers "B.Cu" "B.Mask" "B.Paste")
			(roundrect_rratio 0.25)
			(net 3 "GND")
			(pintype "passive")
		)
		(pad "31" smd roundrect
			(at 2.749 2.15 270)
			(size 0.3 1.2)
			(layers "B.Cu" "B.Mask" "B.Paste")
			(roundrect_rratio 0.25)
			(net 291 "unconnected-(J601-Pad31)")
			(pintype "passive+no_connect")
		)
		(pad "32" smd roundrect
			(at 3.249 2.15 270)
			(size 0.3 1.2)
			(layers "B.Cu" "B.Mask" "B.Paste")
			(roundrect_rratio 0.25)
			(net 274 "/CSI/CamCtrl.VSYNC0")
			(pintype "passive")
		)
		(pad "33" smd roundrect
			(at 3.749 2.15 270)
			(size 0.3 1.2)
			(layers "B.Cu" "B.Mask" "B.Paste")
			(roundrect_rratio 0.25)
			(net 292 "unconnected-(J601-Pad33)")
			(pintype "passive+no_connect")
		)
		(pad "34" smd roundrect
			(at 4.248 2.15 270)
			(size 0.3 1.2)
			(layers "B.Cu" "B.Mask" "B.Paste")
			(roundrect_rratio 0.25)
			(net 275 "/CSI/CamCtrl.VSYNC1")
			(pintype "passive")
		)
		(pad "35" smd roundrect
			(at 4.748 2.15 270)
			(size 0.3 1.2)
			(layers "B.Cu" "B.Mask" "B.Paste")
			(roundrect_rratio 0.25)
			(net 293 "unconnected-(J601-Pad35)")
			(pintype "passive+no_connect")
		)
		(pad "36" smd roundrect
			(at 5.248 2.15 270)
			(size 0.3 1.2)
			(layers "B.Cu" "B.Mask" "B.Paste")
			(roundrect_rratio 0.25)
			(net 294 "unconnected-(J601-Pad36)")
			(pintype "passive+no_connect")
		)
		(pad "37" smd roundrect
			(at 5.749 2.15 270)
			(size 0.3 1.2)
			(layers "B.Cu" "B.Mask" "B.Paste")
			(roundrect_rratio 0.25)
			(net 295 "unconnected-(J601-Pad37)")
			(pintype "passive+no_connect")
		)
		(pad "38" smd roundrect
			(at 6.249 2.15 270)
			(size 0.3 1.2)
			(layers "B.Cu" "B.Mask" "B.Paste")
			(roundrect_rratio 0.25)
			(net 296 "unconnected-(J601-Pad38)")
			(pintype "passive+no_connect")
		)
		(pad "39" smd roundrect
			(at 6.749 2.15 270)
			(size 0.3 1.2)
			(layers "B.Cu" "B.Mask" "B.Paste")
			(roundrect_rratio 0.25)
			(net 141 "/CSI/I_{2}C_CSI0.SDA")
			(pintype "passive")
		)
		(pad "40" smd roundrect
			(at 7.249 2.15 270)
			(size 0.3 1.2)
			(layers "B.Cu" "B.Mask" "B.Paste")
			(roundrect_rratio 0.25)
			(net 140 "/CSI/I_{2}C_CSI0.SCL")
			(pintype "passive")
		)
		(pad "41" smd roundrect
			(at 7.749 2.15 270)
			(size 0.3 1.2)
			(layers "B.Cu" "B.Mask" "B.Paste")
			(roundrect_rratio 0.25)
			(net 143 "/CSI/I_{2}C1.SDA")
			(pintype "passive")
		)
		(pad "42" smd roundrect
			(at 8.249 2.15 270)
			(size 0.3 1.2)
			(layers "B.Cu" "B.Mask" "B.Paste")
			(roundrect_rratio 0.25)
			(net 142 "/CSI/I_{2}C1.SCL")
			(pintype "passive")
		)
		(pad "43" smd roundrect
			(at 8.749 2.15 270)
			(size 0.3 1.2)
			(layers "B.Cu" "B.Mask" "B.Paste")
			(roundrect_rratio 0.25)
			(net 297 "unconnected-(J601-Pad43)")
			(pintype "passive+no_connect")
		)
		(pad "44" smd roundrect
			(at 9.249 2.15 270)
			(size 0.3 1.2)
			(layers "B.Cu" "B.Mask" "B.Paste")
			(roundrect_rratio 0.25)
			(net 298 "unconnected-(J601-Pad44)")
			(pintype "passive+no_connect")
		)
		(pad "45" smd roundrect
			(at 9.749 2.15 270)
			(size 0.3 1.2)
			(layers "B.Cu" "B.Mask" "B.Paste")
			(roundrect_rratio 0.25)
			(net 299 "unconnected-(J601-Pad45)")
			(pintype "passive+no_connect")
		)
		(pad "46" smd roundrect
			(at 10.249 2.15 270)
			(size 0.3 1.2)
			(layers "B.Cu" "B.Mask" "B.Paste")
			(roundrect_rratio 0.25)
			(net 300 "unconnected-(J601-Pad46)")
			(pintype "passive+no_connect")
		)
		(pad "47" smd roundrect
			(at 10.749 2.15 270)
			(size 0.3 1.2)
			(layers "B.Cu" "B.Mask" "B.Paste")
			(roundrect_rratio 0.25)
			(net 19 "/CSI/CSI_3V3")
			(pintype "passive")
		)
		(pad "48" smd roundrect
			(at 11.249 2.15 270)
			(size 0.3 1.2)
			(layers "B.Cu" "B.Mask" "B.Paste")
			(roundrect_rratio 0.25)
			(net 19 "/CSI/CSI_3V3")
			(pintype "passive")
		)
		(pad "49" smd roundrect
			(at 11.749 2.15 270)
			(size 0.3 1.2)
			(layers "B.Cu" "B.Mask" "B.Paste")
			(roundrect_rratio 0.25)
			(net 20 "/CSI/CSI_5V")
			(pintype "passive")
		)
		(pad "50" smd roundrect
			(at 12.249 2.15 270)
			(size 0.3 1.2)
			(layers "B.Cu" "B.Mask" "B.Paste")
			(roundrect_rratio 0.25)
			(net 20 "/CSI/CSI_5V")
			(pintype "passive")
		)
		(pad "MP1" smd roundrect
			(at -14.198 0.3 270)
			(size 2.7 3)
			(layers "B.Cu" "B.Mask" "B.Paste")
			(roundrect_rratio 0.05)
			(net 3 "GND")
			(pinfunction "MP")
			(pintype "passive")
		)
		(pad "MP2" smd roundrect
			(at 14.198 0.3 270)
			(size 2.7 3)
			(layers "B.Cu" "B.Mask" "B.Paste")
			(roundrect_rratio 0.05)
			(net 3 "GND")
			(pinfunction "MP")
			(pintype "passive")
		)
	)
	(footprint "antmicro-footprints:Nexperia_DFN-10_2.5x1mm_P0.5mm"
		(layer "B.Cu")
		(at 110.092962 116.7165 180)
		(property "Reference" "D708"
			(at 1.385 -0.43 0)
			(layer "B.SilkS")
			(effects
				(font
					(size 0.7 0.7)
					(thickness 0.15)
				)
				(justify left bottom mirror)
			)
		)
		(property "Value" "PUSB3F96X_PASS"
			(at -0.016 -1.705 0)
			(layer "B.Fab")
			(effects
				(font
					(size 0.7 0.7)
					(thickness 0.15)
				)
				(justify left bottom mirror)
			)
		)
		(property "Datasheet" "https://mouser.com/datasheet/2/916/PUSB3F96-1600324.pdf"
			(at 0 0 180)
			(layer "B.Fab")
			(hide yes)
			(effects
				(font
					(size 1.27 1.27)
					(thickness 0.15)
				)
			)
		)
		(property "Manufacturer" "Nexperia"
			(at 0 0 180)
			(unlocked yes)
			(layer "B.Fab")
			(hide yes)
			(effects
				(font
					(size 1 1)
					(thickness 0.15)
				)
				(justify mirror)
			)
		)
		(property "MPN" "PUSB3F96X"
			(at 0 0 180)
			(unlocked yes)
			(layer "B.Fab")
			(hide yes)
			(effects
				(font
					(size 1 1)
					(thickness 0.15)
				)
				(justify mirror)
			)
		)
		(property "Author" "Antmicro"
			(at 0 0 180)
			(unlocked yes)
			(layer "B.Fab")
			(hide yes)
			(effects
				(font
					(size 1 1)
					(thickness 0.15)
				)
				(justify mirror)
			)
		)
		(property "License" "Apache-2.0"
			(at 0 0 180)
			(unlocked yes)
			(layer "B.Fab")
			(hide yes)
			(effects
				(font
					(size 1 1)
					(thickness 0.15)
				)
				(justify mirror)
			)
		)
		(sheetname "/Display/")
		(sheetfile "display.kicad_sch")
		(attr smd)
		(fp_line
			(start 1.375 -0.4)
			(end 1.375 0.4)
			(stroke
				(width 0.15)
				(type solid)
			)
			(layer "B.SilkS")
		)
		(fp_line
			(start -1.375 0.4)
			(end -1.375 -0.4)
			(stroke
				(width 0.15)
				(type solid)
			)
			(layer "B.SilkS")
		)
		(fp_circle
			(center -1.4 -0.7)
			(end -1.349 -0.7)
			(stroke
				(width 0.15)
				(type solid)
			)
			(fill yes)
			(layer "B.SilkS")
		)
		(fp_rect
			(start -1.4 0.725)
			(end 1.4 -0.725)
			(stroke
				(width 0.05)
				(type solid)
			)
			(fill no)
			(layer "B.CrtYd")
		)
		(fp_line
			(start 1.25 0.5)
			(end -1.25 0.5)
			(stroke
				(width 0.15)
				(type solid)
			)
			(layer "B.Fab")
		)
		(fp_line
			(start 1.25 -0.5)
			(end 1.25 0.5)
			(stroke
				(width 0.15)
				(type solid)
			)
			(layer "B.Fab")
		)
		(fp_line
			(start -0.9 -0.5)
			(end 1.25 -0.5)
			(stroke
				(width 0.15)
				(type solid)
			)
			(layer "B.Fab")
		)
		(fp_line
			(start -1.25 0.5)
			(end -1.25 -0.15)
			(stroke
				(width 0.15)
				(type solid)
			)
			(layer "B.Fab")
		)
		(fp_line
			(start -1.25 -0.15)
			(end -0.9 -0.5)
			(stroke
				(width 0.15)
				(type solid)
			)
			(layer "B.Fab")
		)
		(fp_text user "License: Apache-2.0"
			(at -1.367 -6.105 0)
			(layer "B.Fab")
			(effects
				(font
					(size 0.7 0.7)
					(thickness 0.15)
				)
				(justify left bottom mirror)
			)
		)
		(fp_text user "Author: Antmicro"
			(at -1.367 -4.905 0)
			(layer "B.Fab")
			(effects
				(font
					(size 0.7 0.7)
					(thickness 0.15)
				)
				(justify left bottom mirror)
			)
		)
		(fp_text user "${REFERENCE}"
			(at -1.367 -3.704 0)
			(layer "B.Fab")
			(effects
				(font
					(size 0.7 0.7)
					(thickness 0.15)
				)
				(justify left bottom mirror)
			)
		)
		(pad "1" smd rect
			(at -1 -0.3875 180)
			(size 0.2 0.475)
			(layers "B.Cu" "B.Mask" "B.Paste")
			(net 262 "/Compute module/HDMI.HPD")
			(pinfunction "CH1")
			(pintype "passive")
			(solder_mask_margin 0.05)
		)
		(pad "2" smd rect
			(at -0.5 -0.3875 180)
			(size 0.2 0.475)
			(layers "B.Cu" "B.Mask" "B.Paste")
			(net 261 "/Compute module/HDMI.CEC")
			(pinfunction "CH2")
			(pintype "passive")
			(solder_mask_margin 0.05)
		)
		(pad "3" smd rect
			(at 0 -0.3875 180)
			(size 0.2 0.475)
			(layers "B.Cu" "B.Mask" "B.Paste")
			(net 3 "GND")
			(pinfunction "GND")
			(pintype "passive")
			(solder_mask_margin 0.05)
		)
		(pad "4" smd rect
			(at 0.5 -0.3875 180)
			(size 0.2 0.475)
			(layers "B.Cu" "B.Mask" "B.Paste")
			(net 267 "/Compute module/HDMI.SCL")
			(pinfunction "CH3")
			(pintype "passive")
			(solder_mask_margin 0.05)
		)
		(pad "5" smd rect
			(at 1 -0.3875 180)
			(size 0.2 0.475)
			(layers "B.Cu" "B.Mask" "B.Paste")
			(net 266 "/Compute module/HDMI.SDA")
			(pinfunction "CH4")
			(pintype "passive")
			(solder_mask_margin 0.05)
		)
		(pad "6" smd rect
			(at 1 0.3875 180)
			(size 0.2 0.475)
			(layers "B.Cu" "B.Mask" "B.Paste")
			(net 266 "/Compute module/HDMI.SDA")
			(pinfunction "CH4")
			(pintype "passive")
			(solder_mask_margin 0.05)
		)
		(pad "7" smd rect
			(at 0.5 0.3875 180)
			(size 0.2 0.475)
			(layers "B.Cu" "B.Mask" "B.Paste")
			(net 267 "/Compute module/HDMI.SCL")
			(pinfunction "CH3")
			(pintype "passive")
			(solder_mask_margin 0.05)
		)
		(pad "8" smd rect
			(at 0 0.3875 180)
			(size 0.2 0.475)
			(layers "B.Cu" "B.Mask" "B.Paste")
			(net 3 "GND")
			(pinfunction "GND")
			(pintype "passive")
			(solder_mask_margin 0.05)
		)
		(pad "9" smd rect
			(at -0.501 0.3875 180)
			(size 0.2 0.475)
			(layers "B.Cu" "B.Mask" "B.Paste")
			(net 261 "/Compute module/HDMI.CEC")
			(pinfunction "CH2")
			(pintype "passive")
			(solder_mask_margin 0.05)
		)
		(pad "10" smd rect
			(at -1 0.3875 180)
			(size 0.2 0.475)
			(layers "B.Cu" "B.Mask" "B.Paste")
			(net 262 "/Compute module/HDMI.HPD")
			(pinfunction "CH1")
			(pintype "passive")
			(solder_mask_margin 0.05)
		)
	)
	(footprint "antmicro-footprints:FB_0603_1608Metric"
		(layer "B.Cu")
		(at 113.627962 115.9865 180)
		(property "Reference" "FB701"
			(at -2.04 -6.055 0)
			(layer "B.SilkS")
			(effects
				(font
					(size 0.7 0.7)
					(thickness 0.15)
				)
				(justify left bottom mirror)
			)
		)
		(property "Value" "FB_220Z_2.2A_TDK-MPZ_0603"
			(at 0 -1.5 0)
			(layer "B.Fab")
			(effects
				(font
					(size 0.7 0.7)
					(thickness 0.15)
				)
				(justify left bottom mirror)
			)
		)
		(property "Datasheet" "https://product.tdk.com/info/en/catalog/datasheets/beads_commercial_power_mpz1608_en.pdf"
			(at 0 0 180)
			(layer "B.Fab")
			(hide yes)
			(effects
				(font
					(size 1.27 1.27)
					(thickness 0.15)
				)
			)
		)
		(property "MPN" "MPZ1608S221ATA00"
			(at 0 0 180)
			(unlocked yes)
			(layer "B.Fab")
			(hide yes)
			(effects
				(font
					(size 1 1)
					(thickness 0.15)
				)
				(justify mirror)
			)
		)
		(property "Manufacturer" "TDK"
			(at 0 0 180)
			(unlocked yes)
			(layer "B.Fab")
			(hide yes)
			(effects
				(font
					(size 1 1)
					(thickness 0.15)
				)
				(justify mirror)
			)
		)
		(property "Author" "Antmicro"
			(at 0 0 180)
			(unlocked yes)
			(layer "B.Fab")
			(hide yes)
			(effects
				(font
					(size 1 1)
					(thickness 0.15)
				)
				(justify mirror)
			)
		)
		(property "License" "Apache-2.0"
			(at 0 0 180)
			(unlocked yes)
			(layer "B.Fab")
			(hide yes)
			(effects
				(font
					(size 1 1)
					(thickness 0.15)
				)
				(justify mirror)
			)
		)
		(property "Val" "220Z/2.2A"
			(at 0 0 180)
			(unlocked yes)
			(layer "B.Fab")
			(hide yes)
			(effects
				(font
					(size 1 1)
					(thickness 0.15)
				)
				(justify mirror)
			)
		)
		(property "Current" ""
			(at 0 0 180)
			(unlocked yes)
			(layer "B.Fab")
			(hide yes)
			(effects
				(font
					(size 1 1)
					(thickness 0.15)
				)
				(justify mirror)
			)
		)
		(sheetname "/Display/")
		(sheetfile "display.kicad_sch")
		(attr smd)
		(fp_line
			(start -0.15 0.4)
			(end 0.15 0.4)
			(stroke
				(width 0.15)
				(type solid)
			)
			(layer "B.SilkS")
		)
		(fp_line
			(start -0.15 -0.4)
			(end 0.15 -0.4)
			(stroke
				(width 0.15)
				(type solid)
			)
			(layer "B.SilkS")
		)
		(fp_rect
			(start -1.25 0.65)
			(end 1.25 -0.65)
			(stroke
				(width 0.05)
				(type solid)
			)
			(fill no)
			(layer "B.CrtYd")
		)
		(fp_line
			(start 0.8 0.408)
			(end 0.8 -0.406)
			(stroke
				(width 0.15)
				(type solid)
			)
			(layer "B.Fab")
		)
		(fp_line
			(start 0.8 0.408)
			(end -0.803 0.408)
			(stroke
				(width 0.15)
				(type solid)
			)
			(layer "B.Fab")
		)
		(fp_line
			(start 0.8 -0.406)
			(end -0.803 -0.406)
			(stroke
				(width 0.15)
				(type solid)
			)
			(layer "B.Fab")
		)
		(fp_line
			(start -0.803 -0.406)
			(end -0.803 0.408)
			(stroke
				(width 0.15)
				(type solid)
			)
			(layer "B.Fab")
		)
		(fp_text user "Author: Antmicro"
			(at -1.653 -3.162 0)
			(layer "B.Fab")
			(effects
				(font
					(size 0.7 0.7)
					(thickness 0.15)
				)
				(justify left bottom mirror)
			)
		)
		(fp_text user "License: Apache-2.0"
			(at -1.653 -5.9 0)
			(layer "B.Fab")
			(effects
				(font
					(size 0.7 0.7)
					(thickness 0.15)
				)
				(justify left bottom mirror)
			)
		)
		(fp_text user "${REFERENCE}"
			(at -1.653 -4.6 0)
			(layer "B.Fab")
			(effects
				(font
					(size 0.7 0.7)
					(thickness 0.15)
				)
				(justify left bottom mirror)
			)
		)
		(pad "1" smd roundrect
			(at -0.7 0 180)
			(size 0.8 1)
			(layers "B.Cu" "B.Mask" "B.Paste")
			(roundrect_rratio 0.2)
			(net 10 "+5V")
			(pintype "passive")
		)
		(pad "2" smd roundrect
			(at 0.7 0 180)
			(size 0.8 1)
			(layers "B.Cu" "B.Mask" "B.Paste")
			(roundrect_rratio 0.2)
			(net 481 "Net-(D710-A)")
			(pintype "passive")
		)
	)
	(footprint "antmicro-footprints:Bus_M.2_Socket_Key_M_TE_1-2199230-6"
		(locked yes)
		(layer "B.Cu")
		(at 124.392962 124.767 90)
		(property "Reference" "J501"
			(at 5.0905 5.705 90)
			(layer "B.SilkS")
			(effects
				(font
					(size 0.7 0.7)
					(thickness 0.15)
				)
				(justify right bottom mirror)
			)
		)
		(property "Value" "Bus_M.2_1-2199230-6"
			(at -11.25 -6.124 90)
			(layer "B.Fab")
			(effects
				(font
					(size 0.7 0.7)
					(thickness 0.15)
				)
				(justify right bottom mirror)
			)
		)
		(property "Datasheet" "https://www.te.com/commerce/DocumentDelivery/DDEController?Action=srchrtrv&DocNm=2199230&DocType=Customer+Drawing&DocLang=English"
			(at 0 0 90)
			(layer "B.Fab")
			(hide yes)
			(effects
				(font
					(size 1.27 1.27)
					(thickness 0.15)
				)
			)
		)
		(property "Manufacturer" "TE Connectivity"
			(at 0 0 90)
			(unlocked yes)
			(layer "B.Fab")
			(hide yes)
			(effects
				(font
					(size 1 1)
					(thickness 0.15)
				)
				(justify mirror)
			)
		)
		(property "MPN" "1-2199230-6"
			(at 0 0 90)
			(unlocked yes)
			(layer "B.Fab")
			(hide yes)
			(effects
				(font
					(size 1 1)
					(thickness 0.15)
				)
				(justify mirror)
			)
		)
		(property "Author" "Antmicro"
			(at 0 0 90)
			(unlocked yes)
			(layer "B.Fab")
			(hide yes)
			(effects
				(font
					(size 1 1)
					(thickness 0.15)
				)
				(justify mirror)
			)
		)
		(property "License" "Apache-2.0"
			(at 0 0 90)
			(unlocked yes)
			(layer "B.Fab")
			(hide yes)
			(effects
				(font
					(size 1 1)
					(thickness 0.15)
				)
				(justify mirror)
			)
		)
		(sheetname "/NVMe & microSD/")
		(sheetfile "nvme-micro-sd.kicad_sch")
		(attr smd)
		(fp_line
			(start 10.948 -3.999)
			(end 10.948 -2.3)
			(stroke
				(width 0.15)
				(type solid)
			)
			(layer "B.SilkS")
		)
		(fp_line
			(start 9.448 -3.999)
			(end 10.948 -3.999)
			(stroke
				(width 0.15)
				(type solid)
			)
			(layer "B.SilkS")
		)
		(fp_line
			(start 5.347 -3.999)
			(end 7.148 -3.999)
			(stroke
				(width 0.15)
				(type solid)
			)
			(layer "B.SilkS")
		)
		(fp_line
			(start -10.951 -3.999)
			(end -9.352 -3.999)
			(stroke
				(width 0.15)
				(type solid)
			)
			(layer "B.SilkS")
		)
		(fp_line
			(start -10.951 -2.7)
			(end -10.951 -3.999)
			(stroke
				(width 0.15)
				(type solid)
			)
			(layer "B.SilkS")
		)
		(fp_line
			(start 10.948 -0.449)
			(end 10.948 1.301)
			(stroke
				(width 0.15)
				(type solid)
			)
			(layer "B.SilkS")
		)
		(fp_line
			(start -10.951 1.401)
			(end -10.951 -0.55)
			(stroke
				(width 0.15)
				(type solid)
			)
			(layer "B.SilkS")
		)
		(fp_line
			(start 5.097 3.75)
			(end 6.898 3.75)
			(stroke
				(width 0.15)
				(type solid)
			)
			(layer "B.SilkS")
		)
		(fp_circle
			(center -9.25 4.875)
			(end -9.201 4.826)
			(stroke
				(width 0.15)
				(type solid)
			)
			(fill yes)
			(layer "B.SilkS")
		)
		(fp_circle
			(center -9.25 5.651)
			(end -9.2 5.651)
			(stroke
				(width 0.15)
				(type solid)
			)
			(fill yes)
			(layer "B.SilkS")
		)
		(fp_line
			(start 11.15 -4.78)
			(end 11.15 4.83)
			(stroke
				(width 0.05)
				(type solid)
			)
			(layer "B.CrtYd")
		)
		(fp_line
			(start -11.16 -4.78)
			(end 11.15 -4.78)
			(stroke
				(width 0.05)
				(type solid)
			)
			(layer "B.CrtYd")
		)
		(fp_line
			(start 11.15 4.83)
			(end -11.16 4.83)
			(stroke
				(width 0.05)
				(type solid)
			)
			(layer "B.CrtYd")
		)
		(fp_line
			(start -11.16 4.83)
			(end -11.16 -4.78)
			(stroke
				(width 0.05)
				(type solid)
			)
			(layer "B.CrtYd")
		)
		(fp_line
			(start 10.95 -4.2)
			(end -10.949 -4.2)
			(stroke
				(width 0.15)
				(type solid)
			)
			(layer "B.Fab")
		)
		(fp_line
			(start -10.949 -4.2)
			(end -10.949 3.55)
			(stroke
				(width 0.15)
				(type solid)
			)
			(layer "B.Fab")
		)
		(fp_line
			(start -10.949 3.55)
			(end -10.4 4.1)
			(stroke
				(width 0.15)
				(type solid)
			)
			(layer "B.Fab")
		)
		(fp_line
			(start 10.95 4.1)
			(end 10.95 -4.2)
			(stroke
				(width 0.15)
				(type solid)
			)
			(layer "B.Fab")
		)
		(fp_line
			(start -10.4 4.1)
			(end 10.95 4.1)
			(stroke
				(width 0.15)
				(type solid)
			)
			(layer "B.Fab")
		)
		(fp_text user "License: Apache-2.0"
			(at -11.35 -10.525 270)
			(layer "B.Fab")
			(effects
				(font
					(size 0.7 0.7)
					(thickness 0.15)
				)
				(justify left bottom mirror)
			)
		)
		(fp_text user "Author: Antmicro"
			(at -11.35 -9.325 270)
			(layer "B.Fab")
			(effects
				(font
					(size 0.7 0.7)
					(thickness 0.15)
				)
				(justify left bottom mirror)
			)
		)
		(fp_text user "${REFERENCE}"
			(at -11.35 -8.124 270)
			(layer "B.Fab")
			(effects
				(font
					(size 0.7 0.7)
					(thickness 0.15)
				)
				(justify left bottom mirror)
			)
		)
		(pad "" np_thru_hole circle
			(at -10 -1.499 90)
			(size 1.1 1.1)
			(drill 1.1)
			(layers "*.Mask")
		)
		(pad "" np_thru_hole circle
			(at 9.997 -1.499 90)
			(size 1.6 1.6)
			(drill 1.6)
			(layers "*.Mask")
		)
		(pad "1" smd rect
			(at -9.25 3.775 90)
			(size 0.3 1.55)
			(layers "B.Cu" "B.Mask" "B.Paste")
			(net 3 "GND")
			(pinfunction "GND")
			(pintype "power_in")
		)
		(pad "2" smd rect
			(at -9.003 -3.773 90)
			(size 0.3 1.55)
			(layers "B.Cu" "B.Mask" "B.Paste")
			(net 65 "3V3_SSD")
			(pinfunction "3V3")
			(pintype "passive")
		)
		(pad "3" smd rect
			(at -8.753 3.775 90)
			(size 0.3 1.55)
			(layers "B.Cu" "B.Mask" "B.Paste")
			(net 3 "GND")
			(pinfunction "GND")
			(pintype "passive")
		)
		(pad "4" smd rect
			(at -8.503 -3.773 90)
			(size 0.3 1.55)
			(layers "B.Cu" "B.Mask" "B.Paste")
			(net 65 "3V3_SSD")
			(pinfunction "3V3")
			(pintype "passive")
		)
		(pad "5" smd rect
			(at -8.253 3.775 90)
			(size 0.3 1.55)
			(layers "B.Cu" "B.Mask" "B.Paste")
			(net 158 "/Compute module/NVMe.RX3_N")
			(pinfunction "PER3_N")
			(pintype "output")
		)
		(pad "6" smd rect
			(at -8.001 -3.773 90)
			(size 0.3 1.55)
			(layers "B.Cu" "B.Mask" "B.Paste")
			(net 246 "unconnected-(J501-NC-Pad6)")
			(pinfunction "NC")
			(pintype "no_connect")
		)
		(pad "7" smd rect
			(at -7.752 3.775 90)
			(size 0.3 1.55)
			(layers "B.Cu" "B.Mask" "B.Paste")
			(net 159 "/Compute module/NVMe.RX3_P")
			(pinfunction "PER3_P")
			(pintype "output")
		)
		(pad "8" smd rect
			(at -7.502 -3.773 90)
			(size 0.3 1.55)
			(layers "B.Cu" "B.Mask" "B.Paste")
			(net 245 "unconnected-(J501-NC-Pad8)")
			(pinfunction "NC")
			(pintype "no_connect")
		)
		(pad "9" smd rect
			(at -7.252 3.775 90)
			(size 0.3 1.55)
			(layers "B.Cu" "B.Mask" "B.Paste")
			(net 3 "GND")
			(pinfunction "GND")
			(pintype "passive")
		)
		(pad "10" smd rect
			(at -7.002 -3.773 90)
			(size 0.3 1.55)
			(layers "B.Cu" "B.Mask" "B.Paste")
			(net 470 "Net-(D503-C)")
			(pinfunction "LED")
			(pintype "passive")
		)
		(pad "11" smd rect
			(at -6.752 3.775 90)
			(size 0.3 1.55)
			(layers "B.Cu" "B.Mask" "B.Paste")
			(net 160 "/Compute module/NVMe.TX3_N")
			(pinfunction "PET3_N")
			(pintype "input")
		)
		(pad "12" smd rect
			(at -6.502 -3.773 90)
			(size 0.3 1.55)
			(layers "B.Cu" "B.Mask" "B.Paste")
			(net 65 "3V3_SSD")
			(pinfunction "3V3")
			(pintype "passive")
		)
		(pad "13" smd rect
			(at -6.252 3.775 90)
			(size 0.3 1.55)
			(layers "B.Cu" "B.Mask" "B.Paste")
			(net 161 "/Compute module/NVMe.TX3_P")
			(pinfunction "PET3_P")
			(pintype "input")
		)
		(pad "14" smd rect
			(at -6.002 -3.773 90)
			(size 0.3 1.55)
			(layers "B.Cu" "B.Mask" "B.Paste")
			(net 65 "3V3_SSD")
			(pinfunction "3V3")
			(pintype "passive")
		)
		(pad "15" smd rect
			(at -5.752 3.775 90)
			(size 0.3 1.55)
			(layers "B.Cu" "B.Mask" "B.Paste")
			(net 3 "GND")
			(pinfunction "GND")
			(pintype "passive")
		)
		(pad "16" smd rect
			(at -5.502 -3.773 90)
			(size 0.3 1.55)
			(layers "B.Cu" "B.Mask" "B.Paste")
			(net 65 "3V3_SSD")
			(pinfunction "3V3")
			(pintype "passive")
		)
		(pad "17" smd rect
			(at -5.252 3.775 90)
			(size 0.3 1.55)
			(layers "B.Cu" "B.Mask" "B.Paste")
			(net 162 "/Compute module/NVMe.RX2_N")
			(pinfunction "PER2_N")
			(pintype "output")
		)
		(pad "18" smd rect
			(at -5.002 -3.773 90)
			(size 0.3 1.55)
			(layers "B.Cu" "B.Mask" "B.Paste")
			(net 65 "3V3_SSD")
			(pinfunction "3V3")
			(pintype "passive")
		)
		(pad "19" smd rect
			(at -4.752 3.775 90)
			(size 0.3 1.55)
			(layers "B.Cu" "B.Mask" "B.Paste")
			(net 163 "/Compute module/NVMe.RX2_P")
			(pinfunction "PER2_P")
			(pintype "output")
		)
		(pad "20" smd rect
			(at -4.502 -3.773 90)
			(size 0.3 1.55)
			(layers "B.Cu" "B.Mask" "B.Paste")
			(net 244 "unconnected-(J501-NC-Pad20)")
			(pinfunction "NC")
			(pintype "no_connect")
		)
		(pad "21" smd rect
			(at -4.252 3.775 90)
			(size 0.3 1.55)
			(layers "B.Cu" "B.Mask" "B.Paste")
			(net 3 "GND")
			(pinfunction "GND")
			(pintype "passive")
		)
		(pad "22" smd rect
			(at -4.002 -3.773 90)
			(size 0.3 1.55)
			(layers "B.Cu" "B.Mask" "B.Paste")
			(net 202 "unconnected-(J501-NC-Pad22)")
			(pinfunction "NC")
			(pintype "no_connect")
		)
		(pad "23" smd rect
			(at -3.751 3.775 90)
			(size 0.3 1.55)
			(layers "B.Cu" "B.Mask" "B.Paste")
			(net 164 "/Compute module/NVMe.TX2_N")
			(pinfunction "PET2_N")
			(pintype "input")
		)
		(pad "24" smd rect
			(at -3.501 -3.773 90)
			(size 0.3 1.55)
			(layers "B.Cu" "B.Mask" "B.Paste")
			(net 201 "unconnected-(J501-NC-Pad24)")
			(pinfunction "NC")
			(pintype "no_connect")
		)
		(pad "25" smd rect
			(at -3.251 3.775 90)
			(size 0.3 1.55)
			(layers "B.Cu" "B.Mask" "B.Paste")
			(net 165 "/Compute module/NVMe.TX2_P")
			(pinfunction "PET2_P")
			(pintype "input")
		)
		(pad "26" smd rect
			(at -3.001 -3.773 90)
			(size 0.3 1.55)
			(layers "B.Cu" "B.Mask" "B.Paste")
			(net 200 "unconnected-(J501-NC-Pad26)")
			(pinfunction "NC")
			(pintype "no_connect")
		)
		(pad "27" smd rect
			(at -2.751 3.775 90)
			(size 0.3 1.55)
			(layers "B.Cu" "B.Mask" "B.Paste")
			(net 3 "GND")
			(pinfunction "GND")
			(pintype "passive")
		)
		(pad "28" smd rect
			(at -2.501 -3.773 90)
			(size 0.3 1.55)
			(layers "B.Cu" "B.Mask" "B.Paste")
			(net 199 "unconnected-(J501-NC-Pad28)")
			(pinfunction "NC")
			(pintype "no_connect")
		)
		(pad "29" smd rect
			(at -2.251 3.775 90)
			(size 0.3 1.55)
			(layers "B.Cu" "B.Mask" "B.Paste")
			(net 166 "/Compute module/NVMe.RX1_N")
			(pinfunction "PER1_N")
			(pintype "output")
		)
		(pad "30" smd rect
			(at -2.001 -3.773 90)
			(size 0.3 1.55)
			(layers "B.Cu" "B.Mask" "B.Paste")
			(net 198 "unconnected-(J501-NC-Pad30)")
			(pinfunction "NC")
			(pintype "no_connect")
		)
		(pad "31" smd rect
			(at -1.752 3.775 90)
			(size 0.3 1.55)
			(layers "B.Cu" "B.Mask" "B.Paste")
			(net 167 "/Compute module/NVMe.RX1_P")
			(pinfunction "PER1_P")
			(pintype "output")
		)
		(pad "32" smd rect
			(at -1.502 -3.773 90)
			(size 0.3 1.55)
			(layers "B.Cu" "B.Mask" "B.Paste")
			(net 197 "unconnected-(J501-NC-Pad32)")
			(pinfunction "NC")
			(pintype "no_connect")
		)
		(pad "33" smd rect
			(at -1.252 3.775 90)
			(size 0.3 1.55)
			(layers "B.Cu" "B.Mask" "B.Paste")
			(net 3 "GND")
			(pinfunction "GND")
			(pintype "passive")
		)
		(pad "34" smd rect
			(at -1.002 -3.773 90)
			(size 0.3 1.55)
			(layers "B.Cu" "B.Mask" "B.Paste")
			(net 196 "unconnected-(J501-NC-Pad34)")
			(pinfunction "NC")
			(pintype "no_connect")
		)
		(pad "35" smd rect
			(at -0.751 3.775 90)
			(size 0.3 1.55)
			(layers "B.Cu" "B.Mask" "B.Paste")
			(net 168 "/Compute module/NVMe.TX1_N")
			(pinfunction "PET1_N")
			(pintype "input")
		)
		(pad "36" smd rect
			(at -0.501 -3.773 90)
			(size 0.3 1.55)
			(layers "B.Cu" "B.Mask" "B.Paste")
			(net 195 "unconnected-(J501-NC-Pad36)")
			(pinfunction "NC")
			(pintype "no_connect")
		)
		(pad "37" smd rect
			(at -0.251 3.775 90)
			(size 0.3 1.55)
			(layers "B.Cu" "B.Mask" "B.Paste")
			(net 169 "/Compute module/NVMe.TX1_P")
			(pinfunction "PET1_P")
			(pintype "input")
		)
		(pad "38" smd rect
			(at -0.001 -3.773 90)
			(size 0.3 1.55)
			(layers "B.Cu" "B.Mask" "B.Paste")
			(net 194 "unconnected-(J501-NC-Pad38)")
			(pinfunction "NC")
			(pintype "no_connect")
		)
		(pad "39" smd rect
			(at 0.248 3.775 90)
			(size 0.3 1.55)
			(layers "B.Cu" "B.Mask" "B.Paste")
			(net 3 "GND")
			(pinfunction "GND")
			(pintype "passive")
		)
		(pad "40" smd rect
			(at 0.498 -3.773 90)
			(size 0.3 1.55)
			(layers "B.Cu" "B.Mask" "B.Paste")
			(net 193 "Net-(J501-SMB_CLK)")
			(pinfunction "SMB_CLK")
			(pintype "input")
		)
		(pad "41" smd rect
			(at 0.748 3.775 90)
			(size 0.3 1.55)
			(layers "B.Cu" "B.Mask" "B.Paste")
			(net 170 "/Compute module/NVMe.RX0_N")
			(pinfunction "PER0_N")
			(pintype "output")
		)
		(pad "42" smd rect
			(at 0.998 -3.773 90)
			(size 0.3 1.55)
			(layers "B.Cu" "B.Mask" "B.Paste")
			(net 192 "Net-(J501-SMB_DATA)")
			(pinfunction "SMB_DATA")
			(pintype "bidirectional")
		)
		(pad "43" smd rect
			(at 1.249 3.775 90)
			(size 0.3 1.55)
			(layers "B.Cu" "B.Mask" "B.Paste")
			(net 171 "/Compute module/NVMe.RX0_P")
			(pinfunction "PER0_P")
			(pintype "output")
		)
		(pad "44" smd rect
			(at 1.499 -3.773 90)
			(size 0.3 1.55)
			(layers "B.Cu" "B.Mask" "B.Paste")
			(net 185 "Net-(J501-ALERT)")
			(pinfunction "ALERT")
			(pintype "output")
		)
		(pad "45" smd rect
			(at 1.749 3.775 90)
			(size 0.3 1.55)
			(layers "B.Cu" "B.Mask" "B.Paste")
			(net 3 "GND")
			(pinfunction "GND")
			(pintype "passive")
		)
		(pad "46" smd rect
			(at 1.999 -3.773 90)
			(size 0.3 1.55)
			(layers "B.Cu" "B.Mask" "B.Paste")
			(net 184 "unconnected-(J501-NC-Pad46)")
			(pinfunction "NC")
			(pintype "no_connect")
		)
		(pad "47" smd rect
			(at 2.249 3.775 90)
			(size 0.3 1.55)
			(layers "B.Cu" "B.Mask" "B.Paste")
			(net 172 "/Compute module/NVMe.TX0_N")
			(pinfunction "PET0_N")
			(pintype "input")
		)
		(pad "48" smd rect
			(at 2.499 -3.773 90)
			(size 0.3 1.55)
			(layers "B.Cu" "B.Mask" "B.Paste")
			(net 183 "unconnected-(J501-NC-Pad48)")
			(pinfunction "NC")
			(pintype "no_connect")
		)
		(pad "49" smd rect
			(at 2.749 3.775 90)
			(size 0.3 1.55)
			(layers "B.Cu" "B.Mask" "B.Paste")
			(net 173 "/Compute module/NVMe.TX0_P")
			(pinfunction "PET0_P")
			(pintype "input")
		)
		(pad "50" smd rect
			(at 2.999 -3.773 90)
			(size 0.3 1.55)
			(layers "B.Cu" "B.Mask" "B.Paste")
			(net 145 "/Compute module/NVMe.~{RST}")
			(pinfunction "~{PERST}")
			(pintype "input")
		)
		(pad "51" smd rect
			(at 3.249 3.775 90)
			(size 0.3 1.55)
			(layers "B.Cu" "B.Mask" "B.Paste")
			(net 3 "GND")
			(pinfunction "GND")
			(pintype "passive")
		)
		(pad "52" smd rect
			(at 3.499 -3.773 90)
			(size 0.3 1.55)
			(layers "B.Cu" "B.Mask" "B.Paste")
			(net 144 "/Compute module/NVMe.~{CLK_REQ}")
			(pinfunction "~{CLKREQ}")
			(pintype "output")
		)
		(pad "53" smd rect
			(at 3.749 3.775 90)
			(size 0.3 1.55)
			(layers "B.Cu" "B.Mask" "B.Paste")
			(net 41 "/Compute module/NVMe.CLK_N")
			(pinfunction "REFCLK_N")
			(pintype "input")
		)
		(pad "54" smd rect
			(at 3.999 -3.773 90)
			(size 0.3 1.55)
			(layers "B.Cu" "B.Mask" "B.Paste")
			(net 182 "Net-(J501-~{PEWAKE})")
			(pinfunction "~{PEWAKE}")
			(pintype "input")
		)
		(pad "55" smd rect
			(at 4.248 3.775 90)
			(size 0.3 1.55)
			(layers "B.Cu" "B.Mask" "B.Paste")
			(net 40 "/Compute module/NVMe.CLK_P")
			(pinfunction "REFCLK_P")
			(pintype "input")
		)
		(pad "56" smd rect
			(at 4.498 -3.773 90)
			(size 0.3 1.55)
			(layers "B.Cu" "B.Mask" "B.Paste")
			(net 181 "unconnected-(J501-NC-Pad56)")
			(pinfunction "NC")
			(pintype "no_connect")
		)
		(pad "57" smd rect
			(at 4.748 3.775 90)
			(size 0.3 1.55)
			(layers "B.Cu" "B.Mask" "B.Paste")
			(net 3 "GND")
			(pinfunction "GND")
			(pintype "passive")
		)
		(pad "58" smd rect
			(at 4.998 -3.773 90)
			(size 0.3 1.55)
			(layers "B.Cu" "B.Mask" "B.Paste")
			(net 180 "unconnected-(J501-NC-Pad58)")
			(pinfunction "NC")
			(pintype "no_connect")
		)
		(pad "67" smd rect
			(at 7.248 3.775 90)
			(size 0.3 1.55)
			(layers "B.Cu" "B.Mask" "B.Paste")
			(net 179 "unconnected-(J501-NC-Pad67)")
			(pinfunction "NC")
			(pintype "no_connect")
		)
		(pad "68" smd rect
			(at 7.498 -3.773 90)
			(size 0.3 1.55)
			(layers "B.Cu" "B.Mask" "B.Paste")
			(net 178 "Net-(J501-SUSCLK)")
			(pinfunction "SUSCLK")
			(pintype "input")
		)
		(pad "69" smd rect
			(at 7.748 3.775 90)
			(size 0.3 1.55)
			(layers "B.Cu" "B.Mask" "B.Paste")
			(net 177 "unconnected-(J501-NC-Pad69)")
			(pinfunction "NC")
			(pintype "no_connect")
		)
		(pad "70" smd rect
			(at 7.998 -3.773 90)
			(size 0.3 1.55)
			(layers "B.Cu" "B.Mask" "B.Paste")
			(net 65 "3V3_SSD")
			(pinfunction "3V3")
			(pintype "passive")
		)
		(pad "71" smd rect
			(at 8.247 3.775 90)
			(size 0.3 1.55)
			(layers "B.Cu" "B.Mask" "B.Paste")
			(net 3 "GND")
			(pinfunction "GND")
			(pintype "passive")
		)
		(pad "72" smd rect
			(at 8.497 -3.773 90)
			(size 0.3 1.55)
			(layers "B.Cu" "B.Mask" "B.Paste")
			(net 65 "3V3_SSD")
			(pinfunction "3V3")
			(pintype "passive")
		)
		(pad "73" smd rect
			(at 8.747 3.775 90)
			(size 0.3 1.55)
			(layers "B.Cu" "B.Mask" "B.Paste")
			(net 3 "GND")
			(pinfunction "GND")
			(pintype "passive")
		)
		(pad "74" smd rect
			(at 8.997 -3.773 90)
			(size 0.3 1.55)
			(layers "B.Cu" "B.Mask" "B.Paste")
			(net 65 "3V3_SSD")
			(pinfunction "3V3")
			(pintype "passive")
		)
		(pad "75" smd rect
			(at 9.247 3.775 90)
			(size 0.3 1.55)
			(layers "B.Cu" "B.Mask" "B.Paste")
			(net 3 "GND")
			(pinfunction "GND")
			(pintype "passive")
		)
		(pad "MP1" smd rect
			(at -10.352 3 90)
			(size 1.2 2.75)
			(layers "B.Cu" "B.Mask" "B.Paste")
			(net 3 "GND")
			(pinfunction "MP")
			(pintype "passive")
		)
		(pad "MP2" smd rect
			(at 10.349 3 90)
			(size 1.2 2.75)
			(layers "B.Cu" "B.Mask" "B.Paste")
			(net 3 "GND")
			(pinfunction "MP")
			(pintype "passive")
		)
	)
	(footprint "antmicro-footprints:SOT-523"
		(layer "B.Cu")
		(at 74.342962 150.6165 90)
		(property "Reference" "Q210"
			(at 1.1665 -1.292962 180)
			(layer "B.SilkS")
			(effects
				(font
					(size 0.7 0.7)
					(thickness 0.15)
				)
				(justify right bottom mirror)
			)
		)
		(property "Value" "PJE138K"
			(at 0.1 -1.824 90)
			(layer "B.Fab")
			(effects
				(font
					(size 0.7 0.7)
					(thickness 0.15)
				)
				(justify right bottom mirror)
			)
		)
		(property "Datasheet" "https://www.mouser.com/datasheet/2/1057/PJE138K-1876698.pdf"
			(at 0 0 90)
			(layer "B.Fab")
			(hide yes)
			(effects
				(font
					(size 1.27 1.27)
					(thickness 0.15)
				)
			)
		)
		(property "MPN" "PJE138K_R1_00001"
			(at 0 0 90)
			(unlocked yes)
			(layer "B.Fab")
			(hide yes)
			(effects
				(font
					(size 1 1)
					(thickness 0.15)
				)
				(justify mirror)
			)
		)
		(property "Manufacturer" "PANJIT"
			(at 0 0 90)
			(unlocked yes)
			(layer "B.Fab")
			(hide yes)
			(effects
				(font
					(size 1 1)
					(thickness 0.15)
				)
				(justify mirror)
			)
		)
		(property "Author" "Antmicro"
			(at 0 0 90)
			(unlocked yes)
			(layer "B.Fab")
			(hide yes)
			(effects
				(font
					(size 1 1)
					(thickness 0.15)
				)
				(justify mirror)
			)
		)
		(property "License" "Apache-2.0"
			(at 0 0 90)
			(unlocked yes)
			(layer "B.Fab")
			(hide yes)
			(effects
				(font
					(size 1 1)
					(thickness 0.15)
				)
				(justify mirror)
			)
		)
		(sheetname "/Compute module/")
		(sheetfile "compute-module.kicad_sch")
		(attr smd)
		(fp_line
			(start -0.927 0.051)
			(end -0.927 0.351)
			(stroke
				(width 0.15)
				(type solid)
			)
			(layer "B.SilkS")
		)
		(fp_line
			(start -0.927 0.351)
			(end -0.725 0.551)
			(stroke
				(width 0.15)
				(type solid)
			)
			(layer "B.SilkS")
		)
		(fp_line
			(start -0.277 0.551)
			(end -0.277 0.75)
			(stroke
				(width 0.15)
				(type solid)
			)
			(layer "B.SilkS")
		)
		(fp_line
			(start -0.725 0.551)
			(end -0.277 0.551)
			(stroke
				(width 0.15)
				(type solid)
			)
			(layer "B.SilkS")
		)
		(fp_circle
			(center -0.9652 -0.9652)
			(end -0.9152 -0.9652)
			(stroke
				(width 0.15)
				(type solid)
			)
			(fill yes)
			(layer "B.SilkS")
		)
		(fp_line
			(start -1.12 -1.15)
			(end 1.1 -1.15)
			(stroke
				(width 0.05)
				(type solid)
			)
			(layer "B.CrtYd")
		)
		(fp_line
			(start 1.1 1.16)
			(end 1.1 -1.15)
			(stroke
				(width 0.05)
				(type solid)
			)
			(layer "B.CrtYd")
		)
		(fp_line
			(start -1.12 1.16)
			(end -1.12 -1.15)
			(stroke
				(width 0.05)
				(type solid)
			)
			(layer "B.CrtYd")
		)
		(fp_line
			(start -1.12 1.16)
			(end 1.1 1.16)
			(stroke
				(width 0.05)
				(type solid)
			)
			(layer "B.CrtYd")
		)
		(fp_line
			(start 0.8 -0.424)
			(end -0.802 -0.424)
			(stroke
				(width 0.15)
				(type solid)
			)
			(layer "B.Fab")
		)
		(fp_line
			(start -0.802 0.276)
			(end -0.802 -0.424)
			(stroke
				(width 0.15)
				(type solid)
			)
			(layer "B.Fab")
		)
		(fp_line
			(start 0.8 0.425)
			(end 0.8 -0.424)
			(stroke
				(width 0.15)
				(type solid)
			)
			(layer "B.Fab")
		)
		(fp_line
			(start 0.8 0.425)
			(end -0.652 0.425)
			(stroke
				(width 0.15)
				(type solid)
			)
			(layer "B.Fab")
		)
		(fp_line
			(start -0.652 0.425)
			(end -0.802 0.276)
			(stroke
				(width 0.15)
				(type solid)
			)
			(layer "B.Fab")
		)
		(fp_circle
			(center -0.9652 -0.9652)
			(end -0.9144 -0.9652)
			(stroke
				(width 0.15)
				(type solid)
			)
			(fill no)
			(layer "B.Fab")
		)
		(fp_text user "${REFERENCE}"
			(at -1.12 -3.824 270)
			(layer "B.Fab")
			(effects
				(font
					(size 0.7 0.7)
					(thickness 0.15)
				)
				(justify left bottom mirror)
			)
		)
		(fp_text user "License: Apache-2.0"
			(at -1.12 -5.024 270)
			(layer "B.Fab")
			(effects
				(font
					(size 0.7 0.7)
					(thickness 0.15)
				)
				(justify left bottom mirror)
			)
		)
		(fp_text user "Author: Antmicro"
			(at -1.12 -6.224 270)
			(layer "B.Fab")
			(effects
				(font
					(size 0.7 0.7)
					(thickness 0.15)
				)
				(justify left bottom mirror)
			)
		)
		(pad "1" smd rect
			(at -0.5 -0.65 90)
			(size 0.4 0.51)
			(layers "B.Cu" "B.Mask" "B.Paste")
			(net 22 "+1V8")
			(pinfunction "G")
			(pintype "input")
		)
		(pad "2" smd rect
			(at 0.498 -0.65 90)
			(size 0.4 0.51)
			(layers "B.Cu" "B.Mask" "B.Paste")
			(net 3 "GND")
			(pinfunction "S")
			(pintype "passive")
		)
		(pad "3" smd rect
			(at 0 0.652 90)
			(size 0.4 0.51)
			(layers "B.Cu" "B.Mask" "B.Paste")
			(net 331 "Net-(Q210-D)")
			(pinfunction "D")
			(pintype "passive")
		)
	)
	(footprint "antmicro-footprints:C_0805_2012Metric"
		(layer "B.Cu")
		(at 56.667962 158.2365 90)
		(descr "Capacitor SMD 0805")
		(tags "capacitor SMD 0805")
		(property "Reference" "C312"
			(at 1.575 1.03 90)
			(layer "B.SilkS")
			(effects
				(font
					(size 0.7 0.7)
					(thickness 0.15)
				)
				(justify right bottom mirror)
			)
		)
		(property "Value" "C_22u_25V_0805"
			(at -2.055717 -1.963152 90)
			(layer "B.Fab")
			(effects
				(font
					(size 0.7 0.7)
					(thickness 0.15)
				)
				(justify right bottom mirror)
			)
		)
		(property "Datasheet" "https://product.samsungsem.com/mlcc/CL21A226MAYNNN.do"
			(at 0 0 90)
			(layer "B.Fab")
			(hide yes)
			(effects
				(font
					(size 1.27 1.27)
					(thickness 0.15)
				)
			)
		)
		(property "Manufacturer" "Samsung Electro-Mechanics"
			(at 0 0 90)
			(unlocked yes)
			(layer "B.Fab")
			(hide yes)
			(effects
				(font
					(size 1 1)
					(thickness 0.15)
				)
				(justify mirror)
			)
		)
		(property "MPN" "CL21A226MAYNNNE"
			(at 0 0 90)
			(unlocked yes)
			(layer "B.Fab")
			(hide yes)
			(effects
				(font
					(size 1 1)
					(thickness 0.15)
				)
				(justify mirror)
			)
		)
		(property "Val" "22u"
			(at 0 0 90)
			(unlocked yes)
			(layer "B.Fab")
			(hide yes)
			(effects
				(font
					(size 1 1)
					(thickness 0.15)
				)
				(justify mirror)
			)
		)
		(property "License" "Apache-2.0"
			(at 0 0 90)
			(unlocked yes)
			(layer "B.Fab")
			(hide yes)
			(effects
				(font
					(size 1 1)
					(thickness 0.15)
				)
				(justify mirror)
			)
		)
		(property "Author" "Antmicro"
			(at 0 0 90)
			(unlocked yes)
			(layer "B.Fab")
			(hide yes)
			(effects
				(font
					(size 1 1)
					(thickness 0.15)
				)
				(justify mirror)
			)
		)
		(property "Voltage" "25V"
			(at 0 0 90)
			(unlocked yes)
			(layer "B.Fab")
			(hide yes)
			(effects
				(font
					(size 1 1)
					(thickness 0.15)
				)
				(justify mirror)
			)
		)
		(property "Dielectric" "X5R"
			(at 0 0 90)
			(unlocked yes)
			(layer "B.Fab")
			(hide yes)
			(effects
				(font
					(size 1 1)
					(thickness 0.15)
				)
				(justify mirror)
			)
		)
		(property "Public" "False"
			(at 0 0 90)
			(unlocked yes)
			(layer "B.Fab")
			(hide yes)
			(effects
				(font
					(size 1 1)
					(thickness 0.15)
				)
				(justify mirror)
			)
		)
		(sheetname "/Supply/")
		(sheetfile "supply.kicad_sch")
		(attr smd)
		(fp_line
			(start -0.3 -0.7)
			(end 0.3 -0.7)
			(stroke
				(width 0.15)
				(type solid)
			)
			(layer "B.SilkS")
		)
		(fp_line
			(start -0.3 0.7)
			(end 0.3 0.7)
			(stroke
				(width 0.15)
				(type solid)
			)
			(layer "B.SilkS")
		)
		(fp_rect
			(start 1.95 0.9)
			(end -1.95 -0.9)
			(stroke
				(width 0.05)
				(type default)
			)
			(fill no)
			(layer "B.CrtYd")
		)
		(fp_rect
			(start -0.95 0.675)
			(end 0.95 -0.675)
			(stroke
				(width 0.15)
				(type solid)
			)
			(fill no)
			(layer "B.Fab")
		)
		(fp_text user "Author: Antmicro"
			(at -1.9 -5.947 270)
			(layer "B.Fab")
			(effects
				(font
					(size 0.7 0.7)
					(thickness 0.15)
				)
				(justify left bottom mirror)
			)
		)
		(fp_text user "${REFERENCE}"
			(at -1.9 -3.947 270)
			(layer "B.Fab")
			(effects
				(font
					(size 0.7 0.7)
					(thickness 0.15)
				)
				(justify left bottom mirror)
			)
		)
		(fp_text user "License: Apache-2.0"
			(at -1.9 -4.947 270)
			(layer "B.Fab")
			(effects
				(font
					(size 0.7 0.7)
					(thickness 0.15)
				)
				(justify left bottom mirror)
			)
		)
		(pad "1" smd roundrect
			(at -1.1 0 90)
			(size 1.2 1.3)
			(layers "B.Cu" "B.Mask" "B.Paste")
			(roundrect_rratio 0.25)
			(net 77 "/Supply/OUT_5V")
			(pintype "passive")
		)
		(pad "2" smd roundrect
			(at 1.1 0 90)
			(size 1.2 1.3)
			(layers "B.Cu" "B.Mask" "B.Paste")
			(roundrect_rratio 0.25)
			(net 3 "GND")
			(pintype "passive")
		)
	)
	(footprint "antmicro-footprints:R_0402_1005Metric"
		(layer "B.Cu")
		(at 52.517962 161.8145 180)
		(descr "Resistor SMD 0402")
		(tags "resistor SMD 0402")
		(property "Reference" "R306"
			(at -1.37 0.468 0)
			(layer "B.SilkS")
			(effects
				(font
					(size 0.7 0.7)
					(thickness 0.15)
				)
				(justify left bottom mirror)
			)
		)
		(property "Value" "R_470k_0402"
			(at -1.011843 -1.772047 0)
			(layer "B.Fab")
			(effects
				(font
					(size 0.7 0.7)
					(thickness 0.15)
				)
				(justify left bottom mirror)
			)
		)
		(property "Datasheet" "https://www.bourns.com/docs/product-datasheets/cr.pdf"
			(at 0 0 180)
			(layer "B.Fab")
			(hide yes)
			(effects
				(font
					(size 1.27 1.27)
					(thickness 0.15)
				)
			)
		)
		(property "MPN" "CR0402-FX-4703GLF"
			(at 0 0 180)
			(unlocked yes)
			(layer "B.Fab")
			(hide yes)
			(effects
				(font
					(size 1 1)
					(thickness 0.15)
				)
				(justify mirror)
			)
		)
		(property "Manufacturer" "Bourns"
			(at 0 0 180)
			(unlocked yes)
			(layer "B.Fab")
			(hide yes)
			(effects
				(font
					(size 1 1)
					(thickness 0.15)
				)
				(justify mirror)
			)
		)
		(property "License" "Apache-2.0"
			(at 0 0 180)
			(unlocked yes)
			(layer "B.Fab")
			(hide yes)
			(effects
				(font
					(size 1 1)
					(thickness 0.15)
				)
				(justify mirror)
			)
		)
		(property "Author" "Antmicro"
			(at 0 0 180)
			(unlocked yes)
			(layer "B.Fab")
			(hide yes)
			(effects
				(font
					(size 1 1)
					(thickness 0.15)
				)
				(justify mirror)
			)
		)
		(property "Val" "470k"
			(at 0 0 180)
			(unlocked yes)
			(layer "B.Fab")
			(hide yes)
			(effects
				(font
					(size 1 1)
					(thickness 0.15)
				)
				(justify mirror)
			)
		)
		(property "Tolerance" "1%"
			(at 0 0 180)
			(unlocked yes)
			(layer "B.Fab")
			(hide yes)
			(effects
				(font
					(size 1 1)
					(thickness 0.15)
				)
				(justify mirror)
			)
		)
		(sheetname "/Supply/")
		(sheetfile "supply.kicad_sch")
		(attr smd)
		(fp_rect
			(start -0.925 0.47)
			(end 0.925 -0.47)
			(stroke
				(width 0.05)
				(type default)
			)
			(fill no)
			(layer "B.CrtYd")
		)
		(fp_rect
			(start -0.5 0.25)
			(end 0.5 -0.25)
			(stroke
				(width 0.15)
				(type solid)
			)
			(fill no)
			(layer "B.Fab")
		)
		(fp_text user "Author: Antmicro"
			(at -0.95 -4.169 0)
			(layer "B.Fab")
			(effects
				(font
					(size 0.7 0.7)
					(thickness 0.15)
				)
				(justify left bottom mirror)
			)
		)
		(fp_text user "License: Apache-2.0"
			(at -0.95 -5.169 0)
			(layer "B.Fab")
			(effects
				(font
					(size 0.7 0.7)
					(thickness 0.15)
				)
				(justify left bottom mirror)
			)
		)
		(fp_text user "${REFERENCE}"
			(at -0.95 -3.168 0)
			(layer "B.Fab")
			(effects
				(font
					(size 0.7 0.7)
					(thickness 0.15)
				)
				(justify left bottom mirror)
			)
		)
		(pad "1" smd roundrect
			(at -0.48 0 180)
			(size 0.59 0.64)
			(layers "B.Cu" "B.Mask" "B.Paste")
			(roundrect_rratio 0.25)
			(net 3 "GND")
			(pintype "passive")
		)
		(pad "2" smd roundrect
			(at 0.48 0 180)
			(size 0.59 0.64)
			(layers "B.Cu" "B.Mask" "B.Paste")
			(roundrect_rratio 0.25)
			(net 337 "Net-(Q303-BIAS)")
			(pintype "passive")
		)
	)
	(footprint "antmicro-footprints:R_0402_1005Metric"
		(layer "B.Cu")
		(at 71.927962 128.9565)
		(descr "Resistor SMD 0402")
		(tags "resistor SMD 0402")
		(property "Reference" "R413"
			(at -0.88 2.37 0)
			(layer "B.SilkS")
			(effects
				(font
					(size 0.7 0.7)
					(thickness 0.15)
				)
				(justify right bottom mirror)
			)
		)
		(property "Value" "R_200R_0402"
			(at -1.011843 -1.772047 0)
			(layer "B.Fab")
			(effects
				(font
					(size 0.7 0.7)
					(thickness 0.15)
				)
				(justify right bottom mirror)
			)
		)
		(property "Datasheet" "https://www.bourns.com/docs/product-datasheets/cr.pdf"
			(at 0 0 0)
			(layer "B.Fab")
			(hide yes)
			(effects
				(font
					(size 1.27 1.27)
					(thickness 0.15)
				)
			)
		)
		(property "Manufacturer" "Bourns"
			(at 0 0 0)
			(unlocked yes)
			(layer "B.Fab")
			(hide yes)
			(effects
				(font
					(size 1 1)
					(thickness 0.15)
				)
				(justify mirror)
			)
		)
		(property "MPN" "CR0402-FX-2000GLF"
			(at 0 0 0)
			(unlocked yes)
			(layer "B.Fab")
			(hide yes)
			(effects
				(font
					(size 1 1)
					(thickness 0.15)
				)
				(justify mirror)
			)
		)
		(property "Val" "200R"
			(at 0 0 0)
			(unlocked yes)
			(layer "B.Fab")
			(hide yes)
			(effects
				(font
					(size 1 1)
					(thickness 0.15)
				)
				(justify mirror)
			)
		)
		(property "License" "Apache-2.0"
			(at 0 0 0)
			(unlocked yes)
			(layer "B.Fab")
			(hide yes)
			(effects
				(font
					(size 1 1)
					(thickness 0.15)
				)
				(justify mirror)
			)
		)
		(property "Author" "Antmicro"
			(at 0 0 0)
			(unlocked yes)
			(layer "B.Fab")
			(hide yes)
			(effects
				(font
					(size 1 1)
					(thickness 0.15)
				)
				(justify mirror)
			)
		)
		(property "Tolerance" "1%"
			(at 0 0 0)
			(unlocked yes)
			(layer "B.Fab")
			(hide yes)
			(effects
				(font
					(size 1 1)
					(thickness 0.15)
				)
				(justify mirror)
			)
		)
		(sheetname "/Ethernet/")
		(sheetfile "ethernet.kicad_sch")
		(attr smd)
		(fp_rect
			(start -0.925 0.47)
			(end 0.925 -0.47)
			(stroke
				(width 0.05)
				(type default)
			)
			(fill no)
			(layer "B.CrtYd")
		)
		(fp_rect
			(start -0.5 0.25)
			(end 0.5 -0.25)
			(stroke
				(width 0.15)
				(type solid)
			)
			(fill no)
			(layer "B.Fab")
		)
		(fp_text user "License: Apache-2.0"
			(at -0.95 -5.169 180)
			(layer "B.Fab")
			(effects
				(font
					(size 0.7 0.7)
					(thickness 0.15)
				)
				(justify left bottom mirror)
			)
		)
		(fp_text user "Author: Antmicro"
			(at -0.95 -4.169 180)
			(layer "B.Fab")
			(effects
				(font
					(size 0.7 0.7)
					(thickness 0.15)
				)
				(justify left bottom mirror)
			)
		)
		(fp_text user "${REFERENCE}"
			(at -0.95 -3.168 180)
			(layer "B.Fab")
			(effects
				(font
					(size 0.7 0.7)
					(thickness 0.15)
				)
				(justify left bottom mirror)
			)
		)
		(pad "1" smd roundrect
			(at -0.48 0)
			(size 0.59 0.64)
			(layers "B.Cu" "B.Mask" "B.Paste")
			(roundrect_rratio 0.25)
			(net 3 "GND")
			(pintype "passive")
		)
		(pad "2" smd roundrect
			(at 0.48 0)
			(size 0.59 0.64)
			(layers "B.Cu" "B.Mask" "B.Paste")
			(roundrect_rratio 0.25)
			(net 92 "Net-(C403-Pad1)")
			(pintype "passive")
		)
	)
	(footprint "antmicro-footprints:R_Array_4x0402_Panasonic_EXB28V"
		(layer "B.Cu")
		(at 99.017962 169.9915 90)
		(property "Reference" "R706"
			(at 3.795 1.19 90)
			(layer "B.SilkS")
			(effects
				(font
					(size 0.7 0.7)
					(thickness 0.15)
				)
				(justify right bottom mirror)
			)
		)
		(property "Value" "R_4x100R_0402_array"
			(at -1.5 -2 90)
			(layer "B.Fab")
			(effects
				(font
					(size 0.7 0.7)
					(thickness 0.15)
				)
				(justify right bottom mirror)
			)
		)
		(property "Datasheet" "http://industrial.panasonic.com/cdbs/www-data/pdf/AOC0000/AOC0000C14.pdf"
			(at 0 0 90)
			(layer "B.Fab")
			(hide yes)
			(effects
				(font
					(size 1.27 1.27)
					(thickness 0.15)
				)
			)
		)
		(property "MPN" "EXB-28V101JX"
			(at 0 0 90)
			(unlocked yes)
			(layer "B.Fab")
			(hide yes)
			(effects
				(font
					(size 1 1)
					(thickness 0.15)
				)
				(justify mirror)
			)
		)
		(property "Manufacturer" "Panasonic"
			(at 0 0 90)
			(unlocked yes)
			(layer "B.Fab")
			(hide yes)
			(effects
				(font
					(size 1 1)
					(thickness 0.15)
				)
				(justify mirror)
			)
		)
		(property "Author" "Antmicro"
			(at 0 0 90)
			(unlocked yes)
			(layer "B.Fab")
			(hide yes)
			(effects
				(font
					(size 1 1)
					(thickness 0.15)
				)
				(justify mirror)
			)
		)
		(property "License" "Apache-2.0"
			(at 0 0 90)
			(unlocked yes)
			(layer "B.Fab")
			(hide yes)
			(effects
				(font
					(size 1 1)
					(thickness 0.15)
				)
				(justify mirror)
			)
		)
		(property "Val" "R_4x100R_0402"
			(at 0 0 90)
			(unlocked yes)
			(layer "B.Fab")
			(hide yes)
			(effects
				(font
					(size 1 1)
					(thickness 0.15)
				)
				(justify mirror)
			)
		)
		(sheetname "/Display/")
		(sheetfile "display.kicad_sch")
		(attr smd)
		(fp_line
			(start 1.25 -0.499)
			(end 1.25 0.499)
			(stroke
				(width 0.15)
				(type solid)
			)
			(layer "B.SilkS")
		)
		(fp_line
			(start -1.25 0.5)
			(end -1.25 -0.498)
			(stroke
				(width 0.15)
				(type solid)
			)
			(layer "B.SilkS")
		)
		(fp_rect
			(start -1.25 0.8)
			(end 1.25 -0.8)
			(stroke
				(width 0.05)
				(type solid)
			)
			(fill no)
			(layer "B.CrtYd")
		)
		(fp_line
			(start 0.998 -0.498)
			(end -1 -0.498)
			(stroke
				(width 0.15)
				(type solid)
			)
			(layer "B.Fab")
		)
		(fp_line
			(start -1 -0.498)
			(end -1 0.5)
			(stroke
				(width 0.15)
				(type solid)
			)
			(layer "B.Fab")
		)
		(fp_line
			(start 0.998 0.5)
			(end 0.998 -0.498)
			(stroke
				(width 0.15)
				(type solid)
			)
			(layer "B.Fab")
		)
		(fp_line
			(start -1 0.5)
			(end 0.998 0.5)
			(stroke
				(width 0.15)
				(type solid)
			)
			(layer "B.Fab")
		)
		(fp_text user "${REFERENCE}"
			(at -1.5 -3.25 270)
			(layer "B.Fab")
			(effects
				(font
					(size 0.7 0.7)
					(thickness 0.15)
				)
				(justify left bottom mirror)
			)
		)
		(fp_text user "Author: Antmicro"
			(at -1.5 -4.5 270)
			(layer "B.Fab")
			(effects
				(font
					(size 0.7 0.7)
					(thickness 0.15)
				)
				(justify left bottom mirror)
			)
		)
		(fp_text user "License: Apache-2.0"
			(at -1.5 -5.75 270)
			(layer "B.Fab")
			(effects
				(font
					(size 0.7 0.7)
					(thickness 0.15)
				)
				(justify left bottom mirror)
			)
		)
		(pad "1" smd roundrect
			(at -0.8875 -0.45 90)
			(size 0.525 0.5)
			(layers "B.Cu" "B.Mask" "B.Paste")
			(roundrect_rratio 0.25)
			(net 305 "Net-(R706-R1.1)")
			(pinfunction "R1.1")
			(pintype "passive")
		)
		(pad "2" smd roundrect
			(at -0.25 -0.45 90)
			(size 0.25 0.5)
			(layers "B.Cu" "B.Mask" "B.Paste")
			(roundrect_rratio 0.25)
			(net 306 "Net-(R706-R2.1)")
			(pinfunction "R2.1")
			(pintype "passive")
		)
		(pad "3" smd roundrect
			(at 0.25 -0.45 90)
			(size 0.25 0.5)
			(layers "B.Cu" "B.Mask" "B.Paste")
			(roundrect_rratio 0.25)
			(net 307 "Net-(R706-R3.1)")
			(pinfunction "R3.1")
			(pintype "passive")
		)
		(pad "4" smd roundrect
			(at 0.8875 -0.45 90)
			(size 0.525 0.5)
			(layers "B.Cu" "B.Mask" "B.Paste")
			(roundrect_rratio 0.25)
			(net 308 "Net-(R706-R4.1)")
			(pinfunction "R4.1")
			(pintype "passive")
		)
		(pad "5" smd roundrect
			(at 0.8875 0.45 90)
			(size 0.525 0.5)
			(layers "B.Cu" "B.Mask" "B.Paste")
			(roundrect_rratio 0.25)
			(net 125 "/Compute module/DSICtrl.GPIO")
			(pinfunction "R4.2")
			(pintype "passive")
		)
		(pad "6" smd roundrect
			(at 0.25 0.45 90)
			(size 0.25 0.5)
			(layers "B.Cu" "B.Mask" "B.Paste")
			(roundrect_rratio 0.25)
			(net 124 "/Compute module/DSICtrl.DIM")
			(pinfunction "R3.2")
			(pintype "passive")
		)
		(pad "7" smd roundrect
			(at -0.25 0.45 90)
			(size 0.25 0.5)
			(layers "B.Cu" "B.Mask" "B.Paste")
			(roundrect_rratio 0.25)
			(net 123 "/Compute module/DSICtrl.~{RST}")
			(pinfunction "R2.2")
			(pintype "passive")
		)
		(pad "8" smd roundrect
			(at -0.8875 0.45 90)
			(size 0.525 0.5)
			(layers "B.Cu" "B.Mask" "B.Paste")
			(roundrect_rratio 0.25)
			(net 122 "/Compute module/DSICtrl.EN")
			(pinfunction "R1.2")
			(pintype "passive")
		)
	)
	(footprint "antmicro-footprints:Nexperia_DFN-10_2.5x1mm_P0.5mm"
		(layer "B.Cu")
		(at 89.505962 169.1785 90)
		(property "Reference" "D703"
			(at -1.198 -1.908 90)
			(layer "B.SilkS")
			(effects
				(font
					(size 0.7 0.7)
					(thickness 0.15)
				)
				(justify right bottom mirror)
			)
		)
		(property "Value" "PUSB3F96X_PASS"
			(at -0.016 -1.705 90)
			(layer "B.Fab")
			(effects
				(font
					(size 0.7 0.7)
					(thickness 0.15)
				)
				(justify right bottom mirror)
			)
		)
		(property "Datasheet" "https://mouser.com/datasheet/2/916/PUSB3F96-1600324.pdf"
			(at 0 0 90)
			(layer "B.Fab")
			(hide yes)
			(effects
				(font
					(size 1.27 1.27)
					(thickness 0.15)
				)
			)
		)
		(property "Manufacturer" "Nexperia"
			(at 0 0 90)
			(unlocked yes)
			(layer "B.Fab")
			(hide yes)
			(effects
				(font
					(size 1 1)
					(thickness 0.15)
				)
				(justify mirror)
			)
		)
		(property "MPN" "PUSB3F96X"
			(at 0 0 90)
			(unlocked yes)
			(layer "B.Fab")
			(hide yes)
			(effects
				(font
					(size 1 1)
					(thickness 0.15)
				)
				(justify mirror)
			)
		)
		(property "Author" "Antmicro"
			(at 0 0 90)
			(unlocked yes)
			(layer "B.Fab")
			(hide yes)
			(effects
				(font
					(size 1 1)
					(thickness 0.15)
				)
				(justify mirror)
			)
		)
		(property "License" "Apache-2.0"
			(at 0 0 90)
			(unlocked yes)
			(layer "B.Fab")
			(hide yes)
			(effects
				(font
					(size 1 1)
					(thickness 0.15)
				)
				(justify mirror)
			)
		)
		(sheetname "/Display/")
		(sheetfile "display.kicad_sch")
		(attr smd)
		(fp_line
			(start 1.375 -0.4)
			(end 1.375 0.4)
			(stroke
				(width 0.15)
				(type solid)
			)
			(layer "B.SilkS")
		)
		(fp_line
			(start -1.375 0.4)
			(end -1.375 -0.4)
			(stroke
				(width 0.15)
				(type solid)
			)
			(layer "B.SilkS")
		)
		(fp_circle
			(center -1.4 -0.7)
			(end -1.349 -0.7)
			(stroke
				(width 0.15)
				(type solid)
			)
			(fill yes)
			(layer "B.SilkS")
		)
		(fp_rect
			(start -1.4 0.725)
			(end 1.4 -0.725)
			(stroke
				(width 0.05)
				(type solid)
			)
			(fill no)
			(layer "B.CrtYd")
		)
		(fp_line
			(start 1.25 -0.5)
			(end 1.25 0.5)
			(stroke
				(width 0.15)
				(type solid)
			)
			(layer "B.Fab")
		)
		(fp_line
			(start -0.9 -0.5)
			(end 1.25 -0.5)
			(stroke
				(width 0.15)
				(type solid)
			)
			(layer "B.Fab")
		)
		(fp_line
			(start -1.25 -0.15)
			(end -0.9 -0.5)
			(stroke
				(width 0.15)
				(type solid)
			)
			(layer "B.Fab")
		)
		(fp_line
			(start 1.25 0.5)
			(end -1.25 0.5)
			(stroke
				(width 0.15)
				(type solid)
			)
			(layer "B.Fab")
		)
		(fp_line
			(start -1.25 0.5)
			(end -1.25 -0.15)
			(stroke
				(width 0.15)
				(type solid)
			)
			(layer "B.Fab")
		)
		(fp_text user "${REFERENCE}"
			(at -1.367 -3.704 270)
			(layer "B.Fab")
			(effects
				(font
					(size 0.7 0.7)
					(thickness 0.15)
				)
				(justify left bottom mirror)
			)
		)
		(fp_text user "License: Apache-2.0"
			(at -1.367 -6.105 270)
			(layer "B.Fab")
			(effects
				(font
					(size 0.7 0.7)
					(thickness 0.15)
				)
				(justify left bottom mirror)
			)
		)
		(fp_text user "Author: Antmicro"
			(at -1.367 -4.905 270)
			(layer "B.Fab")
			(effects
				(font
					(size 0.7 0.7)
					(thickness 0.15)
				)
				(justify left bottom mirror)
			)
		)
		(pad "1" smd rect
			(at -1 -0.3875 90)
			(size 0.2 0.475)
			(layers "B.Cu" "B.Mask" "B.Paste")
			(net 76 "/Compute module/DSI.CLK_N")
			(pinfunction "CH1")
			(pintype "passive")
			(solder_mask_margin 0.05)
		)
		(pad "2" smd rect
			(at -0.5 -0.3875 90)
			(size 0.2 0.475)
			(layers "B.Cu" "B.Mask" "B.Paste")
			(net 86 "/Compute module/DSI.CLK_P")
			(pinfunction "CH2")
			(pintype "passive")
			(solder_mask_margin 0.05)
		)
		(pad "3" smd rect
			(at 0 -0.3875 90)
			(size 0.2 0.475)
			(layers "B.Cu" "B.Mask" "B.Paste")
			(net 3 "GND")
			(pinfunction "GND")
			(pintype "passive")
			(solder_mask_margin 0.05)
		)
		(pad "4" smd rect
			(at 0.5 -0.3875 90)
			(size 0.2 0.475)
			(layers "B.Cu" "B.Mask" "B.Paste")
			(net 3 "GND")
			(pinfunction "CH3")
			(pintype "passive")
			(solder_mask_margin 0.05)
		)
		(pad "5" smd rect
			(at 1 -0.3875 90)
			(size 0.2 0.475)
			(layers "B.Cu" "B.Mask" "B.Paste")
			(net 3 "GND")
			(pinfunction "CH4")
			(pintype "passive")
			(solder_mask_margin 0.05)
		)
		(pad "6" smd rect
			(at 1 0.3875 90)
			(size 0.2 0.475)
			(layers "B.Cu" "B.Mask" "B.Paste")
			(net 3 "GND")
			(pinfunction "CH4")
			(pintype "passive")
			(solder_mask_margin 0.05)
		)
		(pad "7" smd rect
			(at 0.5 0.3875 90)
			(size 0.2 0.475)
			(layers "B.Cu" "B.Mask" "B.Paste")
			(net 3 "GND")
			(pinfunction "CH3")
			(pintype "passive")
			(solder_mask_margin 0.05)
		)
		(pad "8" smd rect
			(at 0 0.3875 90)
			(size 0.2 0.475)
			(layers "B.Cu" "B.Mask" "B.Paste")
			(net 3 "GND")
			(pinfunction "GND")
			(pintype "passive")
			(solder_mask_margin 0.05)
		)
		(pad "9" smd rect
			(at -0.501 0.3875 90)
			(size 0.2 0.475)
			(layers "B.Cu" "B.Mask" "B.Paste")
			(net 86 "/Compute module/DSI.CLK_P")
			(pinfunction "CH2")
			(pintype "passive")
			(solder_mask_margin 0.05)
		)
		(pad "10" smd rect
			(at -1 0.3875 90)
			(size 0.2 0.475)
			(layers "B.Cu" "B.Mask" "B.Paste")
			(net 76 "/Compute module/DSI.CLK_N")
			(pinfunction "CH1")
			(pintype "passive")
			(solder_mask_margin 0.05)
		)
	)
	(footprint "antmicro-footprints:R_0402_1005Metric"
		(layer "B.Cu")
		(at 84.667962 123.7165 180)
		(descr "Resistor SMD 0402")
		(tags "resistor SMD 0402")
		(property "Reference" "R912"
			(at 1 -0.32 0)
			(layer "B.SilkS")
			(effects
				(font
					(size 0.7 0.7)
					(thickness 0.15)
				)
				(justify left bottom mirror)
			)
		)
		(property "Value" "R_6k8_0402"
			(at -1.011843 -1.772047 0)
			(layer "B.Fab")
			(effects
				(font
					(size 0.7 0.7)
					(thickness 0.15)
				)
				(justify left bottom mirror)
			)
		)
		(property "Datasheet" "https://www.bourns.com/docs/product-datasheets/cr.pdf"
			(at 0 0 180)
			(layer "B.Fab")
			(hide yes)
			(effects
				(font
					(size 1.27 1.27)
					(thickness 0.15)
				)
			)
		)
		(property "MPN" "CR0402-FX-6801GLF"
			(at 0 0 180)
			(unlocked yes)
			(layer "B.Fab")
			(hide yes)
			(effects
				(font
					(size 1 1)
					(thickness 0.15)
				)
				(justify mirror)
			)
		)
		(property "Manufacturer" "Bourns"
			(at 0 0 180)
			(unlocked yes)
			(layer "B.Fab")
			(hide yes)
			(effects
				(font
					(size 1 1)
					(thickness 0.15)
				)
				(justify mirror)
			)
		)
		(property "License" "Apache-2.0"
			(at 0 0 180)
			(unlocked yes)
			(layer "B.Fab")
			(hide yes)
			(effects
				(font
					(size 1 1)
					(thickness 0.15)
				)
				(justify mirror)
			)
		)
		(property "Author" "Antmicro"
			(at 0 0 180)
			(unlocked yes)
			(layer "B.Fab")
			(hide yes)
			(effects
				(font
					(size 1 1)
					(thickness 0.15)
				)
				(justify mirror)
			)
		)
		(property "Val" "6k8"
			(at 0 0 180)
			(unlocked yes)
			(layer "B.Fab")
			(hide yes)
			(effects
				(font
					(size 1 1)
					(thickness 0.15)
				)
				(justify mirror)
			)
		)
		(property "Tolerance" "1%"
			(at 0 0 180)
			(unlocked yes)
			(layer "B.Fab")
			(hide yes)
			(effects
				(font
					(size 1 1)
					(thickness 0.15)
				)
				(justify mirror)
			)
		)
		(sheetname "/USB/")
		(sheetfile "usb.kicad_sch")
		(attr smd)
		(fp_rect
			(start -0.925 0.47)
			(end 0.925 -0.47)
			(stroke
				(width 0.05)
				(type default)
			)
			(fill no)
			(layer "B.CrtYd")
		)
		(fp_rect
			(start -0.5 0.25)
			(end 0.5 -0.25)
			(stroke
				(width 0.15)
				(type solid)
			)
			(fill no)
			(layer "B.Fab")
		)
		(fp_text user "Author: Antmicro"
			(at -0.95 -4.169 0)
			(layer "B.Fab")
			(effects
				(font
					(size 0.7 0.7)
					(thickness 0.15)
				)
				(justify left bottom mirror)
			)
		)
		(fp_text user "License: Apache-2.0"
			(at -0.95 -5.169 0)
			(layer "B.Fab")
			(effects
				(font
					(size 0.7 0.7)
					(thickness 0.15)
				)
				(justify left bottom mirror)
			)
		)
		(fp_text user "${REFERENCE}"
			(at -0.95 -3.168 0)
			(layer "B.Fab")
			(effects
				(font
					(size 0.7 0.7)
					(thickness 0.15)
				)
				(justify left bottom mirror)
			)
		)
		(pad "1" smd roundrect
			(at -0.48 0 180)
			(size 0.59 0.64)
			(layers "B.Cu" "B.Mask" "B.Paste")
			(roundrect_rratio 0.25)
			(net 344 "/USB/FB_FTDI")
			(pintype "passive")
		)
		(pad "2" smd roundrect
			(at 0.48 0 180)
			(size 0.59 0.64)
			(layers "B.Cu" "B.Mask" "B.Paste")
			(roundrect_rratio 0.25)
			(net 113 "/USB/OUT_FTDI")
			(pintype "passive")
		)
	)
	(footprint "antmicro-footprints:Spacer_Drill3.7mm_H2.5mm_9774025151R"
		(locked yes)
		(layer "B.Cu")
		(at 44.992962 124.767)
		(descr "Spacer M=3 h=2.5mm fi=5.1mm")
		(property "Reference" "H501"
			(at 1.405 -3.3305 180)
			(layer "B.SilkS")
			(effects
				(font
					(size 0.7 0.7)
					(thickness 0.15)
				)
				(justify left bottom mirror)
			)
		)
		(property "Value" "Spacer_Drill3.7mm_H2.5mm_9774025151R"
			(at 0 -4 180)
			(layer "B.Fab")
			(effects
				(font
					(size 0.7 0.7)
					(thickness 0.15)
				)
				(justify left bottom mirror)
			)
		)
		(property "Datasheet" "https://www.we-online.com/components/products/datasheet/9774025151R.pdf"
			(at 0 0 0)
			(layer "B.Fab")
			(hide yes)
			(effects
				(font
					(size 1.27 1.27)
					(thickness 0.15)
				)
			)
		)
		(property "Manufacturer" "Würth Elektronik"
			(at 0 0 0)
			(unlocked yes)
			(layer "B.Fab")
			(hide yes)
			(effects
				(font
					(size 1 1)
					(thickness 0.15)
				)
				(justify mirror)
			)
		)
		(property "MPN" "9774025151R"
			(at 0 0 0)
			(unlocked yes)
			(layer "B.Fab")
			(hide yes)
			(effects
				(font
					(size 1 1)
					(thickness 0.15)
				)
				(justify mirror)
			)
		)
		(property "Author" "Antmicro"
			(at 0 0 0)
			(unlocked yes)
			(layer "B.Fab")
			(hide yes)
			(effects
				(font
					(size 1 1)
					(thickness 0.15)
				)
				(justify mirror)
			)
		)
		(property "License" "Apache-2.0"
			(at 0 0 0)
			(unlocked yes)
			(layer "B.Fab")
			(hide yes)
			(effects
				(font
					(size 1 1)
					(thickness 0.15)
				)
				(justify mirror)
			)
		)
		(sheetname "/NVMe & microSD/")
		(sheetfile "nvme-micro-sd.kicad_sch")
		(solder_paste_margin_ratio -1)
		(attr smd)
		(fp_circle
			(center 0 0)
			(end 3.05 0)
			(stroke
				(width 0.05)
				(type solid)
			)
			(fill no)
			(layer "B.CrtYd")
		)
		(fp_circle
			(center 0 0)
			(end 2.6 0)
			(stroke
				(width 0.15)
				(type solid)
			)
			(fill no)
			(layer "B.Fab")
		)
		(fp_text user "Author: Antmicro"
			(at -9.6 -7.7 180)
			(layer "B.Fab")
			(effects
				(font
					(size 0.7 0.7)
					(thickness 0.15)
				)
				(justify left bottom mirror)
			)
		)
		(fp_text user "License: Apache-2.0"
			(at -9.6 -8.9 180)
			(layer "B.Fab")
			(effects
				(font
					(size 0.7 0.7)
					(thickness 0.15)
				)
				(justify left bottom mirror)
			)
		)
		(fp_text user "${REFERENCE}"
			(at -9.6 -6.5 180)
			(layer "B.Fab")
			(effects
				(font
					(size 0.7 0.7)
					(thickness 0.15)
				)
				(justify left bottom mirror)
			)
		)
		(pad "" smd custom
			(at -1.7 -1.7 270)
			(size 0.62 0.62)
			(layers "B.Paste")
			(thermal_bridge_angle 90)
			(options
				(clearance outline)
				(anchor circle)
			)
			(primitives
				(gr_arc
					(start 1.266786 0.24747)
					(mid 0.285453 -0.29439)
					(end -0.250195 -1.279127)
					(width 0.2)
				)
				(gr_arc
					(start 1.259603 0.339191)
					(mid 0.218448 -0.232561)
					(end -0.34334 -1.279127)
					(width 0.2)
				)
				(gr_arc
					(start 1.255279 0.431435)
					(mid 0.152481 -0.169693)
					(end -0.436309 -1.279127)
					(width 0.2)
				)
				(gr_arc
					(start 1.253811 0.524161)
					(mid 0.087542 -0.105784)
					(end -0.529126 -1.279127)
					(width 0.2)
				)
				(gr_arc
					(start 1.275473 0.621136)
					(mid 0.0309 -0.033527)
					(end -0.621807 -1.279127)
					(width 0.2)
				)
				(gr_arc
					(start 1.263664 0.711602)
					(mid -0.037759 0.026651)
					(end -0.71437 -1.279127)
					(width 0.2)
				)
				(gr_arc
					(start 1.253435 0.802342)
					(mid -0.105837 0.087395)
					(end -0.806826 -1.279127)
					(width 0.2)
				)
				(gr_arc
					(start 1.267475 0.897258)
					(mid -0.165236 0.156885)
					(end -0.899187 -1.279127)
					(width 0.2)
				)
				(gr_arc
					(start 1.270645 0.990112)
					(mid -0.228522 0.222449)
					(end -0.991463 -1.279127)
					(width 0.2)
				)
				(gr_arc
					(start 1.266278 1.081674)
					(mid -0.294507 0.285313)
					(end -1.083663 -1.279127)
					(width 0.2)
				)
				(gr_line
					(start 1.279127 0.250195)
					(end 1.279127 1.083663)
					(width 0.2)
				)
				(gr_line
					(start -0.250195 -1.279127)
					(end -1.083663 -1.279127)
					(width 0.2)
				)
			)
		)
		(pad "" smd custom
			(at -1.7 1.7)
			(size 0.62 0.62)
			(layers "B.Paste")
			(thermal_bridge_angle 90)
			(options
				(clearance outline)
				(anchor circle)
			)
			(primitives
				(gr_arc
					(start 1.266786 0.24747)
					(mid 0.285453 -0.29439)
					(end -0.250195 -1.279127)
					(width 0.2)
				)
				(gr_arc
					(start 1.259603 0.339191)
					(mid 0.218448 -0.232561)
					(end -0.34334 -1.279127)
					(width 0.2)
				)
				(gr_arc
					(start 1.255279 0.431435)
					(mid 0.152481 -0.169693)
					(end -0.436309 -1.279127)
					(width 0.2)
				)
				(gr_arc
					(start 1.253811 0.524161)
					(mid 0.087542 -0.105784)
					(end -0.529126 -1.279127)
					(width 0.2)
				)
				(gr_arc
					(start 1.275473 0.621136)
					(mid 0.0309 -0.033527)
					(end -0.621807 -1.279127)
					(width 0.2)
				)
				(gr_arc
					(start 1.263664 0.711602)
					(mid -0.037759 0.026651)
					(end -0.71437 -1.279127)
					(width 0.2)
				)
				(gr_arc
					(start 1.253435 0.802342)
					(mid -0.105837 0.087395)
					(end -0.806826 -1.279127)
					(width 0.2)
				)
				(gr_arc
					(start 1.267475 0.897258)
					(mid -0.165236 0.156885)
					(end -0.899187 -1.279127)
					(width 0.2)
				)
				(gr_arc
					(start 1.270645 0.990112)
					(mid -0.228522 0.222449)
					(end -0.991463 -1.279127)
					(width 0.2)
				)
				(gr_arc
					(start 1.266278 1.081674)
					(mid -0.294507 0.285313)
					(end -1.083663 -1.279127)
					(width 0.2)
				)
				(gr_line
					(start 1.279127 0.250195)
					(end 1.279127 1.083663)
					(width 0.2)
				)
				(gr_line
					(start -0.250195 -1.279127)
					(end -1.083663 -1.279127)
					(width 0.2)
				)
			)
		)
		(pad "" smd custom
			(at 1.7 -1.7 180)
			(size 0.62 0.62)
			(layers "B.Paste")
			(thermal_bridge_angle 90)
			(options
				(clearance outline)
				(anchor circle)
			)
			(primitives
				(gr_arc
					(start 1.266786 0.24747)
					(mid 0.285453 -0.29439)
					(end -0.250195 -1.279127)
					(width 0.2)
				)
				(gr_arc
					(start 1.259603 0.339191)
					(mid 0.218448 -0.232561)
					(end -0.34334 -1.279127)
					(width 0.2)
				)
				(gr_arc
					(start 1.255279 0.431435)
					(mid 0.152481 -0.169693)
					(end -0.436309 -1.279127)
					(width 0.2)
				)
				(gr_arc
					(start 1.253811 0.524161)
					(mid 0.087542 -0.105784)
					(end -0.529126 -1.279127)
					(width 0.2)
				)
				(gr_arc
					(start 1.275473 0.621136)
					(mid 0.0309 -0.033527)
					(end -0.621807 -1.279127)
					(width 0.2)
				)
				(gr_arc
					(start 1.263664 0.711602)
					(mid -0.037759 0.026651)
					(end -0.71437 -1.279127)
					(width 0.2)
				)
				(gr_arc
					(start 1.253435 0.802342)
					(mid -0.105837 0.087395)
					(end -0.806826 -1.279127)
					(width 0.2)
				)
				(gr_arc
					(start 1.267475 0.897258)
					(mid -0.165236 0.156885)
					(end -0.899187 -1.279127)
					(width 0.2)
				)
				(gr_arc
					(start 1.270645 0.990112)
					(mid -0.228522 0.222449)
					(end -0.991463 -1.279127)
					(width 0.2)
				)
				(gr_arc
					(start 1.266278 1.081674)
					(mid -0.294507 0.285313)
					(end -1.083663 -1.279127)
					(width 0.2)
				)
				(gr_line
					(start 1.279127 0.250195)
					(end 1.279127 1.083663)
					(width 0.2)
				)
				(gr_line
					(start -0.250195 -1.279127)
					(end -1.083663 -1.279127)
					(width 0.2)
				)
			)
		)
		(pad "" smd custom
			(at 1.7 1.7 90)
			(size 0.62 0.62)
			(layers "B.Paste")
			(thermal_bridge_angle 90)
			(options
				(clearance outline)
				(anchor circle)
			)
			(primitives
				(gr_arc
					(start 1.266786 0.24747)
					(mid 0.285453 -0.29439)
					(end -0.250195 -1.279127)
					(width 0.2)
				)
				(gr_arc
					(start 1.259603 0.339191)
					(mid 0.218448 -0.232561)
					(end -0.34334 -1.279127)
					(width 0.2)
				)
				(gr_arc
					(start 1.255279 0.431435)
					(mid 0.152481 -0.169693)
					(end -0.436309 -1.279127)
					(width 0.2)
				)
				(gr_arc
					(start 1.253811 0.524161)
					(mid 0.087542 -0.105784)
					(end -0.529126 -1.279127)
					(width 0.2)
				)
				(gr_arc
					(start 1.275473 0.621136)
					(mid 0.0309 -0.033527)
					(end -0.621807 -1.279127)
					(width 0.2)
				)
				(gr_arc
					(start 1.263664 0.711602)
					(mid -0.037759 0.026651)
					(end -0.71437 -1.279127)
					(width 0.2)
				)
				(gr_arc
					(start 1.253435 0.802342)
					(mid -0.105837 0.087395)
					(end -0.806826 -1.279127)
					(width 0.2)
				)
				(gr_arc
					(start 1.267475 0.897258)
					(mid -0.165236 0.156885)
					(end -0.899187 -1.279127)
					(width 0.2)
				)
				(gr_arc
					(start 1.270645 0.990112)
					(mid -0.228522 0.222449)
					(end -0.991463 -1.279127)
					(width 0.2)
				)
				(gr_arc
					(start 1.266278 1.081674)
					(mid -0.294507 0.285313)
					(end -1.083663 -1.279127)
					(width 0.2)
				)
				(gr_line
					(start 1.279127 0.250195)
					(end 1.279127 1.083663)
					(width 0.2)
				)
				(gr_line
					(start -0.250195 -1.279127)
					(end -1.083663 -1.279127)
					(width 0.2)
				)
			)
		)
		(pad "1" thru_hole circle
			(at 0 0)
			(size 6 6)
			(drill 3.7)
			(layers "*.Cu" "*.Mask")
			(remove_unused_layers no)
			(net 3 "GND")
			(pintype "passive")
		)
	)
	(footprint "antmicro-footprints:C_0402_1005Metric"
		(layer "B.Cu")
		(at 88.742962 123.1415 180)
		(descr "Capacitor SMD 0402")
		(tags "capacitor SMD 0402")
		(property "Reference" "C906"
			(at 2.835 0.375 0)
			(layer "B.SilkS")
			(effects
				(font
					(size 0.7 0.7)
					(thickness 0.15)
				)
				(justify left bottom mirror)
			)
		)
		(property "Value" "C_100n_0402"
			(at -1.022927 -2.155213 0)
			(layer "B.Fab")
			(effects
				(font
					(size 0.7 0.7)
					(thickness 0.15)
				)
				(justify left bottom mirror)
			)
		)
		(property "Datasheet" "https://www.murata.com/products/productdetail?partno=GRM155R61H104KE14%23"
			(at 0 0 180)
			(layer "B.Fab")
			(hide yes)
			(effects
				(font
					(size 1.27 1.27)
					(thickness 0.15)
				)
			)
		)
		(property "Manufacturer" "Murata"
			(at 0 0 180)
			(unlocked yes)
			(layer "B.Fab")
			(hide yes)
			(effects
				(font
					(size 1 1)
					(thickness 0.15)
				)
				(justify mirror)
			)
		)
		(property "MPN" "GRM155R61H104KE14D"
			(at 0 0 180)
			(unlocked yes)
			(layer "B.Fab")
			(hide yes)
			(effects
				(font
					(size 1 1)
					(thickness 0.15)
				)
				(justify mirror)
			)
		)
		(property "Val" "100n"
			(at 0 0 180)
			(unlocked yes)
			(layer "B.Fab")
			(hide yes)
			(effects
				(font
					(size 1 1)
					(thickness 0.15)
				)
				(justify mirror)
			)
		)
		(property "License" "Apache-2.0"
			(at 0 0 180)
			(unlocked yes)
			(layer "B.Fab")
			(hide yes)
			(effects
				(font
					(size 1 1)
					(thickness 0.15)
				)
				(justify mirror)
			)
		)
		(property "Author" "Antmicro"
			(at 0 0 180)
			(unlocked yes)
			(layer "B.Fab")
			(hide yes)
			(effects
				(font
					(size 1 1)
					(thickness 0.15)
				)
				(justify mirror)
			)
		)
		(property "Voltage" "50V"
			(at 0 0 180)
			(unlocked yes)
			(layer "B.Fab")
			(hide yes)
			(effects
				(font
					(size 1 1)
					(thickness 0.15)
				)
				(justify mirror)
			)
		)
		(property "Dielectric" "X5R"
			(at 0 0 180)
			(unlocked yes)
			(layer "B.Fab")
			(hide yes)
			(effects
				(font
					(size 1 1)
					(thickness 0.15)
				)
				(justify mirror)
			)
		)
		(sheetname "/USB/")
		(sheetfile "usb.kicad_sch")
		(attr smd)
		(fp_rect
			(start -0.925 0.47)
			(end 0.925 -0.47)
			(stroke
				(width 0.05)
				(type default)
			)
			(fill no)
			(layer "B.CrtYd")
		)
		(fp_line
			(start 0.504 0.25)
			(end 0.504 -0.248)
			(stroke
				(width 0.15)
				(type solid)
			)
			(layer "B.Fab")
		)
		(fp_line
			(start 0.504 -0.248)
			(end -0.494 -0.248)
			(stroke
				(width 0.15)
				(type solid)
			)
			(layer "B.Fab")
		)
		(fp_line
			(start -0.494 0.25)
			(end 0.504 0.25)
			(stroke
				(width 0.15)
				(type solid)
			)
			(layer "B.Fab")
		)
		(fp_line
			(start -0.494 -0.248)
			(end -0.494 0.25)
			(stroke
				(width 0.15)
				(type solid)
			)
			(layer "B.Fab")
		)
		(fp_text user "License: Apache-2.0"
			(at -0.939 -5.799 0)
			(layer "B.Fab")
			(effects
				(font
					(size 0.7 0.7)
					(thickness 0.15)
				)
				(justify left bottom mirror)
			)
		)
		(fp_text user "${REFERENCE}"
			(at -0.939 -4.599 0)
			(layer "B.Fab")
			(effects
				(font
					(size 0.7 0.7)
					(thickness 0.15)
				)
				(justify left bottom mirror)
			)
		)
		(fp_text user "Author: Antmicro"
			(at -0.939 -3.399 0)
			(layer "B.Fab")
			(effects
				(font
					(size 0.7 0.7)
					(thickness 0.15)
				)
				(justify left bottom mirror)
			)
		)
		(pad "1" smd roundrect
			(at -0.48 0 180)
			(size 0.59 0.64)
			(layers "B.Cu" "B.Mask" "B.Paste")
			(roundrect_rratio 0.25)
			(net 111 "/USB/SW_FTDI")
			(pintype "passive")
		)
		(pad "2" smd roundrect
			(at 0.48 0 180)
			(size 0.59 0.64)
			(layers "B.Cu" "B.Mask" "B.Paste")
			(roundrect_rratio 0.25)
			(net 112 "Net-(U903-BST)")
			(pintype "passive")
		)
	)
	(footprint "antmicro-footprints:TP_SMD_0.75mm"
		(layer "B.Cu")
		(at 76.792962 135.0415)
		(property "Reference" "TP902"
			(at -0.875 -0.585 0)
			(layer "B.SilkS")
			(effects
				(font
					(size 0.7 0.7)
					(thickness 0.15)
				)
				(justify right bottom mirror)
			)
		)
		(property "Value" "TP_0.75mm_SMD"
			(at 0 -1.2 0)
			(layer "B.Fab")
			(effects
				(font
					(size 0.7 0.7)
					(thickness 0.15)
				)
				(justify right bottom mirror)
			)
		)
		(property "MPN" ""
			(at 0 0 0)
			(unlocked yes)
			(layer "B.Fab")
			(hide yes)
			(effects
				(font
					(size 1 1)
					(thickness 0.15)
				)
				(justify mirror)
			)
		)
		(property "Manufacturer" ""
			(at 0 0 0)
			(unlocked yes)
			(layer "B.Fab")
			(hide yes)
			(effects
				(font
					(size 1 1)
					(thickness 0.15)
				)
				(justify mirror)
			)
		)
		(property "Author" "Antmicro"
			(at 0 0 0)
			(unlocked yes)
			(layer "B.Fab")
			(hide yes)
			(effects
				(font
					(size 1 1)
					(thickness 0.15)
				)
				(justify mirror)
			)
		)
		(property "License" "Apache-2.0"
			(at 0 0 0)
			(unlocked yes)
			(layer "B.Fab")
			(hide yes)
			(effects
				(font
					(size 1 1)
					(thickness 0.15)
				)
				(justify mirror)
			)
		)
		(sheetname "/USB/")
		(sheetfile "usb.kicad_sch")
		(attr exclude_from_pos_files exclude_from_bom)
		(fp_circle
			(center 0 0)
			(end 0.475 0)
			(stroke
				(width 0.05)
				(type default)
			)
			(fill no)
			(layer "B.CrtYd")
		)
		(fp_text user "${REFERENCE}"
			(at -0.4 -2.7 180)
			(layer "B.Fab")
			(effects
				(font
					(size 0.7 0.7)
					(thickness 0.15)
				)
				(justify left bottom mirror)
			)
		)
		(fp_text user "Author: Antmicro"
			(at -0.4 -3.901 180)
			(layer "B.Fab")
			(effects
				(font
					(size 0.7 0.7)
					(thickness 0.15)
				)
				(justify left bottom mirror)
			)
		)
		(fp_text user "License: Apache-2.0"
			(at -0.4 -5.101 180)
			(layer "B.Fab")
			(effects
				(font
					(size 0.7 0.7)
					(thickness 0.15)
				)
				(justify left bottom mirror)
			)
		)
		(pad "1" smd circle
			(at 0 0)
			(size 0.75 0.75)
			(layers "B.Cu" "B.Mask")
			(net 29 "/USB/USBD_SVBUS")
			(pinfunction "1")
			(pintype "passive")
		)
	)
	(footprint "antmicro-footprints:SOT-363"
		(layer "B.Cu")
		(at 60.142962 163.6665)
		(property "Reference" "Q302"
			(at 2.185 1.95 90)
			(layer "B.SilkS")
			(effects
				(font
					(size 0.7 0.7)
					(thickness 0.15)
				)
				(justify right bottom mirror)
			)
		)
		(property "Value" "DZDH0401DW"
			(at 0 -2.2 0)
			(layer "B.Fab")
			(effects
				(font
					(size 0.7 0.7)
					(thickness 0.15)
				)
				(justify right bottom mirror)
			)
		)
		(property "Datasheet" "https://www.mouser.com/datasheet/2/115/DIOD_S_A0011803041_1-2543705.pdf"
			(at 0 0 0)
			(layer "B.Fab")
			(hide yes)
			(effects
				(font
					(size 1.27 1.27)
					(thickness 0.15)
				)
			)
		)
		(property "MPN" "DZDH0401DW"
			(at 0 0 0)
			(unlocked yes)
			(layer "B.Fab")
			(hide yes)
			(effects
				(font
					(size 1 1)
					(thickness 0.15)
				)
				(justify mirror)
			)
		)
		(property "Manufacturer" "Diodes Incorporated"
			(at 0 0 0)
			(unlocked yes)
			(layer "B.Fab")
			(hide yes)
			(effects
				(font
					(size 1 1)
					(thickness 0.15)
				)
				(justify mirror)
			)
		)
		(property "Author" "Antmicro"
			(at 0 0 0)
			(unlocked yes)
			(layer "B.Fab")
			(hide yes)
			(effects
				(font
					(size 1 1)
					(thickness 0.15)
				)
				(justify mirror)
			)
		)
		(property "License" "Apache-2.0"
			(at 0 0 0)
			(unlocked yes)
			(layer "B.Fab")
			(hide yes)
			(effects
				(font
					(size 1 1)
					(thickness 0.15)
				)
				(justify mirror)
			)
		)
		(sheetname "/Supply/")
		(sheetfile "supply.kicad_sch")
		(attr smd)
		(fp_line
			(start -0.8 -1.223)
			(end 0.803 -1.223)
			(stroke
				(width 0.15)
				(type solid)
			)
			(layer "B.SilkS")
		)
		(fp_line
			(start -0.8 -1.146)
			(end -0.8 -1.223)
			(stroke
				(width 0.15)
				(type solid)
			)
			(layer "B.SilkS")
		)
		(fp_line
			(start -0.72 1.153)
			(end -0.72 1.228)
			(stroke
				(width 0.15)
				(type solid)
			)
			(layer "B.SilkS")
		)
		(fp_line
			(start 0.803 -1.146)
			(end 0.803 -1.223)
			(stroke
				(width 0.15)
				(type solid)
			)
			(layer "B.SilkS")
		)
		(fp_line
			(start 0.803 1.153)
			(end 0.803 1.228)
			(stroke
				(width 0.15)
				(type solid)
			)
			(layer "B.SilkS")
		)
		(fp_line
			(start 0.803 1.228)
			(end -0.72 1.228)
			(stroke
				(width 0.15)
				(type solid)
			)
			(layer "B.SilkS")
		)
		(fp_circle
			(center -0.978102 1.2)
			(end -0.928102 1.2)
			(stroke
				(width 0.15)
				(type solid)
			)
			(fill yes)
			(layer "B.SilkS")
		)
		(fp_rect
			(start 1.3 1.3)
			(end -1.3 -1.3)
			(stroke
				(width 0.05)
				(type solid)
			)
			(fill no)
			(layer "B.CrtYd")
		)
		(fp_line
			(start -0.1 1.1)
			(end -0.68 0.52)
			(stroke
				(width 0.15)
				(type solid)
			)
			(layer "B.Fab")
		)
		(fp_rect
			(start 0.68 -1.1)
			(end -0.68 1.1)
			(stroke
				(width 0.15)
				(type solid)
			)
			(fill no)
			(layer "B.Fab")
		)
		(fp_text user "Author: Antmicro"
			(at -1.3 -6.4 180)
			(layer "B.Fab")
			(effects
				(font
					(size 0.7 0.7)
					(thickness 0.15)
				)
				(justify left bottom mirror)
			)
		)
		(fp_text user "${REFERENCE}"
			(at -1.3 -4 180)
			(layer "B.Fab")
			(effects
				(font
					(size 0.7 0.7)
					(thickness 0.15)
				)
				(justify left bottom mirror)
			)
		)
		(fp_text user "License: Apache-2.0"
			(at -1.3 -5.2 180)
			(layer "B.Fab")
			(effects
				(font
					(size 0.7 0.7)
					(thickness 0.15)
				)
				(justify left bottom mirror)
			)
		)
		(pad "1" smd custom
			(at -0.948 0.752 90)
			(size 0.6 0.6)
			(layers "B.Cu" "B.Mask" "B.Paste")
			(net 494 "unconnected-(Q302-NC-Pad1)")
			(pinfunction "NC")
			(pintype "no_connect")
			(options
				(clearance outline)
				(anchor rect)
			)
			(primitives)
		)
		(pad "2" smd rect
			(at -0.948 0.002 90)
			(size 0.4 0.6)
			(layers "B.Cu" "B.Mask" "B.Paste")
			(net 334 "Net-(Q302-REF)")
			(pinfunction "REF")
			(pintype "input")
		)
		(pad "3" smd custom
			(at -0.948 -0.745 90)
			(size 0.6 0.6)
			(layers "B.Cu" "B.Mask" "B.Paste")
			(net 335 "Net-(Q302-BIAS)")
			(pinfunction "BIAS")
			(pintype "output")
			(options
				(clearance outline)
				(anchor rect)
			)
			(primitives)
		)
		(pad "4" smd custom
			(at 0.951 -0.745 90)
			(size 0.6 0.6)
			(layers "B.Cu" "B.Mask" "B.Paste")
			(net 21 "/Supply/VCC_IN")
			(pinfunction "S")
			(pintype "power_in")
			(options
				(clearance outline)
				(anchor rect)
			)
			(primitives)
		)
		(pad "5" smd rect
			(at 0.951 0.002 90)
			(size 0.4 0.6)
			(layers "B.Cu" "B.Mask" "B.Paste")
			(net 495 "unconnected-(Q302-NC-Pad5)")
			(pinfunction "NC")
			(pintype "no_connect")
		)
		(pad "6" smd custom
			(at 0.951 0.752 90)
			(size 0.6 0.6)
			(layers "B.Cu" "B.Mask" "B.Paste")
			(net 47 "/Ethernet/POE_12V")
			(pinfunction "D")
			(pintype "power_in")
			(options
				(clearance outline)
				(anchor rect)
			)
			(primitives)
		)
	)
	(footprint "antmicro-footprints:R_0402_1005Metric"
		(layer "B.Cu")
		(at 84.937962 164.1365)
		(descr "Resistor SMD 0402")
		(tags "resistor SMD 0402")
		(property "Reference" "R208"
			(at -3.62 0.53 0)
			(layer "B.SilkS")
			(effects
				(font
					(size 0.7 0.7)
					(thickness 0.15)
				)
				(justify right bottom mirror)
			)
		)
		(property "Value" "R_0R_0402"
			(at -1.011843 -1.772047 0)
			(layer "B.Fab")
			(effects
				(font
					(size 0.7 0.7)
					(thickness 0.15)
				)
				(justify right bottom mirror)
			)
		)
		(property "Datasheet" "https://industrial.panasonic.com/cdbs/www-data/pdf/RDA0000/AOA0000C301.pdf"
			(at 0 0 0)
			(layer "B.Fab")
			(hide yes)
			(effects
				(font
					(size 1.27 1.27)
					(thickness 0.15)
				)
			)
		)
		(property "Manufacturer" "Panasonic"
			(at 0 0 0)
			(unlocked yes)
			(layer "B.Fab")
			(hide yes)
			(effects
				(font
					(size 1 1)
					(thickness 0.15)
				)
				(justify mirror)
			)
		)
		(property "MPN" "ERJ2GE0R00X"
			(at 0 0 0)
			(unlocked yes)
			(layer "B.Fab")
			(hide yes)
			(effects
				(font
					(size 1 1)
					(thickness 0.15)
				)
				(justify mirror)
			)
		)
		(property "Val" "0R"
			(at 0 0 0)
			(unlocked yes)
			(layer "B.Fab")
			(hide yes)
			(effects
				(font
					(size 1 1)
					(thickness 0.15)
				)
				(justify mirror)
			)
		)
		(property "License" "Apache-2.0"
			(at 0 0 0)
			(unlocked yes)
			(layer "B.Fab")
			(hide yes)
			(effects
				(font
					(size 1 1)
					(thickness 0.15)
				)
				(justify mirror)
			)
		)
		(property "Author" "Antmicro"
			(at 0 0 0)
			(unlocked yes)
			(layer "B.Fab")
			(hide yes)
			(effects
				(font
					(size 1 1)
					(thickness 0.15)
				)
				(justify mirror)
			)
		)
		(property "Tolerance" "~"
			(at 0 0 0)
			(unlocked yes)
			(layer "B.Fab")
			(hide yes)
			(effects
				(font
					(size 1 1)
					(thickness 0.15)
				)
				(justify mirror)
			)
		)
		(property "Current" "1A"
			(at 0 0 0)
			(unlocked yes)
			(layer "B.Fab")
			(hide yes)
			(effects
				(font
					(size 1 1)
					(thickness 0.15)
				)
				(justify mirror)
			)
		)
		(sheetname "/Compute module/")
		(sheetfile "compute-module.kicad_sch")
		(attr smd exclude_from_pos_files exclude_from_bom dnp)
		(fp_rect
			(start -0.925 0.47)
			(end 0.925 -0.47)
			(stroke
				(width 0.05)
				(type default)
			)
			(fill no)
			(layer "B.CrtYd")
		)
		(fp_rect
			(start -0.5 0.25)
			(end 0.5 -0.25)
			(stroke
				(width 0.15)
				(type solid)
			)
			(fill no)
			(layer "B.Fab")
		)
		(fp_text user "License: Apache-2.0"
			(at -0.95 -5.169 180)
			(layer "B.Fab")
			(effects
				(font
					(size 0.7 0.7)
					(thickness 0.15)
				)
				(justify left bottom mirror)
			)
		)
		(fp_text user "Author: Antmicro"
			(at -0.95 -4.169 180)
			(layer "B.Fab")
			(effects
				(font
					(size 0.7 0.7)
					(thickness 0.15)
				)
				(justify left bottom mirror)
			)
		)
		(fp_text user "${REFERENCE}"
			(at -0.95 -3.168 180)
			(layer "B.Fab")
			(effects
				(font
					(size 0.7 0.7)
					(thickness 0.15)
				)
				(justify left bottom mirror)
			)
		)
		(pad "1" smd roundrect
			(at -0.48 0)
			(size 0.59 0.64)
			(layers "B.Cu" "B.Mask" "B.Paste")
			(roundrect_rratio 0.25)
			(net 254 "/Compute module/CAM_GPIO")
			(pintype "passive")
		)
		(pad "2" smd roundrect
			(at 0.48 0)
			(size 0.59 0.64)
			(layers "B.Cu" "B.Mask" "B.Paste")
			(roundrect_rratio 0.25)
			(net 274 "/CSI/CamCtrl.VSYNC0")
			(pintype "passive")
		)
	)
	(footprint "antmicro-footprints:MicroSD_Amphenol_1140084168"
		(layer "B.Cu")
		(at 133.800462 163.5665 -90)
		(property "Reference" "J502"
			(at -6.72 -5.9675 0)
			(layer "B.SilkS")
			(effects
				(font
					(size 0.7 0.7)
					(thickness 0.15)
				)
				(justify right bottom mirror)
			)
		)
		(property "Value" "MicroSD_1140084168"
			(at -6.9 -11.4 90)
			(layer "B.Fab")
			(effects
				(font
					(size 0.7 0.7)
					(thickness 0.15)
				)
				(justify left bottom mirror)
			)
		)
		(property "Datasheet" "https://cdn.amphenol-cs.com/media/wysiwyg/files/documentation/datasheet/inputoutput/io_micro_sdcard.pdf"
			(at 0 0 270)
			(layer "B.Fab")
			(hide yes)
			(effects
				(font
					(size 1.27 1.27)
					(thickness 0.15)
				)
			)
		)
		(property "MPN" "1140084168"
			(at 0 0 270)
			(unlocked yes)
			(layer "B.Fab")
			(hide yes)
			(effects
				(font
					(size 1 1)
					(thickness 0.15)
				)
				(justify mirror)
			)
		)
		(property "Manufacturer" "Amphenol"
			(at 0 0 270)
			(unlocked yes)
			(layer "B.Fab")
			(hide yes)
			(effects
				(font
					(size 1 1)
					(thickness 0.15)
				)
				(justify mirror)
			)
		)
		(property "Author" "Antmicro"
			(at 0 0 270)
			(unlocked yes)
			(layer "B.Fab")
			(hide yes)
			(effects
				(font
					(size 1 1)
					(thickness 0.15)
				)
				(justify mirror)
			)
		)
		(property "License" "Apache-2.0"
			(at 0 0 270)
			(unlocked yes)
			(layer "B.Fab")
			(hide yes)
			(effects
				(font
					(size 1 1)
					(thickness 0.15)
				)
				(justify mirror)
			)
		)
		(sheetname "/NVMe & microSD/")
		(sheetfile "nvme-micro-sd.kicad_sch")
		(attr smd)
		(fp_line
			(start -6.3 6.1)
			(end -6.3 4.7)
			(stroke
				(width 0.15)
				(type solid)
			)
			(layer "B.SilkS")
		)
		(fp_line
			(start 4.8 6.1)
			(end -6.3 6.1)
			(stroke
				(width 0.15)
				(type solid)
			)
			(layer "B.SilkS")
		)
		(fp_line
			(start 6.2 6.1)
			(end 6.1 6.1)
			(stroke
				(width 0.15)
				(type solid)
			)
			(layer "B.SilkS")
		)
		(fp_line
			(start 6.2 4)
			(end 6.2 6.1)
			(stroke
				(width 0.15)
				(type solid)
			)
			(layer "B.SilkS")
		)
		(fp_line
			(start -6.3 1.6)
			(end -6.3 -4.2)
			(stroke
				(width 0.15)
				(type solid)
			)
			(layer "B.SilkS")
		)
		(fp_line
			(start 6.2 -4.2)
			(end 6.2 2.2)
			(stroke
				(width 0.15)
				(type solid)
			)
			(layer "B.SilkS")
		)
		(fp_rect
			(start -6.5 6.3)
			(end 6.4 -6.2)
			(stroke
				(width 0.05)
				(type solid)
			)
			(fill no)
			(layer "B.CrtYd")
		)
		(fp_line
			(start -5.6 -5.8)
			(end -5.6 -9.5)
			(stroke
				(width 0.12)
				(type solid)
			)
			(layer "B.Fab")
		)
		(fp_line
			(start -1 -8.2)
			(end -2.3 -8.3)
			(stroke
				(width 0.12)
				(type solid)
			)
			(layer "B.Fab")
		)
		(fp_line
			(start 0.8 -8.2)
			(end -1 -8.2)
			(stroke
				(width 0.12)
				(type solid)
			)
			(layer "B.Fab")
		)
		(fp_line
			(start -2.3 -8.3)
			(end -3.8 -8.5)
			(stroke
				(width 0.12)
				(type solid)
			)
			(layer "B.Fab")
		)
		(fp_line
			(start 2.1 -8.3)
			(end 0.8 -8.2)
			(stroke
				(width 0.12)
				(type solid)
			)
			(layer "B.Fab")
		)
		(fp_line
			(start 2.9 -8.4)
			(end 2.1 -8.3)
			(stroke
				(width 0.12)
				(type solid)
			)
			(layer "B.Fab")
		)
		(fp_line
			(start -3.8 -8.5)
			(end -5.1 -8.8)
			(stroke
				(width 0.12)
				(type solid)
			)
			(layer "B.Fab")
		)
		(fp_line
			(start -1 -8.5)
			(end -2.3 -8.6)
			(stroke
				(width 0.12)
				(type solid)
			)
			(layer "B.Fab")
		)
		(fp_line
			(start 0.8 -8.5)
			(end -1 -8.5)
			(stroke
				(width 0.12)
				(type solid)
			)
			(layer "B.Fab")
		)
		(fp_line
			(start -2.3 -8.6)
			(end -3.8 -8.8)
			(stroke
				(width 0.12)
				(type solid)
			)
			(layer "B.Fab")
		)
		(fp_line
			(start 2.1 -8.6)
			(end 0.8 -8.5)
			(stroke
				(width 0.12)
				(type solid)
			)
			(layer "B.Fab")
		)
		(fp_line
			(start 2.9 -8.7)
			(end 2.1 -8.6)
			(stroke
				(width 0.12)
				(type solid)
			)
			(layer "B.Fab")
		)
		(fp_line
			(start 4.6 -8.7)
			(end 2.9 -8.4)
			(stroke
				(width 0.12)
				(type solid)
			)
			(layer "B.Fab")
		)
		(fp_line
			(start -5.1 -8.8)
			(end -5.6 -8.9)
			(stroke
				(width 0.12)
				(type solid)
			)
			(layer "B.Fab")
		)
		(fp_line
			(start -3.8 -8.8)
			(end -5.1 -9.1)
			(stroke
				(width 0.12)
				(type solid)
			)
			(layer "B.Fab")
		)
		(fp_line
			(start 5.4 -8.9)
			(end 4.6 -8.7)
			(stroke
				(width 0.12)
				(type solid)
			)
			(layer "B.Fab")
		)
		(fp_line
			(start 4.6 -9)
			(end 2.9 -8.7)
			(stroke
				(width 0.12)
				(type solid)
			)
			(layer "B.Fab")
		)
		(fp_line
			(start -5.1 -9.1)
			(end -5.6 -9.2)
			(stroke
				(width 0.12)
				(type solid)
			)
			(layer "B.Fab")
		)
		(fp_line
			(start 5.4 -9.2)
			(end 4.6 -9)
			(stroke
				(width 0.12)
				(type solid)
			)
			(layer "B.Fab")
		)
		(fp_line
			(start 5.4 -9.5)
			(end 5.4 -5.8)
			(stroke
				(width 0.12)
				(type solid)
			)
			(layer "B.Fab")
		)
		(fp_line
			(start 4.9 -10)
			(end -5.1 -10)
			(stroke
				(width 0.12)
				(type solid)
			)
			(layer "B.Fab")
		)
		(fp_rect
			(start -6 5.8)
			(end 5.999 -5.799)
			(stroke
				(width 0.1)
				(type solid)
			)
			(fill no)
			(layer "B.Fab")
		)
		(fp_arc
			(start -5.6 -9.5)
			(mid -5.453553 -9.853553)
			(end -5.1 -10)
			(stroke
				(width 0.12)
				(type solid)
			)
			(layer "B.Fab")
		)
		(fp_arc
			(start 4.9 -10)
			(mid 5.253553 -9.853553)
			(end 5.4 -9.5)
			(stroke
				(width 0.12)
				(type solid)
			)
			(layer "B.Fab")
		)
		(fp_text user "License: Apache-2.0"
			(at -6.925 -15.4 90)
			(layer "B.Fab")
			(effects
				(font
					(size 0.7 0.7)
					(thickness 0.15)
				)
				(justify left bottom mirror)
			)
		)
		(fp_text user "${REFERENCE}"
			(at -6.925 -12.774 90)
			(layer "B.Fab")
			(effects
				(font
					(size 0.7 0.7)
					(thickness 0.15)
				)
				(justify left bottom mirror)
			)
		)
		(fp_text user "Author: Antmicro"
			(at -6.925 -14.1 90)
			(layer "B.Fab")
			(effects
				(font
					(size 0.7 0.7)
					(thickness 0.15)
				)
				(justify left bottom mirror)
			)
		)
		(pad "1" smd rect
			(at 3.124 -5.254 90)
			(size 0.7 1.75)
			(layers "B.Cu" "B.Mask" "B.Paste")
			(net 12 "/Compute module/SDIO.D2")
			(pinfunction "DAT2")
			(pintype "bidirectional")
		)
		(pad "2" smd rect
			(at 2.024 -5.254 90)
			(size 0.7 1.75)
			(layers "B.Cu" "B.Mask" "B.Paste")
			(net 11 "/Compute module/SDIO.D3")
			(pinfunction "CD/DAT3")
			(pintype "bidirectional")
		)
		(pad "3" smd rect
			(at 0.925 -5.254 90)
			(size 0.7 1.75)
			(layers "B.Cu" "B.Mask" "B.Paste")
			(net 8 "/Compute module/SDIO.CMD")
			(pinfunction "CMD")
			(pintype "bidirectional")
		)
		(pad "4" smd rect
			(at -0.176 -5.254 90)
			(size 0.7 1.75)
			(layers "B.Cu" "B.Mask" "B.Paste")
			(net 9 "+3V3")
			(pinfunction "VDD")
			(pintype "power_in")
		)
		(pad "5" smd rect
			(at -1.276 -5.254 90)
			(size 0.7 1.75)
			(layers "B.Cu" "B.Mask" "B.Paste")
			(net 7 "/Compute module/SDIO.CLK")
			(pinfunction "CLK")
			(pintype "output")
		)
		(pad "6" smd rect
			(at -2.375 -5.254 90)
			(size 0.7 1.75)
			(layers "B.Cu" "B.Mask" "B.Paste")
			(net 3 "GND")
			(pinfunction "VSS")
			(pintype "power_in")
		)
		(pad "7" smd rect
			(at -3.476 -5.254 90)
			(size 0.7 1.75)
			(layers "B.Cu" "B.Mask" "B.Paste")
			(net 6 "/Compute module/SDIO.D0")
			(pinfunction "DAT0")
			(pintype "bidirectional")
		)
		(pad "8" smd rect
			(at -4.576 -5.254 90)
			(size 0.7 1.75)
			(layers "B.Cu" "B.Mask" "B.Paste")
			(net 5 "/Compute module/SDIO.D1")
			(pinfunction "DAT1")
			(pintype "bidirectional")
		)
		(pad "9" smd rect
			(at -5.675 4.05 270)
			(size 1.4 1)
			(layers "B.Cu" "B.Mask" "B.Paste")
			(net 268 "Net-(J502-CD1)")
			(pinfunction "CD1")
			(pintype "passive")
		)
		(pad "10" smd rect
			(at 5.424 5.531 180)
			(size 1.4 1)
			(layers "B.Cu" "B.Mask" "B.Paste")
			(net 263 "Net-(J502-CD2)")
			(pinfunction "CD2")
			(pintype "passive")
		)
		(pad "SH" smd rect
			(at -5.976 2.48 180)
			(size 1.5 0.8)
			(layers "B.Cu" "B.Mask" "B.Paste")
			(net 3 "GND")
			(pinfunction "Shell")
			(pintype "passive")
		)
		(pad "SH" smd rect
			(at -5.776 -5.129 270)
			(size 1.3 1.5)
			(layers "B.Cu" "B.Mask" "B.Paste")
			(net 3 "GND")
			(pinfunction "Shell")
			(pintype "passive")
		)
		(pad "SH" smd rect
			(at 5.575 -5.129 270)
			(size 1.5 1.5)
			(layers "B.Cu" "B.Mask" "B.Paste")
			(net 3 "GND")
			(pinfunction "Shell")
			(pintype "passive")
		)
		(pad "SH" smd rect
			(at 5.874 3.13 180)
			(size 1.5 0.8)
			(layers "B.Cu" "B.Mask" "B.Paste")
			(net 3 "GND")
			(pinfunction "Shell")
			(pintype "passive")
		)
	)
	(footprint "antmicro-footprints:R_0402_1005Metric"
		(layer "B.Cu")
		(at 52.862962 169.9165 180)
		(descr "Resistor SMD 0402")
		(tags "resistor SMD 0402")
		(property "Reference" "R422"
			(at -1.095 -1.32 0)
			(layer "B.SilkS")
			(effects
				(font
					(size 0.7 0.7)
					(thickness 0.15)
				)
				(justify left bottom mirror)
			)
		)
		(property "Value" "R_0R_0402"
			(at -1.011843 -1.772047 0)
			(layer "B.Fab")
			(effects
				(font
					(size 0.7 0.7)
					(thickness 0.15)
				)
				(justify left bottom mirror)
			)
		)
		(property "Datasheet" "https://industrial.panasonic.com/cdbs/www-data/pdf/RDA0000/AOA0000C301.pdf"
			(at 0 0 180)
			(layer "B.Fab")
			(hide yes)
			(effects
				(font
					(size 1.27 1.27)
					(thickness 0.15)
				)
			)
		)
		(property "Manufacturer" "Panasonic"
			(at 0 0 180)
			(unlocked yes)
			(layer "B.Fab")
			(hide yes)
			(effects
				(font
					(size 1 1)
					(thickness 0.15)
				)
				(justify mirror)
			)
		)
		(property "MPN" "ERJ2GE0R00X"
			(at 0 0 180)
			(unlocked yes)
			(layer "B.Fab")
			(hide yes)
			(effects
				(font
					(size 1 1)
					(thickness 0.15)
				)
				(justify mirror)
			)
		)
		(property "Val" "0R"
			(at 0 0 180)
			(unlocked yes)
			(layer "B.Fab")
			(hide yes)
			(effects
				(font
					(size 1 1)
					(thickness 0.15)
				)
				(justify mirror)
			)
		)
		(property "License" "Apache-2.0"
			(at 0 0 180)
			(unlocked yes)
			(layer "B.Fab")
			(hide yes)
			(effects
				(font
					(size 1 1)
					(thickness 0.15)
				)
				(justify mirror)
			)
		)
		(property "Author" "Antmicro"
			(at 0 0 180)
			(unlocked yes)
			(layer "B.Fab")
			(hide yes)
			(effects
				(font
					(size 1 1)
					(thickness 0.15)
				)
				(justify mirror)
			)
		)
		(property "Tolerance" "~"
			(at 0 0 180)
			(unlocked yes)
			(layer "B.Fab")
			(hide yes)
			(effects
				(font
					(size 1 1)
					(thickness 0.15)
				)
				(justify mirror)
			)
		)
		(property "Current" "1A"
			(at 0 0 180)
			(unlocked yes)
			(layer "B.Fab")
			(hide yes)
			(effects
				(font
					(size 1 1)
					(thickness 0.15)
				)
				(justify mirror)
			)
		)
		(sheetname "/Ethernet/")
		(sheetfile "ethernet.kicad_sch")
		(attr smd exclude_from_pos_files exclude_from_bom dnp)
		(fp_rect
			(start -0.925 0.47)
			(end 0.925 -0.47)
			(stroke
				(width 0.05)
				(type default)
			)
			(fill no)
			(layer "B.CrtYd")
		)
		(fp_rect
			(start -0.5 0.25)
			(end 0.5 -0.25)
			(stroke
				(width 0.15)
				(type solid)
			)
			(fill no)
			(layer "B.Fab")
		)
		(fp_text user "Author: Antmicro"
			(at -0.95 -4.169 0)
			(layer "B.Fab")
			(effects
				(font
					(size 0.7 0.7)
					(thickness 0.15)
				)
				(justify left bottom mirror)
			)
		)
		(fp_text user "License: Apache-2.0"
			(at -0.95 -5.169 0)
			(layer "B.Fab")
			(effects
				(font
					(size 0.7 0.7)
					(thickness 0.15)
				)
				(justify left bottom mirror)
			)
		)
		(fp_text user "${REFERENCE}"
			(at -0.95 -3.168 0)
			(layer "B.Fab")
			(effects
				(font
					(size 0.7 0.7)
					(thickness 0.15)
				)
				(justify left bottom mirror)
			)
		)
		(pad "1" smd roundrect
			(at -0.48 0 180)
			(size 0.59 0.64)
			(layers "B.Cu" "B.Mask" "B.Paste")
			(roundrect_rratio 0.25)
			(net 47 "/Ethernet/POE_12V")
			(pintype "passive")
		)
		(pad "2" smd roundrect
			(at 0.48 0 180)
			(size 0.59 0.64)
			(layers "B.Cu" "B.Mask" "B.Paste")
			(roundrect_rratio 0.25)
			(net 368 "Net-(U403-TRIM)")
			(pintype "passive")
		)
	)
	(footprint "antmicro-footprints:R_0402_1005Metric"
		(layer "B.Cu")
		(at 92.537962 152.4165)
		(descr "Resistor SMD 0402")
		(tags "resistor SMD 0402")
		(property "Reference" "R236"
			(at -0.99 3.96 0)
			(layer "B.SilkS")
			(effects
				(font
					(size 0.7 0.7)
					(thickness 0.15)
				)
				(justify right bottom mirror)
			)
		)
		(property "Value" "R_10k_0402"
			(at -1.011843 -1.772047 0)
			(layer "B.Fab")
			(effects
				(font
					(size 0.7 0.7)
					(thickness 0.15)
				)
				(justify right bottom mirror)
			)
		)
		(property "Datasheet" "https://www.bourns.com/docs/product-datasheets/cr.pdf"
			(at 0 0 0)
			(layer "B.Fab")
			(hide yes)
			(effects
				(font
					(size 1.27 1.27)
					(thickness 0.15)
				)
			)
		)
		(property "MPN" "CR0402-FX-1002GLF"
			(at 0 0 0)
			(unlocked yes)
			(layer "B.Fab")
			(hide yes)
			(effects
				(font
					(size 1 1)
					(thickness 0.15)
				)
				(justify mirror)
			)
		)
		(property "Manufacturer" "Bourns"
			(at 0 0 0)
			(unlocked yes)
			(layer "B.Fab")
			(hide yes)
			(effects
				(font
					(size 1 1)
					(thickness 0.15)
				)
				(justify mirror)
			)
		)
		(property "License" "Apache-2.0"
			(at 0 0 0)
			(unlocked yes)
			(layer "B.Fab")
			(hide yes)
			(effects
				(font
					(size 1 1)
					(thickness 0.15)
				)
				(justify mirror)
			)
		)
		(property "Author" "Antmicro"
			(at 0 0 0)
			(unlocked yes)
			(layer "B.Fab")
			(hide yes)
			(effects
				(font
					(size 1 1)
					(thickness 0.15)
				)
				(justify mirror)
			)
		)
		(property "Val" "10k"
			(at 0 0 0)
			(unlocked yes)
			(layer "B.Fab")
			(hide yes)
			(effects
				(font
					(size 1 1)
					(thickness 0.15)
				)
				(justify mirror)
			)
		)
		(property "Tolerance" "1%"
			(at 0 0 0)
			(unlocked yes)
			(layer "B.Fab")
			(hide yes)
			(effects
				(font
					(size 1 1)
					(thickness 0.15)
				)
				(justify mirror)
			)
		)
		(sheetname "/Compute module/")
		(sheetfile "compute-module.kicad_sch")
		(attr smd exclude_from_pos_files exclude_from_bom dnp)
		(fp_rect
			(start -0.925 0.47)
			(end 0.925 -0.47)
			(stroke
				(width 0.05)
				(type default)
			)
			(fill no)
			(layer "B.CrtYd")
		)
		(fp_rect
			(start -0.5 0.25)
			(end 0.5 -0.25)
			(stroke
				(width 0.15)
				(type solid)
			)
			(fill no)
			(layer "B.Fab")
		)
		(fp_text user "Author: Antmicro"
			(at -0.95 -4.169 180)
			(layer "B.Fab")
			(effects
				(font
					(size 0.7 0.7)
					(thickness 0.15)
				)
				(justify left bottom mirror)
			)
		)
		(fp_text user "License: Apache-2.0"
			(at -0.95 -5.169 180)
			(layer "B.Fab")
			(effects
				(font
					(size 0.7 0.7)
					(thickness 0.15)
				)
				(justify left bottom mirror)
			)
		)
		(fp_text user "${REFERENCE}"
			(at -0.95 -3.168 180)
			(layer "B.Fab")
			(effects
				(font
					(size 0.7 0.7)
					(thickness 0.15)
				)
				(justify left bottom mirror)
			)
		)
		(pad "1" smd roundrect
			(at -0.48 0)
			(size 0.59 0.64)
			(layers "B.Cu" "B.Mask" "B.Paste")
			(roundrect_rratio 0.25)
			(net 349 "Net-(U204-A0)")
			(pintype "passive")
		)
		(pad "2" smd roundrect
			(at 0.48 0)
			(size 0.59 0.64)
			(layers "B.Cu" "B.Mask" "B.Paste")
			(roundrect_rratio 0.25)
			(net 9 "+3V3")
			(pintype "passive")
		)
	)
	(footprint "antmicro-footprints:C_0402_1005Metric"
		(layer "B.Cu")
		(at 42.327962 157.1365 90)
		(descr "Capacitor SMD 0402")
		(tags "capacitor SMD 0402")
		(property "Reference" "C302"
			(at -1.49 -2.51 90)
			(layer "B.SilkS")
			(effects
				(font
					(size 0.7 0.7)
					(thickness 0.15)
				)
				(justify right bottom mirror)
			)
		)
		(property "Value" "C_100n_0402"
			(at -1.022927 -2.155213 90)
			(layer "B.Fab")
			(effects
				(font
					(size 0.7 0.7)
					(thickness 0.15)
				)
				(justify right bottom mirror)
			)
		)
		(property "Datasheet" "https://www.murata.com/products/productdetail?partno=GRM155R61H104KE14%23"
			(at 0 0 90)
			(layer "B.Fab")
			(hide yes)
			(effects
				(font
					(size 1.27 1.27)
					(thickness 0.15)
				)
			)
		)
		(property "Manufacturer" "Murata"
			(at 0 0 90)
			(unlocked yes)
			(layer "B.Fab")
			(hide yes)
			(effects
				(font
					(size 1 1)
					(thickness 0.15)
				)
				(justify mirror)
			)
		)
		(property "MPN" "GRM155R61H104KE14D"
			(at 0 0 90)
			(unlocked yes)
			(layer "B.Fab")
			(hide yes)
			(effects
				(font
					(size 1 1)
					(thickness 0.15)
				)
				(justify mirror)
			)
		)
		(property "Val" "100n"
			(at 0 0 90)
			(unlocked yes)
			(layer "B.Fab")
			(hide yes)
			(effects
				(font
					(size 1 1)
					(thickness 0.15)
				)
				(justify mirror)
			)
		)
		(property "License" "Apache-2.0"
			(at 0 0 90)
			(unlocked yes)
			(layer "B.Fab")
			(hide yes)
			(effects
				(font
					(size 1 1)
					(thickness 0.15)
				)
				(justify mirror)
			)
		)
		(property "Author" "Antmicro"
			(at 0 0 90)
			(unlocked yes)
			(layer "B.Fab")
			(hide yes)
			(effects
				(font
					(size 1 1)
					(thickness 0.15)
				)
				(justify mirror)
			)
		)
		(property "Voltage" "50V"
			(at 0 0 90)
			(unlocked yes)
			(layer "B.Fab")
			(hide yes)
			(effects
				(font
					(size 1 1)
					(thickness 0.15)
				)
				(justify mirror)
			)
		)
		(property "Dielectric" "X5R"
			(at 0 0 90)
			(unlocked yes)
			(layer "B.Fab")
			(hide yes)
			(effects
				(font
					(size 1 1)
					(thickness 0.15)
				)
				(justify mirror)
			)
		)
		(sheetname "/Supply/")
		(sheetfile "supply.kicad_sch")
		(attr smd)
		(fp_rect
			(start -0.925 0.47)
			(end 0.925 -0.47)
			(stroke
				(width 0.05)
				(type default)
			)
			(fill no)
			(layer "B.CrtYd")
		)
		(fp_line
			(start 0.504 -0.248)
			(end -0.494 -0.248)
			(stroke
				(width 0.15)
				(type solid)
			)
			(layer "B.Fab")
		)
		(fp_line
			(start -0.494 -0.248)
			(end -0.494 0.25)
			(stroke
				(width 0.15)
				(type solid)
			)
			(layer "B.Fab")
		)
		(fp_line
			(start 0.504 0.25)
			(end 0.504 -0.248)
			(stroke
				(width 0.15)
				(type solid)
			)
			(layer "B.Fab")
		)
		(fp_line
			(start -0.494 0.25)
			(end 0.504 0.25)
			(stroke
				(width 0.15)
				(type solid)
			)
			(layer "B.Fab")
		)
		(fp_text user "${REFERENCE}"
			(at -0.939 -4.599 270)
			(layer "B.Fab")
			(effects
				(font
					(size 0.7 0.7)
					(thickness 0.15)
				)
				(justify left bottom mirror)
			)
		)
		(fp_text user "Author: Antmicro"
			(at -0.939 -3.399 270)
			(layer "B.Fab")
			(effects
				(font
					(size 0.7 0.7)
					(thickness 0.15)
				)
				(justify left bottom mirror)
			)
		)
		(fp_text user "License: Apache-2.0"
			(at -0.939 -5.799 270)
			(layer "B.Fab")
			(effects
				(font
					(size 0.7 0.7)
					(thickness 0.15)
				)
				(justify left bottom mirror)
			)
		)
		(pad "1" smd roundrect
			(at -0.48 0 90)
			(size 0.59 0.64)
			(layers "B.Cu" "B.Mask" "B.Paste")
			(roundrect_rratio 0.25)
			(net 17 "Net-(Q307-G)")
			(pintype "passive")
		)
		(pad "2" smd roundrect
			(at 0.48 0 90)
			(size 0.59 0.64)
			(layers "B.Cu" "B.Mask" "B.Paste")
			(roundrect_rratio 0.25)
			(net 43 "VCC")
			(pintype "passive")
		)
	)
	(footprint "antmicro-footprints:Spacer_Drill3.7mm_H6mm_9774060151R"
		(layer "B.Cu")
		(at 138.917962 174.7165 180)
		(descr "Spacer M=3 h=36mm fi=5.1mm")
		(property "Reference" "H102"
			(at -2.052038 3.3865 0)
			(layer "B.SilkS")
			(effects
				(font
					(size 0.7 0.7)
					(thickness 0.15)
				)
				(justify left bottom mirror)
			)
		)
		(property "Value" "Spacer_Drill3.7mm_H6mm_9774060151R"
			(at 0 -4 0)
			(layer "B.Fab")
			(effects
				(font
					(size 0.7 0.7)
					(thickness 0.15)
				)
				(justify left bottom mirror)
			)
		)
		(property "Datasheet" "https://www.we-online.com/components/products/datasheet/9774060151R.pdf"
			(at 0 0 0)
			(layer "B.Fab")
			(hide yes)
			(effects
				(font
					(size 1.27 1.27)
					(thickness 0.15)
				)
				(justify mirror)
			)
		)
		(property "Manufacturer" "Würth Elektronik"
			(at 0 0 180)
			(unlocked yes)
			(layer "B.Fab")
			(hide yes)
			(effects
				(font
					(size 1 1)
					(thickness 0.15)
				)
				(justify mirror)
			)
		)
		(property "MPN" "9774060151R"
			(at 0 0 180)
			(unlocked yes)
			(layer "B.Fab")
			(hide yes)
			(effects
				(font
					(size 1 1)
					(thickness 0.15)
				)
				(justify mirror)
			)
		)
		(property "Author" "Antmicro"
			(at 0 0 180)
			(unlocked yes)
			(layer "B.Fab")
			(hide yes)
			(effects
				(font
					(size 1 1)
					(thickness 0.15)
				)
				(justify mirror)
			)
		)
		(property "License" "Apache-2.0"
			(at 0 0 180)
			(unlocked yes)
			(layer "B.Fab")
			(hide yes)
			(effects
				(font
					(size 1 1)
					(thickness 0.15)
				)
				(justify mirror)
			)
		)
		(sheetname "/")
		(sheetfile "cm4-baseboard.kicad_sch")
		(solder_paste_margin_ratio -1)
		(attr smd)
		(fp_circle
			(center 0 0)
			(end 3.05 0)
			(stroke
				(width 0.05)
				(type solid)
			)
			(fill no)
			(layer "B.CrtYd")
		)
		(fp_circle
			(center 0 0)
			(end 2.6 0)
			(stroke
				(width 0.15)
				(type solid)
			)
			(fill no)
			(layer "B.Fab")
		)
		(fp_text user "${REFERENCE}"
			(at -9.6 -6.5 0)
			(layer "B.Fab")
			(effects
				(font
					(size 0.7 0.7)
					(thickness 0.15)
				)
				(justify left bottom mirror)
			)
		)
		(fp_text user "Author: Antmicro"
			(at -9.6 -7.7 0)
			(layer "B.Fab")
			(effects
				(font
					(size 0.7 0.7)
					(thickness 0.15)
				)
				(justify left bottom mirror)
			)
		)
		(fp_text user "License: Apache-2.0"
			(at -9.6 -8.9 0)
			(layer "B.Fab")
			(effects
				(font
					(size 0.7 0.7)
					(thickness 0.15)
				)
				(justify left bottom mirror)
			)
		)
		(pad "" smd custom
			(at -1.7 -1.7 90)
			(size 0.62 0.62)
			(layers "B.Paste")
			(thermal_bridge_angle 90)
			(options
				(clearance outline)
				(anchor circle)
			)
			(primitives
				(gr_arc
					(start 1.266786 0.24747)
					(mid 0.285453 -0.29439)
					(end -0.250195 -1.279127)
					(width 0.2)
				)
				(gr_arc
					(start 1.259603 0.339191)
					(mid 0.218448 -0.232561)
					(end -0.34334 -1.279127)
					(width 0.2)
				)
				(gr_arc
					(start 1.255279 0.431435)
					(mid 0.152481 -0.169693)
					(end -0.436309 -1.279127)
					(width 0.2)
				)
				(gr_arc
					(start 1.253811 0.524161)
					(mid 0.087542 -0.105784)
					(end -0.529126 -1.279127)
					(width 0.2)
				)
				(gr_arc
					(start 1.275473 0.621136)
					(mid 0.0309 -0.033527)
					(end -0.621807 -1.279127)
					(width 0.2)
				)
				(gr_arc
					(start 1.263664 0.711602)
					(mid -0.037759 0.026651)
					(end -0.71437 -1.279127)
					(width 0.2)
				)
				(gr_arc
					(start 1.253435 0.802342)
					(mid -0.105837 0.087395)
					(end -0.806826 -1.279127)
					(width 0.2)
				)
				(gr_arc
					(start 1.267475 0.897258)
					(mid -0.165236 0.156885)
					(end -0.899187 -1.279127)
					(width 0.2)
				)
				(gr_arc
					(start 1.270645 0.990112)
					(mid -0.228522 0.222449)
					(end -0.991463 -1.279127)
					(width 0.2)
				)
				(gr_arc
					(start 1.266278 1.081674)
					(mid -0.294507 0.285313)
					(end -1.083663 -1.279127)
					(width 0.2)
				)
				(gr_line
					(start 1.279127 0.250195)
					(end 1.279127 1.083663)
					(width 0.2)
				)
				(gr_line
					(start -0.250195 -1.279127)
					(end -1.083663 -1.279127)
					(width 0.2)
				)
			)
		)
		(pad "" smd custom
			(at -1.7 1.7 180)
			(size 0.62 0.62)
			(layers "B.Paste")
			(thermal_bridge_angle 90)
			(options
				(clearance outline)
				(anchor circle)
			)
			(primitives
				(gr_arc
					(start 1.266786 0.24747)
					(mid 0.285453 -0.29439)
					(end -0.250195 -1.279127)
					(width 0.2)
				)
				(gr_arc
					(start 1.259603 0.339191)
					(mid 0.218448 -0.232561)
					(end -0.34334 -1.279127)
					(width 0.2)
				)
				(gr_arc
					(start 1.255279 0.431435)
					(mid 0.152481 -0.169693)
					(end -0.436309 -1.279127)
					(width 0.2)
				)
				(gr_arc
					(start 1.253811 0.524161)
					(mid 0.087542 -0.105784)
					(end -0.529126 -1.279127)
					(width 0.2)
				)
				(gr_arc
					(start 1.275473 0.621136)
					(mid 0.0309 -0.033527)
					(end -0.621807 -1.279127)
					(width 0.2)
				)
				(gr_arc
					(start 1.263664 0.711602)
					(mid -0.037759 0.026651)
					(end -0.71437 -1.279127)
					(width 0.2)
				)
				(gr_arc
					(start 1.253435 0.802342)
					(mid -0.105837 0.087395)
					(end -0.806826 -1.279127)
					(width 0.2)
				)
				(gr_arc
					(start 1.267475 0.897258)
					(mid -0.165236 0.156885)
					(end -0.899187 -1.279127)
					(width 0.2)
				)
				(gr_arc
					(start 1.270645 0.990112)
					(mid -0.228522 0.222449)
					(end -0.991463 -1.279127)
					(width 0.2)
				)
				(gr_arc
					(start 1.266278 1.081674)
					(mid -0.294507 0.285313)
					(end -1.083663 -1.279127)
					(width 0.2)
				)
				(gr_line
					(start 1.279127 0.250195)
					(end 1.279127 1.083663)
					(width 0.2)
				)
				(gr_line
					(start -0.250195 -1.279127)
					(end -1.083663 -1.279127)
					(width 0.2)
				)
			)
		)
		(pad "" smd custom
			(at 1.7 -1.7)
			(size 0.62 0.62)
			(layers "B.Paste")
			(thermal_bridge_angle 90)
			(options
				(clearance outline)
				(anchor circle)
			)
			(primitives
				(gr_arc
					(start 1.266786 0.24747)
					(mid 0.285453 -0.29439)
					(end -0.250195 -1.279127)
					(width 0.2)
				)
				(gr_arc
					(start 1.259603 0.339191)
					(mid 0.218448 -0.232561)
					(end -0.34334 -1.279127)
					(width 0.2)
				)
				(gr_arc
					(start 1.255279 0.431435)
					(mid 0.152481 -0.169693)
					(end -0.436309 -1.279127)
					(width 0.2)
				)
				(gr_arc
					(start 1.253811 0.524161)
					(mid 0.087542 -0.105784)
					(end -0.529126 -1.279127)
					(width 0.2)
				)
				(gr_arc
					(start 1.275473 0.621136)
					(mid 0.0309 -0.033527)
					(end -0.621807 -1.279127)
					(width 0.2)
				)
				(gr_arc
					(start 1.263664 0.711602)
					(mid -0.037759 0.026651)
					(end -0.71437 -1.279127)
					(width 0.2)
				)
				(gr_arc
					(start 1.253435 0.802342)
					(mid -0.105837 0.087395)
					(end -0.806826 -1.279127)
					(width 0.2)
				)
				(gr_arc
					(start 1.267475 0.897258)
					(mid -0.165236 0.156885)
					(end -0.899187 -1.279127)
					(width 0.2)
				)
				(gr_arc
					(start 1.270645 0.990112)
					(mid -0.228522 0.222449)
					(end -0.991463 -1.279127)
					(width 0.2)
				)
				(gr_arc
					(start 1.266278 1.081674)
					(mid -0.294507 0.285313)
					(end -1.083663 -1.279127)
					(width 0.2)
				)
				(gr_line
					(start 1.279127 0.250195)
					(end 1.279127 1.083663)
					(width 0.2)
				)
				(gr_line
					(start -0.250195 -1.279127)
					(end -1.083663 -1.279127)
					(width 0.2)
				)
			)
		)
		(pad "" smd custom
			(at 1.7 1.7 270)
			(size 0.62 0.62)
			(layers "B.Paste")
			(thermal_bridge_angle 90)
			(options
				(clearance outline)
				(anchor circle)
			)
			(primitives
				(gr_arc
					(start 1.266786 0.24747)
					(mid 0.285453 -0.29439)
					(end -0.250195 -1.279127)
					(width 0.2)
				)
				(gr_arc
					(start 1.259603 0.339191)
					(mid 0.218448 -0.232561)
					(end -0.34334 -1.279127)
					(width 0.2)
				)
				(gr_arc
					(start 1.255279 0.431435)
					(mid 0.152481 -0.169693)
					(end -0.436309 -1.279127)
					(width 0.2)
				)
				(gr_arc
					(start 1.253811 0.524161)
					(mid 0.087542 -0.105784)
					(end -0.529126 -1.279127)
					(width 0.2)
				)
				(gr_arc
					(start 1.275473 0.621136)
					(mid 0.0309 -0.033527)
					(end -0.621807 -1.279127)
					(width 0.2)
				)
				(gr_arc
					(start 1.263664 0.711602)
					(mid -0.037759 0.026651)
					(end -0.71437 -1.279127)
					(width 0.2)
				)
				(gr_arc
					(start 1.253435 0.802342)
					(mid -0.105837 0.087395)
					(end -0.806826 -1.279127)
					(width 0.2)
				)
				(gr_arc
					(start 1.267475 0.897258)
					(mid -0.165236 0.156885)
					(end -0.899187 -1.279127)
					(width 0.2)
				)
				(gr_arc
					(start 1.270645 0.990112)
					(mid -0.228522 0.222449)
					(end -0.991463 -1.279127)
					(width 0.2)
				)
				(gr_arc
					(start 1.266278 1.081674)
					(mid -0.294507 0.285313)
					(end -1.083663 -1.279127)
					(width 0.2)
				)
				(gr_line
					(start 1.279127 0.250195)
					(end 1.279127 1.083663)
					(width 0.2)
				)
				(gr_line
					(start -0.250195 -1.279127)
					(end -1.083663 -1.279127)
					(width 0.2)
				)
			)
		)
		(pad "1" thru_hole circle
			(at 0 0 180)
			(size 6 6)
			(drill 3.7)
			(layers "*.Cu" "*.Mask")
			(remove_unused_layers no)
			(net 3 "GND")
			(pintype "passive")
		)
	)
	(footprint "antmicro-footprints:R_0402_1005Metric"
		(layer "B.Cu")
		(at 75.342962 136.0165)
		(descr "Resistor SMD 0402")
		(tags "resistor SMD 0402")
		(property "Reference" "R917"
			(at -3.835 0.38 0)
			(layer "B.SilkS")
			(effects
				(font
					(size 0.7 0.7)
					(thickness 0.15)
				)
				(justify right bottom mirror)
			)
		)
		(property "Value" "R_15k_0402"
			(at -1.011843 -1.772047 0)
			(layer "B.Fab")
			(effects
				(font
					(size 0.7 0.7)
					(thickness 0.15)
				)
				(justify right bottom mirror)
			)
		)
		(property "Datasheet" "https://www.bourns.com/docs/product-datasheets/cr.pdf"
			(at 0 0 0)
			(layer "B.Fab")
			(hide yes)
			(effects
				(font
					(size 1.27 1.27)
					(thickness 0.15)
				)
			)
		)
		(property "Manufacturer" "Bourns"
			(at 0 0 0)
			(unlocked yes)
			(layer "B.Fab")
			(hide yes)
			(effects
				(font
					(size 1 1)
					(thickness 0.15)
				)
				(justify mirror)
			)
		)
		(property "MPN" "CR0402-FX-1502GLF"
			(at 0 0 0)
			(unlocked yes)
			(layer "B.Fab")
			(hide yes)
			(effects
				(font
					(size 1 1)
					(thickness 0.15)
				)
				(justify mirror)
			)
		)
		(property "Val" "15k"
			(at 0 0 0)
			(unlocked yes)
			(layer "B.Fab")
			(hide yes)
			(effects
				(font
					(size 1 1)
					(thickness 0.15)
				)
				(justify mirror)
			)
		)
		(property "License" "Apache-2.0"
			(at 0 0 0)
			(unlocked yes)
			(layer "B.Fab")
			(hide yes)
			(effects
				(font
					(size 1 1)
					(thickness 0.15)
				)
				(justify mirror)
			)
		)
		(property "Author" "Antmicro"
			(at 0 0 0)
			(unlocked yes)
			(layer "B.Fab")
			(hide yes)
			(effects
				(font
					(size 1 1)
					(thickness 0.15)
				)
				(justify mirror)
			)
		)
		(property "Tolerance" "1%"
			(at 0 0 0)
			(unlocked yes)
			(layer "B.Fab")
			(hide yes)
			(effects
				(font
					(size 1 1)
					(thickness 0.15)
				)
				(justify mirror)
			)
		)
		(sheetname "/USB/")
		(sheetfile "usb.kicad_sch")
		(attr smd)
		(fp_rect
			(start -0.925 0.47)
			(end 0.925 -0.47)
			(stroke
				(width 0.05)
				(type default)
			)
			(fill no)
			(layer "B.CrtYd")
		)
		(fp_rect
			(start -0.5 0.25)
			(end 0.5 -0.25)
			(stroke
				(width 0.15)
				(type solid)
			)
			(fill no)
			(layer "B.Fab")
		)
		(fp_text user "${REFERENCE}"
			(at -0.95 -3.168 180)
			(layer "B.Fab")
			(effects
				(font
					(size 0.7 0.7)
					(thickness 0.15)
				)
				(justify left bottom mirror)
			)
		)
		(fp_text user "Author: Antmicro"
			(at -0.95 -4.169 180)
			(layer "B.Fab")
			(effects
				(font
					(size 0.7 0.7)
					(thickness 0.15)
				)
				(justify left bottom mirror)
			)
		)
		(fp_text user "License: Apache-2.0"
			(at -0.95 -5.169 180)
			(layer "B.Fab")
			(effects
				(font
					(size 0.7 0.7)
					(thickness 0.15)
				)
				(justify left bottom mirror)
			)
		)
		(pad "1" smd roundrect
			(at -0.48 0)
			(size 0.59 0.64)
			(layers "B.Cu" "B.Mask" "B.Paste")
			(roundrect_rratio 0.25)
			(net 3 "GND")
			(pintype "passive")
		)
		(pad "2" smd roundrect
			(at 0.48 0)
			(size 0.59 0.64)
			(layers "B.Cu" "B.Mask" "B.Paste")
			(roundrect_rratio 0.25)
			(net 29 "/USB/USBD_SVBUS")
			(pintype "passive")
		)
	)
	(footprint "antmicro-footprints:R_0603_1608Metric"
		(layer "B.Cu")
		(at 69.917962 159.1665)
		(descr "Resistor SMD 0603")
		(tags "resistor SMD 0603")
		(property "Reference" "R324"
			(at 1.29 0.37 0)
			(layer "B.SilkS")
			(effects
				(font
					(size 0.7 0.7)
					(thickness 0.15)
				)
				(justify right bottom mirror)
			)
		)
		(property "Value" "R_0R_22.4A_0603"
			(at 0 -1.6 0)
			(layer "B.Fab")
			(effects
				(font
					(size 0.7 0.7)
					(thickness 0.15)
				)
				(justify right bottom mirror)
			)
		)
		(property "Datasheet" "https://fscdn.rohm.com/en/products/databook/datasheet/passive/resistor/chip_resistor/pmr-jpw-e.pdf"
			(at 0 0 0)
			(layer "B.Fab")
			(hide yes)
			(effects
				(font
					(size 1.27 1.27)
					(thickness 0.15)
				)
			)
		)
		(property "Manufacturer" "ROHM Semiconductor"
			(at 0 0 0)
			(unlocked yes)
			(layer "B.Fab")
			(hide yes)
			(effects
				(font
					(size 1 1)
					(thickness 0.15)
				)
				(justify mirror)
			)
		)
		(property "MPN" "PMR03EZPJ000"
			(at 0 0 0)
			(unlocked yes)
			(layer "B.Fab")
			(hide yes)
			(effects
				(font
					(size 1 1)
					(thickness 0.15)
				)
				(justify mirror)
			)
		)
		(property "Val" "0R"
			(at 0 0 0)
			(unlocked yes)
			(layer "B.Fab")
			(hide yes)
			(effects
				(font
					(size 1 1)
					(thickness 0.15)
				)
				(justify mirror)
			)
		)
		(property "Author" "Antmicro"
			(at 0 0 0)
			(unlocked yes)
			(layer "B.Fab")
			(hide yes)
			(effects
				(font
					(size 1 1)
					(thickness 0.15)
				)
				(justify mirror)
			)
		)
		(property "License" "Apache-2.0"
			(at 0 0 0)
			(unlocked yes)
			(layer "B.Fab")
			(hide yes)
			(effects
				(font
					(size 1 1)
					(thickness 0.15)
				)
				(justify mirror)
			)
		)
		(property "Max. Curr." "22.4A"
			(at 0 0 0)
			(unlocked yes)
			(layer "B.Fab")
			(hide yes)
			(effects
				(font
					(size 1 1)
					(thickness 0.15)
				)
				(justify mirror)
			)
		)
		(property "Tolerance" "template_tolerance"
			(at 0 0 0)
			(unlocked yes)
			(layer "B.Fab")
			(hide yes)
			(effects
				(font
					(size 1 1)
					(thickness 0.15)
				)
				(justify mirror)
			)
		)
		(sheetname "/Supply/")
		(sheetfile "supply.kicad_sch")
		(attr smd)
		(fp_line
			(start -0.15 -0.4)
			(end 0.15 -0.4)
			(stroke
				(width 0.15)
				(type solid)
			)
			(layer "B.SilkS")
		)
		(fp_line
			(start -0.15 0.4)
			(end 0.15 0.4)
			(stroke
				(width 0.15)
				(type solid)
			)
			(layer "B.SilkS")
		)
		(fp_rect
			(start -1.25 0.65)
			(end 1.25 -0.65)
			(stroke
				(width 0.05)
				(type solid)
			)
			(fill no)
			(layer "B.CrtYd")
		)
		(fp_rect
			(start -0.8 0.4)
			(end 0.8 -0.4)
			(stroke
				(width 0.15)
				(type solid)
			)
			(fill no)
			(layer "B.Fab")
		)
		(fp_text user "Author: Antmicro"
			(at -1.25 -4.9 180)
			(layer "B.Fab")
			(effects
				(font
					(size 0.7 0.7)
					(thickness 0.15)
				)
				(justify left bottom mirror)
			)
		)
		(fp_text user "License: Apache-2.0"
			(at -1.25 -5.9 180)
			(layer "B.Fab")
			(effects
				(font
					(size 0.7 0.7)
					(thickness 0.15)
				)
				(justify left bottom mirror)
			)
		)
		(fp_text user "${REFERENCE}"
			(at -1.25 -3.898 180)
			(layer "B.Fab")
			(effects
				(font
					(size 0.7 0.7)
					(thickness 0.15)
				)
				(justify left bottom mirror)
			)
		)
		(pad "1" smd roundrect
			(at -0.7 0)
			(size 0.8 1)
			(layers "B.Cu" "B.Mask" "B.Paste")
			(roundrect_rratio 0.2)
			(net 77 "/Supply/OUT_5V")
			(pintype "passive")
		)
		(pad "2" smd roundrect
			(at 0.7 0)
			(size 0.8 1)
			(layers "B.Cu" "B.Mask" "B.Paste")
			(roundrect_rratio 0.2)
			(net 10 "+5V")
			(pintype "passive")
		)
	)
	(footprint "antmicro-footprints:R_0402_1005Metric"
		(layer "B.Cu")
		(at 118.892962 118.1415 90)
		(descr "Resistor SMD 0402")
		(tags "resistor SMD 0402")
		(property "Reference" "R502"
			(at -2.025 -0.585 90)
			(layer "B.SilkS")
			(effects
				(font
					(size 0.7 0.7)
					(thickness 0.15)
				)
				(justify right bottom mirror)
			)
		)
		(property "Value" "R_10k_0402"
			(at -1.011843 -1.772047 90)
			(layer "B.Fab")
			(effects
				(font
					(size 0.7 0.7)
					(thickness 0.15)
				)
				(justify right bottom mirror)
			)
		)
		(property "Datasheet" "https://www.bourns.com/docs/product-datasheets/cr.pdf"
			(at 0 0 90)
			(layer "B.Fab")
			(hide yes)
			(effects
				(font
					(size 1.27 1.27)
					(thickness 0.15)
				)
			)
		)
		(property "Manufacturer" "Bourns"
			(at 0 0 90)
			(unlocked yes)
			(layer "B.Fab")
			(hide yes)
			(effects
				(font
					(size 1 1)
					(thickness 0.15)
				)
				(justify mirror)
			)
		)
		(property "MPN" "CR0402-FX-1002GLF"
			(at 0 0 90)
			(unlocked yes)
			(layer "B.Fab")
			(hide yes)
			(effects
				(font
					(size 1 1)
					(thickness 0.15)
				)
				(justify mirror)
			)
		)
		(property "Val" "10k"
			(at 0 0 90)
			(unlocked yes)
			(layer "B.Fab")
			(hide yes)
			(effects
				(font
					(size 1 1)
					(thickness 0.15)
				)
				(justify mirror)
			)
		)
		(property "License" "Apache-2.0"
			(at 0 0 90)
			(unlocked yes)
			(layer "B.Fab")
			(hide yes)
			(effects
				(font
					(size 1 1)
					(thickness 0.15)
				)
				(justify mirror)
			)
		)
		(property "Author" "Antmicro"
			(at 0 0 90)
			(unlocked yes)
			(layer "B.Fab")
			(hide yes)
			(effects
				(font
					(size 1 1)
					(thickness 0.15)
				)
				(justify mirror)
			)
		)
		(property "Tolerance" "1%"
			(at 0 0 90)
			(unlocked yes)
			(layer "B.Fab")
			(hide yes)
			(effects
				(font
					(size 1 1)
					(thickness 0.15)
				)
				(justify mirror)
			)
		)
		(sheetname "/NVMe & microSD/")
		(sheetfile "nvme-micro-sd.kicad_sch")
		(attr smd)
		(fp_rect
			(start -0.925 0.47)
			(end 0.925 -0.47)
			(stroke
				(width 0.05)
				(type default)
			)
			(fill no)
			(layer "B.CrtYd")
		)
		(fp_rect
			(start -0.5 0.25)
			(end 0.5 -0.25)
			(stroke
				(width 0.15)
				(type solid)
			)
			(fill no)
			(layer "B.Fab")
		)
		(fp_text user "Author: Antmicro"
			(at -0.95 -4.169 270)
			(layer "B.Fab")
			(effects
				(font
					(size 0.7 0.7)
					(thickness 0.15)
				)
				(justify left bottom mirror)
			)
		)
		(fp_text user "License: Apache-2.0"
			(at -0.95 -5.169 270)
			(layer "B.Fab")
			(effects
				(font
					(size 0.7 0.7)
					(thickness 0.15)
				)
				(justify left bottom mirror)
			)
		)
		(fp_text user "${REFERENCE}"
			(at -0.95 -3.168 270)
			(layer "B.Fab")
			(effects
				(font
					(size 0.7 0.7)
					(thickness 0.15)
				)
				(justify left bottom mirror)
			)
		)
		(pad "1" smd roundrect
			(at -0.48 0 90)
			(size 0.59 0.64)
			(layers "B.Cu" "B.Mask" "B.Paste")
			(roundrect_rratio 0.25)
			(net 144 "/Compute module/NVMe.~{CLK_REQ}")
			(pintype "passive")
		)
		(pad "2" smd roundrect
			(at 0.48 0 90)
			(size 0.59 0.64)
			(layers "B.Cu" "B.Mask" "B.Paste")
			(roundrect_rratio 0.25)
			(net 65 "3V3_SSD")
			(pintype "passive")
		)
	)
	(footprint "antmicro-footprints:R_0402_1005Metric"
		(layer "B.Cu")
		(at 126.4 169.05 180)
		(descr "Resistor SMD 0402")
		(tags "resistor SMD 0402")
		(property "Reference" "R505"
			(at 1.01 -0.435 0)
			(layer "B.SilkS")
			(effects
				(font
					(size 0.7 0.7)
					(thickness 0.15)
				)
				(justify left bottom mirror)
			)
		)
		(property "Value" "R_470R_0402"
			(at -1.011843 -1.772047 0)
			(layer "B.Fab")
			(effects
				(font
					(size 0.7 0.7)
					(thickness 0.15)
				)
				(justify left bottom mirror)
			)
		)
		(property "Datasheet" "https://www.bourns.com/docs/product-datasheets/cr.pdf"
			(at 0 0 180)
			(layer "B.Fab")
			(hide yes)
			(effects
				(font
					(size 1.27 1.27)
					(thickness 0.15)
				)
			)
		)
		(property "Manufacturer" "Bourns"
			(at 0 0 180)
			(unlocked yes)
			(layer "B.Fab")
			(hide yes)
			(effects
				(font
					(size 1 1)
					(thickness 0.15)
				)
				(justify mirror)
			)
		)
		(property "MPN" "CR0402-FX-4700GLF"
			(at 0 0 180)
			(unlocked yes)
			(layer "B.Fab")
			(hide yes)
			(effects
				(font
					(size 1 1)
					(thickness 0.15)
				)
				(justify mirror)
			)
		)
		(property "Val" "470R"
			(at 0 0 180)
			(unlocked yes)
			(layer "B.Fab")
			(hide yes)
			(effects
				(font
					(size 1 1)
					(thickness 0.15)
				)
				(justify mirror)
			)
		)
		(property "License" "Apache-2.0"
			(at 0 0 180)
			(unlocked yes)
			(layer "B.Fab")
			(hide yes)
			(effects
				(font
					(size 1 1)
					(thickness 0.15)
				)
				(justify mirror)
			)
		)
		(property "Author" "Antmicro"
			(at 0 0 180)
			(unlocked yes)
			(layer "B.Fab")
			(hide yes)
			(effects
				(font
					(size 1 1)
					(thickness 0.15)
				)
				(justify mirror)
			)
		)
		(property "Tolerance" "1%"
			(at 0 0 180)
			(unlocked yes)
			(layer "B.Fab")
			(hide yes)
			(effects
				(font
					(size 1 1)
					(thickness 0.15)
				)
				(justify mirror)
			)
		)
		(sheetname "/NVMe & microSD/")
		(sheetfile "nvme-micro-sd.kicad_sch")
		(attr smd)
		(fp_rect
			(start -0.925 0.47)
			(end 0.925 -0.47)
			(stroke
				(width 0.05)
				(type default)
			)
			(fill no)
			(layer "B.CrtYd")
		)
		(fp_rect
			(start -0.5 0.25)
			(end 0.5 -0.25)
			(stroke
				(width 0.15)
				(type solid)
			)
			(fill no)
			(layer "B.Fab")
		)
		(fp_text user "${REFERENCE}"
			(at -0.95 -3.168 0)
			(layer "B.Fab")
			(effects
				(font
					(size 0.7 0.7)
					(thickness 0.15)
				)
				(justify left bottom mirror)
			)
		)
		(fp_text user "License: Apache-2.0"
			(at -0.95 -5.169 0)
			(layer "B.Fab")
			(effects
				(font
					(size 0.7 0.7)
					(thickness 0.15)
				)
				(justify left bottom mirror)
			)
		)
		(fp_text user "Author: Antmicro"
			(at -0.95 -4.169 0)
			(layer "B.Fab")
			(effects
				(font
					(size 0.7 0.7)
					(thickness 0.15)
				)
				(justify left bottom mirror)
			)
		)
		(pad "1" smd roundrect
			(at -0.48 0 180)
			(size 0.59 0.64)
			(layers "B.Cu" "B.Mask" "B.Paste")
			(roundrect_rratio 0.25)
			(net 263 "Net-(J502-CD2)")
			(pintype "passive")
		)
		(pad "2" smd roundrect
			(at 0.48 0 180)
			(size 0.59 0.64)
			(layers "B.Cu" "B.Mask" "B.Paste")
			(roundrect_rratio 0.25)
			(net 118 "/Compute module/SDIO.CD")
			(pintype "passive")
		)
	)
	(footprint "antmicro-footprints:R_0402_1005Metric"
		(layer "B.Cu")
		(at 90.377962 152.4165)
		(descr "Resistor SMD 0402")
		(tags "resistor SMD 0402")
		(property "Reference" "R237"
			(at -1.71 3.94 0)
			(layer "B.SilkS")
			(effects
				(font
					(size 0.7 0.7)
					(thickness 0.15)
				)
				(justify right bottom mirror)
			)
		)
		(property "Value" "R_10k_0402"
			(at -1.011843 -1.772047 0)
			(layer "B.Fab")
			(effects
				(font
					(size 0.7 0.7)
					(thickness 0.15)
				)
				(justify right bottom mirror)
			)
		)
		(property "Datasheet" "https://www.bourns.com/docs/product-datasheets/cr.pdf"
			(at 0 0 0)
			(layer "B.Fab")
			(hide yes)
			(effects
				(font
					(size 1.27 1.27)
					(thickness 0.15)
				)
			)
		)
		(property "MPN" "CR0402-FX-1002GLF"
			(at 0 0 0)
			(unlocked yes)
			(layer "B.Fab")
			(hide yes)
			(effects
				(font
					(size 1 1)
					(thickness 0.15)
				)
				(justify mirror)
			)
		)
		(property "Manufacturer" "Bourns"
			(at 0 0 0)
			(unlocked yes)
			(layer "B.Fab")
			(hide yes)
			(effects
				(font
					(size 1 1)
					(thickness 0.15)
				)
				(justify mirror)
			)
		)
		(property "License" "Apache-2.0"
			(at 0 0 0)
			(unlocked yes)
			(layer "B.Fab")
			(hide yes)
			(effects
				(font
					(size 1 1)
					(thickness 0.15)
				)
				(justify mirror)
			)
		)
		(property "Author" "Antmicro"
			(at 0 0 0)
			(unlocked yes)
			(layer "B.Fab")
			(hide yes)
			(effects
				(font
					(size 1 1)
					(thickness 0.15)
				)
				(justify mirror)
			)
		)
		(property "Val" "10k"
			(at 0 0 0)
			(unlocked yes)
			(layer "B.Fab")
			(hide yes)
			(effects
				(font
					(size 1 1)
					(thickness 0.15)
				)
				(justify mirror)
			)
		)
		(property "Tolerance" "1%"
			(at 0 0 0)
			(unlocked yes)
			(layer "B.Fab")
			(hide yes)
			(effects
				(font
					(size 1 1)
					(thickness 0.15)
				)
				(justify mirror)
			)
		)
		(sheetname "/Compute module/")
		(sheetfile "compute-module.kicad_sch")
		(attr smd)
		(fp_rect
			(start -0.925 0.47)
			(end 0.925 -0.47)
			(stroke
				(width 0.05)
				(type default)
			)
			(fill no)
			(layer "B.CrtYd")
		)
		(fp_rect
			(start -0.5 0.25)
			(end 0.5 -0.25)
			(stroke
				(width 0.15)
				(type solid)
			)
			(fill no)
			(layer "B.Fab")
		)
		(fp_text user "License: Apache-2.0"
			(at -0.95 -5.169 180)
			(layer "B.Fab")
			(effects
				(font
					(size 0.7 0.7)
					(thickness 0.15)
				)
				(justify left bottom mirror)
			)
		)
		(fp_text user "Author: Antmicro"
			(at -0.95 -4.169 180)
			(layer "B.Fab")
			(effects
				(font
					(size 0.7 0.7)
					(thickness 0.15)
				)
				(justify left bottom mirror)
			)
		)
		(fp_text user "${REFERENCE}"
			(at -0.95 -3.168 180)
			(layer "B.Fab")
			(effects
				(font
					(size 0.7 0.7)
					(thickness 0.15)
				)
				(justify left bottom mirror)
			)
		)
		(pad "1" smd roundrect
			(at -0.48 0)
			(size 0.59 0.64)
			(layers "B.Cu" "B.Mask" "B.Paste")
			(roundrect_rratio 0.25)
			(net 3 "GND")
			(pintype "passive")
		)
		(pad "2" smd roundrect
			(at 0.48 0)
			(size 0.59 0.64)
			(layers "B.Cu" "B.Mask" "B.Paste")
			(roundrect_rratio 0.25)
			(net 349 "Net-(U204-A0)")
			(pintype "passive")
		)
	)
	(footprint "antmicro-footprints:R_0402_1005Metric"
		(layer "B.Cu")
		(at 59.667962 161.8805 180)
		(descr "Resistor SMD 0402")
		(tags "resistor SMD 0402")
		(property "Reference" "R305"
			(at -1.52 0.414 0)
			(layer "B.SilkS")
			(effects
				(font
					(size 0.7 0.7)
					(thickness 0.15)
				)
				(justify left bottom mirror)
			)
		)
		(property "Value" "R_470k_0402"
			(at -1.011843 -1.772047 0)
			(layer "B.Fab")
			(effects
				(font
					(size 0.7 0.7)
					(thickness 0.15)
				)
				(justify left bottom mirror)
			)
		)
		(property "Datasheet" "https://www.bourns.com/docs/product-datasheets/cr.pdf"
			(at 0 0 180)
			(layer "B.Fab")
			(hide yes)
			(effects
				(font
					(size 1.27 1.27)
					(thickness 0.15)
				)
			)
		)
		(property "MPN" "CR0402-FX-4703GLF"
			(at 0 0 180)
			(unlocked yes)
			(layer "B.Fab")
			(hide yes)
			(effects
				(font
					(size 1 1)
					(thickness 0.15)
				)
				(justify mirror)
			)
		)
		(property "Manufacturer" "Bourns"
			(at 0 0 180)
			(unlocked yes)
			(layer "B.Fab")
			(hide yes)
			(effects
				(font
					(size 1 1)
					(thickness 0.15)
				)
				(justify mirror)
			)
		)
		(property "License" "Apache-2.0"
			(at 0 0 180)
			(unlocked yes)
			(layer "B.Fab")
			(hide yes)
			(effects
				(font
					(size 1 1)
					(thickness 0.15)
				)
				(justify mirror)
			)
		)
		(property "Author" "Antmicro"
			(at 0 0 180)
			(unlocked yes)
			(layer "B.Fab")
			(hide yes)
			(effects
				(font
					(size 1 1)
					(thickness 0.15)
				)
				(justify mirror)
			)
		)
		(property "Val" "470k"
			(at 0 0 180)
			(unlocked yes)
			(layer "B.Fab")
			(hide yes)
			(effects
				(font
					(size 1 1)
					(thickness 0.15)
				)
				(justify mirror)
			)
		)
		(property "Tolerance" "1%"
			(at 0 0 180)
			(unlocked yes)
			(layer "B.Fab")
			(hide yes)
			(effects
				(font
					(size 1 1)
					(thickness 0.15)
				)
				(justify mirror)
			)
		)
		(sheetname "/Supply/")
		(sheetfile "supply.kicad_sch")
		(attr smd)
		(fp_rect
			(start -0.925 0.47)
			(end 0.925 -0.47)
			(stroke
				(width 0.05)
				(type default)
			)
			(fill no)
			(layer "B.CrtYd")
		)
		(fp_rect
			(start -0.5 0.25)
			(end 0.5 -0.25)
			(stroke
				(width 0.15)
				(type solid)
			)
			(fill no)
			(layer "B.Fab")
		)
		(fp_text user "Author: Antmicro"
			(at -0.95 -4.169 0)
			(layer "B.Fab")
			(effects
				(font
					(size 0.7 0.7)
					(thickness 0.15)
				)
				(justify left bottom mirror)
			)
		)
		(fp_text user "License: Apache-2.0"
			(at -0.95 -5.169 0)
			(layer "B.Fab")
			(effects
				(font
					(size 0.7 0.7)
					(thickness 0.15)
				)
				(justify left bottom mirror)
			)
		)
		(fp_text user "${REFERENCE}"
			(at -0.95 -3.168 0)
			(layer "B.Fab")
			(effects
				(font
					(size 0.7 0.7)
					(thickness 0.15)
				)
				(justify left bottom mirror)
			)
		)
		(pad "1" smd roundrect
			(at -0.48 0 180)
			(size 0.59 0.64)
			(layers "B.Cu" "B.Mask" "B.Paste")
			(roundrect_rratio 0.25)
			(net 3 "GND")
			(pintype "passive")
		)
		(pad "2" smd roundrect
			(at 0.48 0 180)
			(size 0.59 0.64)
			(layers "B.Cu" "B.Mask" "B.Paste")
			(roundrect_rratio 0.25)
			(net 335 "Net-(Q302-BIAS)")
			(pintype "passive")
		)
	)
	(footprint "antmicro-footprints:R_0402_1005Metric"
		(layer "B.Cu")
		(at 52.516962 165.4145)
		(descr "Resistor SMD 0402")
		(tags "resistor SMD 0402")
		(property "Reference" "R303"
			(at 0.201 1.262 0)
			(layer "B.SilkS")
			(effects
				(font
					(size 0.7 0.7)
					(thickness 0.15)
				)
				(justify right bottom mirror)
			)
		)
		(property "Value" "R_33k_0402"
			(at -1.011843 -1.772047 0)
			(layer "B.Fab")
			(effects
				(font
					(size 0.7 0.7)
					(thickness 0.15)
				)
				(justify right bottom mirror)
			)
		)
		(property "Datasheet" "https://www.bourns.com/docs/product-datasheets/cr.pdf"
			(at 0 0 0)
			(layer "B.Fab")
			(hide yes)
			(effects
				(font
					(size 1.27 1.27)
					(thickness 0.15)
				)
			)
		)
		(property "MPN" "CR0402-FX-3302GLF"
			(at 0 0 0)
			(unlocked yes)
			(layer "B.Fab")
			(hide yes)
			(effects
				(font
					(size 1 1)
					(thickness 0.15)
				)
				(justify mirror)
			)
		)
		(property "Manufacturer" "Bourns"
			(at 0 0 0)
			(unlocked yes)
			(layer "B.Fab")
			(hide yes)
			(effects
				(font
					(size 1 1)
					(thickness 0.15)
				)
				(justify mirror)
			)
		)
		(property "License" "Apache-2.0"
			(at 0 0 0)
			(unlocked yes)
			(layer "B.Fab")
			(hide yes)
			(effects
				(font
					(size 1 1)
					(thickness 0.15)
				)
				(justify mirror)
			)
		)
		(property "Author" "Antmicro"
			(at 0 0 0)
			(unlocked yes)
			(layer "B.Fab")
			(hide yes)
			(effects
				(font
					(size 1 1)
					(thickness 0.15)
				)
				(justify mirror)
			)
		)
		(property "Val" "33k"
			(at 0 0 0)
			(unlocked yes)
			(layer "B.Fab")
			(hide yes)
			(effects
				(font
					(size 1 1)
					(thickness 0.15)
				)
				(justify mirror)
			)
		)
		(property "Tolerance" "1%"
			(at 0 0 0)
			(unlocked yes)
			(layer "B.Fab")
			(hide yes)
			(effects
				(font
					(size 1 1)
					(thickness 0.15)
				)
				(justify mirror)
			)
		)
		(sheetname "/Supply/")
		(sheetfile "supply.kicad_sch")
		(attr smd)
		(fp_rect
			(start -0.925 0.47)
			(end 0.925 -0.47)
			(stroke
				(width 0.05)
				(type default)
			)
			(fill no)
			(layer "B.CrtYd")
		)
		(fp_rect
			(start -0.5 0.25)
			(end 0.5 -0.25)
			(stroke
				(width 0.15)
				(type solid)
			)
			(fill no)
			(layer "B.Fab")
		)
		(fp_text user "License: Apache-2.0"
			(at -0.95 -5.169 180)
			(layer "B.Fab")
			(effects
				(font
					(size 0.7 0.7)
					(thickness 0.15)
				)
				(justify left bottom mirror)
			)
		)
		(fp_text user "Author: Antmicro"
			(at -0.95 -4.169 180)
			(layer "B.Fab")
			(effects
				(font
					(size 0.7 0.7)
					(thickness 0.15)
				)
				(justify left bottom mirror)
			)
		)
		(fp_text user "${REFERENCE}"
			(at -0.95 -3.168 180)
			(layer "B.Fab")
			(effects
				(font
					(size 0.7 0.7)
					(thickness 0.15)
				)
				(justify left bottom mirror)
			)
		)
		(pad "1" smd roundrect
			(at -0.48 0)
			(size 0.59 0.64)
			(layers "B.Cu" "B.Mask" "B.Paste")
			(roundrect_rratio 0.25)
			(net 3 "GND")
			(pintype "passive")
		)
		(pad "2" smd roundrect
			(at 0.48 0)
			(size 0.59 0.64)
			(layers "B.Cu" "B.Mask" "B.Paste")
			(roundrect_rratio 0.25)
			(net 336 "Net-(Q303-REF)")
			(pintype "passive")
		)
	)
	(footprint "antmicro-footprints:R_0402_1005Metric"
		(layer "B.Cu")
		(at 92.067962 129.3415 -90)
		(descr "Resistor SMD 0402")
		(tags "resistor SMD 0402")
		(property "Reference" "R919"
			(at -1.955 -1.42 90)
			(layer "B.SilkS")
			(effects
				(font
					(size 0.7 0.7)
					(thickness 0.15)
				)
				(justify left bottom mirror)
			)
		)
		(property "Value" "R_0R_0402"
			(at -1.011843 -1.772047 90)
			(layer "B.Fab")
			(effects
				(font
					(size 0.7 0.7)
					(thickness 0.15)
				)
				(justify left bottom mirror)
			)
		)
		(property "Datasheet" "https://industrial.panasonic.com/cdbs/www-data/pdf/RDA0000/AOA0000C301.pdf"
			(at 0 0 270)
			(layer "B.Fab")
			(hide yes)
			(effects
				(font
					(size 1.27 1.27)
					(thickness 0.15)
				)
			)
		)
		(property "Manufacturer" "Panasonic"
			(at 0 0 270)
			(unlocked yes)
			(layer "B.Fab")
			(hide yes)
			(effects
				(font
					(size 1 1)
					(thickness 0.15)
				)
				(justify mirror)
			)
		)
		(property "MPN" "ERJ2GE0R00X"
			(at 0 0 270)
			(unlocked yes)
			(layer "B.Fab")
			(hide yes)
			(effects
				(font
					(size 1 1)
					(thickness 0.15)
				)
				(justify mirror)
			)
		)
		(property "Val" "0R"
			(at 0 0 270)
			(unlocked yes)
			(layer "B.Fab")
			(hide yes)
			(effects
				(font
					(size 1 1)
					(thickness 0.15)
				)
				(justify mirror)
			)
		)
		(property "License" "Apache-2.0"
			(at 0 0 270)
			(unlocked yes)
			(layer "B.Fab")
			(hide yes)
			(effects
				(font
					(size 1 1)
					(thickness 0.15)
				)
				(justify mirror)
			)
		)
		(property "Author" "Antmicro"
			(at 0 0 270)
			(unlocked yes)
			(layer "B.Fab")
			(hide yes)
			(effects
				(font
					(size 1 1)
					(thickness 0.15)
				)
				(justify mirror)
			)
		)
		(property "Tolerance" "~"
			(at 0 0 270)
			(unlocked yes)
			(layer "B.Fab")
			(hide yes)
			(effects
				(font
					(size 1 1)
					(thickness 0.15)
				)
				(justify mirror)
			)
		)
		(property "Current" "1A"
			(at 0 0 270)
			(unlocked yes)
			(layer "B.Fab")
			(hide yes)
			(effects
				(font
					(size 1 1)
					(thickness 0.15)
				)
				(justify mirror)
			)
		)
		(sheetname "/USB/")
		(sheetfile "usb.kicad_sch")
		(attr smd)
		(fp_rect
			(start -0.925 0.47)
			(end 0.925 -0.47)
			(stroke
				(width 0.05)
				(type default)
			)
			(fill no)
			(layer "B.CrtYd")
		)
		(fp_rect
			(start -0.5 0.25)
			(end 0.5 -0.25)
			(stroke
				(width 0.15)
				(type solid)
			)
			(fill no)
			(layer "B.Fab")
		)
		(fp_text user "License: Apache-2.0"
			(at -0.95 -5.169 90)
			(layer "B.Fab")
			(effects
				(font
					(size 0.7 0.7)
					(thickness 0.15)
				)
				(justify left bottom mirror)
			)
		)
		(fp_text user "${REFERENCE}"
			(at -0.95 -3.168 90)
			(layer "B.Fab")
			(effects
				(font
					(size 0.7 0.7)
					(thickness 0.15)
				)
				(justify left bottom mirror)
			)
		)
		(fp_text user "Author: Antmicro"
			(at -0.95 -4.169 90)
			(layer "B.Fab")
			(effects
				(font
					(size 0.7 0.7)
					(thickness 0.15)
				)
				(justify left bottom mirror)
			)
		)
		(pad "1" smd roundrect
			(at -0.48 0 270)
			(size 0.59 0.64)
			(layers "B.Cu" "B.Mask" "B.Paste")
			(roundrect_rratio 0.25)
			(net 113 "/USB/OUT_FTDI")
			(pintype "passive")
		)
		(pad "2" smd roundrect
			(at 0.48 0 270)
			(size 0.59 0.64)
			(layers "B.Cu" "B.Mask" "B.Paste")
			(roundrect_rratio 0.25)
			(net 27 "/USB/USB_3V3")
			(pintype "passive")
		)
	)
	(footprint "antmicro-footprints:SOT-363"
		(layer "B.Cu")
		(at 45.817962 163.6305)
		(property "Reference" "Q301"
			(at 2.135 1.846 90)
			(layer "B.SilkS")
			(effects
				(font
					(size 0.7 0.7)
					(thickness 0.15)
				)
				(justify right bottom mirror)
			)
		)
		(property "Value" "DZDH0401DW"
			(at 0 -2.2 0)
			(layer "B.Fab")
			(effects
				(font
					(size 0.7 0.7)
					(thickness 0.15)
				)
				(justify right bottom mirror)
			)
		)
		(property "Datasheet" "https://www.mouser.com/datasheet/2/115/DIOD_S_A0011803041_1-2543705.pdf"
			(at 0 0 0)
			(layer "B.Fab")
			(hide yes)
			(effects
				(font
					(size 1.27 1.27)
					(thickness 0.15)
				)
			)
		)
		(property "MPN" "DZDH0401DW"
			(at 0 0 0)
			(unlocked yes)
			(layer "B.Fab")
			(hide yes)
			(effects
				(font
					(size 1 1)
					(thickness 0.15)
				)
				(justify mirror)
			)
		)
		(property "Manufacturer" "Diodes Incorporated"
			(at 0 0 0)
			(unlocked yes)
			(layer "B.Fab")
			(hide yes)
			(effects
				(font
					(size 1 1)
					(thickness 0.15)
				)
				(justify mirror)
			)
		)
		(property "Author" "Antmicro"
			(at 0 0 0)
			(unlocked yes)
			(layer "B.Fab")
			(hide yes)
			(effects
				(font
					(size 1 1)
					(thickness 0.15)
				)
				(justify mirror)
			)
		)
		(property "License" "Apache-2.0"
			(at 0 0 0)
			(unlocked yes)
			(layer "B.Fab")
			(hide yes)
			(effects
				(font
					(size 1 1)
					(thickness 0.15)
				)
				(justify mirror)
			)
		)
		(sheetname "/Supply/")
		(sheetfile "supply.kicad_sch")
		(attr smd)
		(fp_line
			(start -0.8 -1.223)
			(end 0.803 -1.223)
			(stroke
				(width 0.15)
				(type solid)
			)
			(layer "B.SilkS")
		)
		(fp_line
			(start -0.8 -1.146)
			(end -0.8 -1.223)
			(stroke
				(width 0.15)
				(type solid)
			)
			(layer "B.SilkS")
		)
		(fp_line
			(start -0.72 1.153)
			(end -0.72 1.228)
			(stroke
				(width 0.15)
				(type solid)
			)
			(layer "B.SilkS")
		)
		(fp_line
			(start 0.803 -1.146)
			(end 0.803 -1.223)
			(stroke
				(width 0.15)
				(type solid)
			)
			(layer "B.SilkS")
		)
		(fp_line
			(start 0.803 1.153)
			(end 0.803 1.228)
			(stroke
				(width 0.15)
				(type solid)
			)
			(layer "B.SilkS")
		)
		(fp_line
			(start 0.803 1.228)
			(end -0.72 1.228)
			(stroke
				(width 0.15)
				(type solid)
			)
			(layer "B.SilkS")
		)
		(fp_circle
			(center -0.978102 1.2)
			(end -0.928102 1.2)
			(stroke
				(width 0.15)
				(type solid)
			)
			(fill yes)
			(layer "B.SilkS")
		)
		(fp_rect
			(start 1.3 1.3)
			(end -1.3 -1.3)
			(stroke
				(width 0.05)
				(type solid)
			)
			(fill no)
			(layer "B.CrtYd")
		)
		(fp_line
			(start -0.1 1.1)
			(end -0.68 0.52)
			(stroke
				(width 0.15)
				(type solid)
			)
			(layer "B.Fab")
		)
		(fp_rect
			(start 0.68 -1.1)
			(end -0.68 1.1)
			(stroke
				(width 0.15)
				(type solid)
			)
			(fill no)
			(layer "B.Fab")
		)
		(fp_text user "Author: Antmicro"
			(at -1.3 -6.4 180)
			(layer "B.Fab")
			(effects
				(font
					(size 0.7 0.7)
					(thickness 0.15)
				)
				(justify left bottom mirror)
			)
		)
		(fp_text user "License: Apache-2.0"
			(at -1.3 -5.2 180)
			(layer "B.Fab")
			(effects
				(font
					(size 0.7 0.7)
					(thickness 0.15)
				)
				(justify left bottom mirror)
			)
		)
		(fp_text user "${REFERENCE}"
			(at -1.3 -4 180)
			(layer "B.Fab")
			(effects
				(font
					(size 0.7 0.7)
					(thickness 0.15)
				)
				(justify left bottom mirror)
			)
		)
		(pad "1" smd custom
			(at -0.948 0.752 90)
			(size 0.6 0.6)
			(layers "B.Cu" "B.Mask" "B.Paste")
			(net 492 "unconnected-(Q301-NC-Pad1)")
			(pinfunction "NC")
			(pintype "no_connect")
			(options
				(clearance outline)
				(anchor rect)
			)
			(primitives)
		)
		(pad "2" smd rect
			(at -0.948 0.002 90)
			(size 0.4 0.6)
			(layers "B.Cu" "B.Mask" "B.Paste")
			(net 332 "Net-(Q301-REF)")
			(pinfunction "REF")
			(pintype "input")
		)
		(pad "3" smd custom
			(at -0.948 -0.745 90)
			(size 0.6 0.6)
			(layers "B.Cu" "B.Mask" "B.Paste")
			(net 333 "Net-(Q301-BIAS)")
			(pinfunction "BIAS")
			(pintype "output")
			(options
				(clearance outline)
				(anchor rect)
			)
			(primitives)
		)
		(pad "4" smd custom
			(at 0.951 -0.745 90)
			(size 0.6 0.6)
			(layers "B.Cu" "B.Mask" "B.Paste")
			(net 21 "/Supply/VCC_IN")
			(pinfunction "S")
			(pintype "power_in")
			(options
				(clearance outline)
				(anchor rect)
			)
			(primitives)
		)
		(pad "5" smd rect
			(at 0.951 0.002 90)
			(size 0.4 0.6)
			(layers "B.Cu" "B.Mask" "B.Paste")
			(net 493 "unconnected-(Q301-NC-Pad5)")
			(pinfunction "NC")
			(pintype "no_connect")
		)
		(pad "6" smd custom
			(at 0.951 0.752 90)
			(size 0.6 0.6)
			(layers "B.Cu" "B.Mask" "B.Paste")
			(net 472 "Net-(D301-C)")
			(pinfunction "D")
			(pintype "power_in")
			(options
				(clearance outline)
				(anchor rect)
			)
			(primitives)
		)
	)
	(footprint "antmicro-footprints:C_0402_1005Metric"
		(layer "B.Cu")
		(at 99.442962 174.7915 90)
		(descr "Capacitor SMD 0402")
		(tags "capacitor SMD 0402")
		(property "Reference" "C703"
			(at -0.915 6.505 90)
			(layer "B.SilkS")
			(effects
				(font
					(size 0.7 0.7)
					(thickness 0.15)
				)
				(justify right bottom mirror)
			)
		)
		(property "Value" "C_10u_0402"
			(at -1.022927 -2.155213 90)
			(layer "B.Fab")
			(effects
				(font
					(size 0.7 0.7)
					(thickness 0.15)
				)
				(justify right bottom mirror)
			)
		)
		(property "Datasheet" "https://www.yageo.com/en/Chart/Download/pdf/CC0402MRX5R5BB106"
			(at 0 0 90)
			(layer "B.Fab")
			(hide yes)
			(effects
				(font
					(size 1.27 1.27)
					(thickness 0.15)
				)
			)
		)
		(property "MPN" "CC0402MRX5R5BB106"
			(at 0 0 90)
			(unlocked yes)
			(layer "B.Fab")
			(hide yes)
			(effects
				(font
					(size 1 1)
					(thickness 0.15)
				)
				(justify mirror)
			)
		)
		(property "Manufacturer" "YAGEO"
			(at 0 0 90)
			(unlocked yes)
			(layer "B.Fab")
			(hide yes)
			(effects
				(font
					(size 1 1)
					(thickness 0.15)
				)
				(justify mirror)
			)
		)
		(property "License" "Apache-2.0"
			(at 0 0 90)
			(unlocked yes)
			(layer "B.Fab")
			(hide yes)
			(effects
				(font
					(size 1 1)
					(thickness 0.15)
				)
				(justify mirror)
			)
		)
		(property "Author" "Antmicro"
			(at 0 0 90)
			(unlocked yes)
			(layer "B.Fab")
			(hide yes)
			(effects
				(font
					(size 1 1)
					(thickness 0.15)
				)
				(justify mirror)
			)
		)
		(property "Val" "10u"
			(at 0 0 90)
			(unlocked yes)
			(layer "B.Fab")
			(hide yes)
			(effects
				(font
					(size 1 1)
					(thickness 0.15)
				)
				(justify mirror)
			)
		)
		(property "Voltage" ""
			(at 0 0 90)
			(unlocked yes)
			(layer "B.Fab")
			(hide yes)
			(effects
				(font
					(size 1 1)
					(thickness 0.15)
				)
				(justify mirror)
			)
		)
		(property "Dielectric" ""
			(at 0 0 90)
			(unlocked yes)
			(layer "B.Fab")
			(hide yes)
			(effects
				(font
					(size 1 1)
					(thickness 0.15)
				)
				(justify mirror)
			)
		)
		(sheetname "/Display/")
		(sheetfile "display.kicad_sch")
		(attr smd)
		(fp_rect
			(start -0.925 0.47)
			(end 0.925 -0.47)
			(stroke
				(width 0.05)
				(type default)
			)
			(fill no)
			(layer "B.CrtYd")
		)
		(fp_line
			(start 0.504 -0.248)
			(end -0.494 -0.248)
			(stroke
				(width 0.15)
				(type solid)
			)
			(layer "B.Fab")
		)
		(fp_line
			(start -0.494 -0.248)
			(end -0.494 0.25)
			(stroke
				(width 0.15)
				(type solid)
			)
			(layer "B.Fab")
		)
		(fp_line
			(start 0.504 0.25)
			(end 0.504 -0.248)
			(stroke
				(width 0.15)
				(type solid)
			)
			(layer "B.Fab")
		)
		(fp_line
			(start -0.494 0.25)
			(end 0.504 0.25)
			(stroke
				(width 0.15)
				(type solid)
			)
			(layer "B.Fab")
		)
		(fp_text user "Author: Antmicro"
			(at -0.939 -3.399 270)
			(layer "B.Fab")
			(effects
				(font
					(size 0.7 0.7)
					(thickness 0.15)
				)
				(justify left bottom mirror)
			)
		)
		(fp_text user "License: Apache-2.0"
			(at -0.939 -5.799 270)
			(layer "B.Fab")
			(effects
				(font
					(size 0.7 0.7)
					(thickness 0.15)
				)
				(justify left bottom mirror)
			)
		)
		(fp_text user "${REFERENCE}"
			(at -0.939 -4.599 270)
			(layer "B.Fab")
			(effects
				(font
					(size 0.7 0.7)
					(thickness 0.15)
				)
				(justify left bottom mirror)
			)
		)
		(pad "1" smd roundrect
			(at -0.48 0 90)
			(size 0.59 0.64)
			(layers "B.Cu" "B.Mask" "B.Paste")
			(roundrect_rratio 0.25)
			(net 3 "GND")
			(pintype "passive")
		)
		(pad "2" smd roundrect
			(at 0.48 0 90)
			(size 0.59 0.64)
			(layers "B.Cu" "B.Mask" "B.Paste")
			(roundrect_rratio 0.25)
			(net 9 "+3V3")
			(pintype "passive")
		)
	)
	(footprint "antmicro-footprints:SOD-523"
		(layer "B.Cu")
		(at 113.592962 117.2665 180)
		(property "Reference" "D710"
			(at -2.245 -5.86 0)
			(layer "B.SilkS")
			(effects
				(font
					(size 0.7 0.7)
					(thickness 0.15)
				)
				(justify left bottom mirror)
			)
		)
		(property "Value" "RB521S30T1G"
			(at 0 -1.499 0)
			(layer "B.Fab")
			(effects
				(font
					(size 0.7 0.7)
					(thickness 0.15)
				)
				(justify left bottom mirror)
			)
		)
		(property "Datasheet" "https://www.onsemi.com/pdf/datasheet/rb521s30t1-d.pdf"
			(at 0 0 180)
			(layer "B.Fab")
			(hide yes)
			(effects
				(font
					(size 1.27 1.27)
					(thickness 0.15)
				)
			)
		)
		(property "MPN" "RB521S30T1G"
			(at 0 0 180)
			(unlocked yes)
			(layer "B.Fab")
			(hide yes)
			(effects
				(font
					(size 1 1)
					(thickness 0.15)
				)
				(justify mirror)
			)
		)
		(property "Manufacturer" "ON Semiconductor"
			(at 0 0 180)
			(unlocked yes)
			(layer "B.Fab")
			(hide yes)
			(effects
				(font
					(size 1 1)
					(thickness 0.15)
				)
				(justify mirror)
			)
		)
		(property "Author" "Antmicro"
			(at 0 0 180)
			(unlocked yes)
			(layer "B.Fab")
			(hide yes)
			(effects
				(font
					(size 1 1)
					(thickness 0.15)
				)
				(justify mirror)
			)
		)
		(property "License" "Apache-2.0"
			(at 0 0 180)
			(unlocked yes)
			(layer "B.Fab")
			(hide yes)
			(effects
				(font
					(size 1 1)
					(thickness 0.15)
				)
				(justify mirror)
			)
		)
		(sheetname "/Display/")
		(sheetfile "display.kicad_sch")
		(attr smd)
		(fp_line
			(start -0.35 0.5)
			(end -0.35 -0.5)
			(stroke
				(width 0.15)
				(type solid)
			)
			(layer "B.SilkS")
		)
		(fp_rect
			(start -1 0.6)
			(end 1 -0.6)
			(stroke
				(width 0.05)
				(type solid)
			)
			(fill no)
			(layer "B.CrtYd")
		)
		(fp_line
			(start 0.65 0.425)
			(end 0.65 -0.423)
			(stroke
				(width 0.15)
				(type solid)
			)
			(layer "B.Fab")
		)
		(fp_line
			(start -0.35 0.4)
			(end -0.35 -0.4)
			(stroke
				(width 0.15)
				(type solid)
			)
			(layer "B.Fab")
		)
		(fp_line
			(start -0.652 0.425)
			(end 0.65 0.425)
			(stroke
				(width 0.15)
				(type solid)
			)
			(layer "B.Fab")
		)
		(fp_line
			(start -0.652 -0.423)
			(end 0.65 -0.423)
			(stroke
				(width 0.15)
				(type solid)
			)
			(layer "B.Fab")
		)
		(fp_line
			(start -0.652 -0.423)
			(end -0.652 0.425)
			(stroke
				(width 0.15)
				(type solid)
			)
			(layer "B.Fab")
		)
		(fp_text user "Author: Antmicro"
			(at -1.276 -4.7 0)
			(layer "B.Fab")
			(effects
				(font
					(size 0.7 0.7)
					(thickness 0.15)
				)
				(justify left bottom mirror)
			)
		)
		(fp_text user "${REFERENCE}"
			(at -1.276 -3.499 0)
			(layer "B.Fab")
			(effects
				(font
					(size 0.7 0.7)
					(thickness 0.15)
				)
				(justify left bottom mirror)
			)
		)
		(fp_text user "License: Apache-2.0"
			(at -1.276 -5.9 0)
			(layer "B.Fab")
			(effects
				(font
					(size 0.7 0.7)
					(thickness 0.15)
				)
				(justify left bottom mirror)
			)
		)
		(pad "1" smd roundrect
			(at -0.701 0 180)
			(size 0.5 0.6)
			(layers "B.Cu" "B.Mask" "B.Paste")
			(roundrect_rratio 0.25)
			(net 119 "Net-(D710-C)")
			(pinfunction "C")
			(pintype "passive")
		)
		(pad "2" smd roundrect
			(at 0.699 0 180)
			(size 0.5 0.6)
			(layers "B.Cu" "B.Mask" "B.Paste")
			(roundrect_rratio 0.25)
			(net 481 "Net-(D710-A)")
			(pinfunction "A")
			(pintype "passive")
		)
	)
	(footprint "antmicro-footprints:Nexperia_DFN-10_2.5x1mm_P0.5mm"
		(layer "B.Cu")
		(at 126.467962 164.0915 90)
		(property "Reference" "D502"
			(at -1.195 -1.78 90)
			(layer "B.SilkS")
			(effects
				(font
					(size 0.7 0.7)
					(thickness 0.15)
				)
				(justify right bottom mirror)
			)
		)
		(property "Value" "PUSB3F96X_PASS"
			(at -0.016 -1.705 90)
			(layer "B.Fab")
			(effects
				(font
					(size 0.7 0.7)
					(thickness 0.15)
				)
				(justify right bottom mirror)
			)
		)
		(property "Datasheet" "https://mouser.com/datasheet/2/916/PUSB3F96-1600324.pdf"
			(at 0 0 90)
			(layer "B.Fab")
			(hide yes)
			(effects
				(font
					(size 1.27 1.27)
					(thickness 0.15)
				)
			)
		)
		(property "Manufacturer" "Nexperia"
			(at 0 0 90)
			(unlocked yes)
			(layer "B.Fab")
			(hide yes)
			(effects
				(font
					(size 1 1)
					(thickness 0.15)
				)
				(justify mirror)
			)
		)
		(property "MPN" "PUSB3F96X"
			(at 0 0 90)
			(unlocked yes)
			(layer "B.Fab")
			(hide yes)
			(effects
				(font
					(size 1 1)
					(thickness 0.15)
				)
				(justify mirror)
			)
		)
		(property "Author" "Antmicro"
			(at 0 0 90)
			(unlocked yes)
			(layer "B.Fab")
			(hide yes)
			(effects
				(font
					(size 1 1)
					(thickness 0.15)
				)
				(justify mirror)
			)
		)
		(property "License" "Apache-2.0"
			(at 0 0 90)
			(unlocked yes)
			(layer "B.Fab")
			(hide yes)
			(effects
				(font
					(size 1 1)
					(thickness 0.15)
				)
				(justify mirror)
			)
		)
		(sheetname "/NVMe & microSD/")
		(sheetfile "nvme-micro-sd.kicad_sch")
		(attr smd)
		(fp_line
			(start 1.375 -0.4)
			(end 1.375 0.4)
			(stroke
				(width 0.15)
				(type solid)
			)
			(layer "B.SilkS")
		)
		(fp_line
			(start -1.375 0.4)
			(end -1.375 -0.4)
			(stroke
				(width 0.15)
				(type solid)
			)
			(layer "B.SilkS")
		)
		(fp_circle
			(center -1.4 -0.7)
			(end -1.349 -0.7)
			(stroke
				(width 0.15)
				(type solid)
			)
			(fill yes)
			(layer "B.SilkS")
		)
		(fp_rect
			(start -1.4 0.725)
			(end 1.4 -0.725)
			(stroke
				(width 0.05)
				(type solid)
			)
			(fill no)
			(layer "B.CrtYd")
		)
		(fp_line
			(start 1.25 -0.5)
			(end 1.25 0.5)
			(stroke
				(width 0.15)
				(type solid)
			)
			(layer "B.Fab")
		)
		(fp_line
			(start -0.9 -0.5)
			(end 1.25 -0.5)
			(stroke
				(width 0.15)
				(type solid)
			)
			(layer "B.Fab")
		)
		(fp_line
			(start -1.25 -0.15)
			(end -0.9 -0.5)
			(stroke
				(width 0.15)
				(type solid)
			)
			(layer "B.Fab")
		)
		(fp_line
			(start 1.25 0.5)
			(end -1.25 0.5)
			(stroke
				(width 0.15)
				(type solid)
			)
			(layer "B.Fab")
		)
		(fp_line
			(start -1.25 0.5)
			(end -1.25 -0.15)
			(stroke
				(width 0.15)
				(type solid)
			)
			(layer "B.Fab")
		)
		(fp_text user "${REFERENCE}"
			(at -1.367 -3.704 270)
			(layer "B.Fab")
			(effects
				(font
					(size 0.7 0.7)
					(thickness 0.15)
				)
				(justify left bottom mirror)
			)
		)
		(fp_text user "License: Apache-2.0"
			(at -1.367 -6.105 270)
			(layer "B.Fab")
			(effects
				(font
					(size 0.7 0.7)
					(thickness 0.15)
				)
				(justify left bottom mirror)
			)
		)
		(fp_text user "Author: Antmicro"
			(at -1.367 -4.905 270)
			(layer "B.Fab")
			(effects
				(font
					(size 0.7 0.7)
					(thickness 0.15)
				)
				(justify left bottom mirror)
			)
		)
		(pad "1" smd rect
			(at -1 -0.3875 90)
			(size 0.2 0.475)
			(layers "B.Cu" "B.Mask" "B.Paste")
			(net 3 "GND")
			(pinfunction "CH1")
			(pintype "passive")
			(solder_mask_margin 0.05)
		)
		(pad "2" smd rect
			(at -0.5 -0.3875 90)
			(size 0.2 0.475)
			(layers "B.Cu" "B.Mask" "B.Paste")
			(net 7 "/Compute module/SDIO.CLK")
			(pinfunction "CH2")
			(pintype "passive")
			(solder_mask_margin 0.05)
		)
		(pad "3" smd rect
			(at 0 -0.3875 90)
			(size 0.2 0.475)
			(layers "B.Cu" "B.Mask" "B.Paste")
			(net 3 "GND")
			(pinfunction "GND")
			(pintype "passive")
			(solder_mask_margin 0.05)
		)
		(pad "4" smd rect
			(at 0.5 -0.3875 90)
			(size 0.2 0.475)
			(layers "B.Cu" "B.Mask" "B.Paste")
			(net 6 "/Compute module/SDIO.D0")
			(pinfunction "CH3")
			(pintype "passive")
			(solder_mask_margin 0.05)
		)
		(pad "5" smd rect
			(at 1 -0.3875 90)
			(size 0.2 0.475)
			(layers "B.Cu" "B.Mask" "B.Paste")
			(net 5 "/Compute module/SDIO.D1")
			(pinfunction "CH4")
			(pintype "passive")
			(solder_mask_margin 0.05)
		)
		(pad "6" smd rect
			(at 1 0.3875 90)
			(size 0.2 0.475)
			(layers "B.Cu" "B.Mask" "B.Paste")
			(net 5 "/Compute module/SDIO.D1")
			(pinfunction "CH4")
			(pintype "passive")
			(solder_mask_margin 0.05)
		)
		(pad "7" smd rect
			(at 0.5 0.3875 90)
			(size 0.2 0.475)
			(layers "B.Cu" "B.Mask" "B.Paste")
			(net 6 "/Compute module/SDIO.D0")
			(pinfunction "CH3")
			(pintype "passive")
			(solder_mask_margin 0.05)
		)
		(pad "8" smd rect
			(at 0 0.3875 90)
			(size 0.2 0.475)
			(layers "B.Cu" "B.Mask" "B.Paste")
			(net 3 "GND")
			(pinfunction "GND")
			(pintype "passive")
			(solder_mask_margin 0.05)
		)
		(pad "9" smd rect
			(at -0.501 0.3875 90)
			(size 0.2 0.475)
			(layers "B.Cu" "B.Mask" "B.Paste")
			(net 7 "/Compute module/SDIO.CLK")
			(pinfunction "CH2")
			(pintype "passive")
			(solder_mask_margin 0.05)
		)
		(pad "10" smd rect
			(at -1 0.3875 90)
			(size 0.2 0.475)
			(layers "B.Cu" "B.Mask" "B.Paste")
			(net 3 "GND")
			(pinfunction "CH1")
			(pintype "passive")
			(solder_mask_margin 0.05)
		)
	)
	(footprint "antmicro-footprints:DFN3538"
		(layer "B.Cu")
		(at 63.217962 115.1665 -90)
		(property "Reference" "D401"
			(at -1.2865 -3.592038 90)
			(unlocked yes)
			(layer "B.SilkS")
			(effects
				(font
					(size 0.7 0.7)
					(thickness 0.15)
				)
				(justify left bottom mirror)
			)
		)
		(property "Value" "CD-MMBL110S"
			(at 0 -3.5 90)
			(unlocked yes)
			(layer "B.Fab")
			(effects
				(font
					(size 0.7 0.7)
					(thickness 0.15)
				)
				(justify left bottom mirror)
			)
		)
		(property "Datasheet" "https://www.bourns.com/docs/product-datasheets/CD-MMBL110S.pdf"
			(at 0 0 270)
			(layer "B.Fab")
			(hide yes)
			(effects
				(font
					(size 1.27 1.27)
					(thickness 0.15)
				)
			)
		)
		(property "MPN" "CD-MMBL110S"
			(at 0 0 270)
			(unlocked yes)
			(layer "B.Fab")
			(hide yes)
			(effects
				(font
					(size 1 1)
					(thickness 0.15)
				)
				(justify mirror)
			)
		)
		(property "Manufacturer" "Bourns"
			(at 0 0 270)
			(unlocked yes)
			(layer "B.Fab")
			(hide yes)
			(effects
				(font
					(size 1 1)
					(thickness 0.15)
				)
				(justify mirror)
			)
		)
		(property "Author" "Antmicro"
			(at 0 0 270)
			(unlocked yes)
			(layer "B.Fab")
			(hide yes)
			(effects
				(font
					(size 1 1)
					(thickness 0.15)
				)
				(justify mirror)
			)
		)
		(property "License" "Apache-2.0"
			(at 0 0 270)
			(unlocked yes)
			(layer "B.Fab")
			(hide yes)
			(effects
				(font
					(size 1 1)
					(thickness 0.15)
				)
				(justify mirror)
			)
		)
		(sheetname "/Ethernet/")
		(sheetfile "ethernet.kicad_sch")
		(attr smd)
		(fp_line
			(start 0.748 2.452)
			(end 0.748 2.15)
			(stroke
				(width 0.15)
				(type solid)
			)
			(layer "B.SilkS")
		)
		(fp_line
			(start 0.9 2.301)
			(end 0.598 2.301)
			(stroke
				(width 0.15)
				(type solid)
			)
			(layer "B.SilkS")
		)
		(fp_line
			(start -0.902 2.25)
			(end -0.6 2.25)
			(stroke
				(width 0.15)
				(type solid)
			)
			(layer "B.SilkS")
		)
		(fp_line
			(start -0.95 2)
			(end 0.95 2)
			(stroke
				(width 0.15)
				(type solid)
			)
			(layer "B.SilkS")
		)
		(fp_line
			(start 1.6 2)
			(end 1.8 2)
			(stroke
				(width 0.15)
				(type solid)
			)
			(layer "B.SilkS")
		)
		(fp_line
			(start 1.8 2)
			(end 1.8 -2.05)
			(stroke
				(width 0.15)
				(type solid)
			)
			(layer "B.SilkS")
		)
		(fp_line
			(start -1.8 1.5)
			(end -1.8 -2.05)
			(stroke
				(width 0.15)
				(type solid)
			)
			(layer "B.SilkS")
		)
		(fp_line
			(start -1.8 -2.05)
			(end -1.6 -2.05)
			(stroke
				(width 0.15)
				(type solid)
			)
			(layer "B.SilkS")
		)
		(fp_line
			(start -0.95 -2.05)
			(end 0.95 -2.05)
			(stroke
				(width 0.15)
				(type solid)
			)
			(layer "B.SilkS")
		)
		(fp_line
			(start 1.6 -2.05)
			(end 1.8 -2.05)
			(stroke
				(width 0.15)
				(type solid)
			)
			(layer "B.SilkS")
		)
		(fp_rect
			(start -2.1 2.6)
			(end 2.1 -2.6)
			(stroke
				(width 0.05)
				(type solid)
			)
			(fill no)
			(layer "B.CrtYd")
		)
		(fp_line
			(start -1.051 2)
			(end -1.801 1.25)
			(stroke
				(width 0.15)
				(type solid)
			)
			(layer "B.Fab")
		)
		(fp_rect
			(start 1.8 -2.048)
			(end -1.8 2)
			(stroke
				(width 0.15)
				(type solid)
			)
			(fill no)
			(layer "B.Fab")
		)
		(fp_text user "~"
			(at -0.31 -2.7 90)
			(unlocked yes)
			(layer "B.SilkS")
			(effects
				(font
					(size 0.7 0.7)
					(thickness 0.15)
				)
				(justify left bottom mirror)
			)
		)
		(fp_text user "${REFERENCE}"
			(at -2.1 -4.599 90)
			(layer "B.Fab")
			(effects
				(font
					(size 0.7 0.7)
					(thickness 0.15)
				)
				(justify left bottom mirror)
			)
		)
		(fp_text user "License: Apache-2.0"
			(at -2.1 -6.599 90)
			(layer "B.Fab")
			(effects
				(font
					(size 0.7 0.7)
					(thickness 0.15)
				)
				(justify left bottom mirror)
			)
		)
		(fp_text user "Author: Antmicro"
			(at -2.1 -5.599 90)
			(layer "B.Fab")
			(effects
				(font
					(size 0.7 0.7)
					(thickness 0.15)
				)
				(justify left bottom mirror)
			)
		)
		(pad "1" smd roundrect
			(at -1.27 1.85 180)
			(size 1.4 0.48)
			(layers "B.Cu" "B.Mask" "B.Paste")
			(roundrect_rratio 0.25)
			(net 116 "Net-(D401-Pad1)")
			(pinfunction "1")
			(pintype "passive")
		)
		(pad "2" smd roundrect
			(at 1.27 1.85 180)
			(size 1.4 0.48)
			(layers "B.Cu" "B.Mask" "B.Paste")
			(roundrect_rratio 0.25)
			(net 117 "Net-(D401-Pad2)")
			(pinfunction "2")
			(pintype "passive")
		)
		(pad "3" smd roundrect
			(at -1.27 -1.85 180)
			(size 1.4 0.48)
			(layers "B.Cu" "B.Mask" "B.Paste")
			(roundrect_rratio 0.25)
			(net 61 "/Ethernet/PAIR_12")
			(pinfunction "3")
			(pintype "passive")
		)
		(pad "4" smd roundrect
			(at 1.27 -1.85 180)
			(size 1.4 0.48)
			(layers "B.Cu" "B.Mask" "B.Paste")
			(roundrect_rratio 0.25)
			(net 62 "/Ethernet/PAIR_36")
			(pinfunction "4")
			(pintype "passive")
		)
	)
	(footprint "antmicro-footprints:R_0402_1005Metric"
		(layer "B.Cu")
		(at 63.492962 163.1915 180)
		(descr "Resistor SMD 0402")
		(tags "resistor SMD 0402")
		(property "Reference" "R311"
			(at -15.365 0.215 0)
			(layer "B.SilkS")
			(effects
				(font
					(size 0.7 0.7)
					(thickness 0.15)
				)
				(justify left bottom mirror)
			)
		)
		(property "Value" "R_10k_0402"
			(at -1.011843 -1.772047 0)
			(layer "B.Fab")
			(effects
				(font
					(size 0.7 0.7)
					(thickness 0.15)
				)
				(justify left bottom mirror)
			)
		)
		(property "Datasheet" "https://www.bourns.com/docs/product-datasheets/cr.pdf"
			(at 0 0 180)
			(layer "B.Fab")
			(hide yes)
			(effects
				(font
					(size 1.27 1.27)
					(thickness 0.15)
				)
			)
		)
		(property "Manufacturer" "Bourns"
			(at 0 0 180)
			(unlocked yes)
			(layer "B.Fab")
			(hide yes)
			(effects
				(font
					(size 1 1)
					(thickness 0.15)
				)
				(justify mirror)
			)
		)
		(property "MPN" "CR0402-FX-1002GLF"
			(at 0 0 180)
			(unlocked yes)
			(layer "B.Fab")
			(hide yes)
			(effects
				(font
					(size 1 1)
					(thickness 0.15)
				)
				(justify mirror)
			)
		)
		(property "Val" "10k"
			(at 0 0 180)
			(unlocked yes)
			(layer "B.Fab")
			(hide yes)
			(effects
				(font
					(size 1 1)
					(thickness 0.15)
				)
				(justify mirror)
			)
		)
		(property "License" "Apache-2.0"
			(at 0 0 180)
			(unlocked yes)
			(layer "B.Fab")
			(hide yes)
			(effects
				(font
					(size 1 1)
					(thickness 0.15)
				)
				(justify mirror)
			)
		)
		(property "Author" "Antmicro"
			(at 0 0 180)
			(unlocked yes)
			(layer "B.Fab")
			(hide yes)
			(effects
				(font
					(size 1 1)
					(thickness 0.15)
				)
				(justify mirror)
			)
		)
		(property "Tolerance" "1%"
			(at 0 0 180)
			(unlocked yes)
			(layer "B.Fab")
			(hide yes)
			(effects
				(font
					(size 1 1)
					(thickness 0.15)
				)
				(justify mirror)
			)
		)
		(sheetname "/Supply/")
		(sheetfile "supply.kicad_sch")
		(attr smd)
		(fp_rect
			(start -0.925 0.47)
			(end 0.925 -0.47)
			(stroke
				(width 0.05)
				(type default)
			)
			(fill no)
			(layer "B.CrtYd")
		)
		(fp_rect
			(start -0.5 0.25)
			(end 0.5 -0.25)
			(stroke
				(width 0.15)
				(type solid)
			)
			(fill no)
			(layer "B.Fab")
		)
		(fp_text user "${REFERENCE}"
			(at -0.95 -3.168 0)
			(layer "B.Fab")
			(effects
				(font
					(size 0.7 0.7)
					(thickness 0.15)
				)
				(justify left bottom mirror)
			)
		)
		(fp_text user "License: Apache-2.0"
			(at -0.95 -5.169 0)
			(layer "B.Fab")
			(effects
				(font
					(size 0.7 0.7)
					(thickness 0.15)
				)
				(justify left bottom mirror)
			)
		)
		(fp_text user "Author: Antmicro"
			(at -0.95 -4.169 0)
			(layer "B.Fab")
			(effects
				(font
					(size 0.7 0.7)
					(thickness 0.15)
				)
				(justify left bottom mirror)
			)
		)
		(pad "1" smd roundrect
			(at -0.48 0 180)
			(size 0.59 0.64)
			(layers "B.Cu" "B.Mask" "B.Paste")
			(roundrect_rratio 0.25)
			(net 350 "/Supply/EN_3V3")
			(pintype "passive")
		)
		(pad "2" smd roundrect
			(at 0.48 0 180)
			(size 0.59 0.64)
			(layers "B.Cu" "B.Mask" "B.Paste")
			(roundrect_rratio 0.25)
			(net 43 "VCC")
			(pintype "passive")
		)
	)
	(footprint "antmicro-footprints:SOD-123FL"
		(layer "B.Cu")
		(at 40.467962 154.7865 180)
		(property "Reference" "D303"
			(at -2.53 1.3 0)
			(layer "B.SilkS")
			(effects
				(font
					(size 0.7 0.7)
					(thickness 0.15)
				)
				(justify left bottom mirror)
			)
		)
		(property "Value" "SMF4L15A"
			(at 0 -1.967 0)
			(layer "B.Fab")
			(effects
				(font
					(size 0.7 0.7)
					(thickness 0.15)
				)
				(justify left bottom mirror)
			)
		)
		(property "Datasheet" "https://www.littelfuse.com/media?resourcetype=datasheets&itemid=d2ba8fab-1de3-4176-8530-f36ecb0b8799&filename=smf4l"
			(at 0 0 180)
			(layer "B.Fab")
			(hide yes)
			(effects
				(font
					(size 1.27 1.27)
					(thickness 0.15)
				)
			)
		)
		(property "Manufacturer" "Littelfuse"
			(at 0 0 180)
			(unlocked yes)
			(layer "B.Fab")
			(hide yes)
			(effects
				(font
					(size 1 1)
					(thickness 0.15)
				)
				(justify mirror)
			)
		)
		(property "MPN" "SMF4L15A"
			(at 0 0 180)
			(unlocked yes)
			(layer "B.Fab")
			(hide yes)
			(effects
				(font
					(size 1 1)
					(thickness 0.15)
				)
				(justify mirror)
			)
		)
		(property "Author" "Antmicro"
			(at 0 0 180)
			(unlocked yes)
			(layer "B.Fab")
			(hide yes)
			(effects
				(font
					(size 1 1)
					(thickness 0.15)
				)
				(justify mirror)
			)
		)
		(property "License" "Apache-2.0"
			(at 0 0 180)
			(unlocked yes)
			(layer "B.Fab")
			(hide yes)
			(effects
				(font
					(size 1 1)
					(thickness 0.15)
				)
				(justify mirror)
			)
		)
		(sheetname "/Supply/")
		(sheetfile "supply.kicad_sch")
		(attr smd)
		(fp_line
			(start 0 1.1)
			(end -2.3 1.1)
			(stroke
				(width 0.15)
				(type solid)
			)
			(layer "B.SilkS")
		)
		(fp_line
			(start -2.3 1.1)
			(end -2.3 -1.1)
			(stroke
				(width 0.15)
				(type solid)
			)
			(layer "B.SilkS")
		)
		(fp_line
			(start -2.3 -1.1)
			(end 0 -1.1)
			(stroke
				(width 0.15)
				(type solid)
			)
			(layer "B.SilkS")
		)
		(fp_rect
			(start -2.35 1.125)
			(end 2.35 -1.125)
			(stroke
				(width 0.05)
				(type solid)
			)
			(fill no)
			(layer "B.CrtYd")
		)
		(fp_rect
			(start -0.775 0.875)
			(end -0.525 -0.875)
			(stroke
				(width 0.15)
				(type solid)
			)
			(fill yes)
			(layer "B.Fab")
		)
		(fp_rect
			(start -1.825 0.875)
			(end 1.824 -0.873)
			(stroke
				(width 0.15)
				(type solid)
			)
			(fill no)
			(layer "B.Fab")
		)
		(fp_text user "Author: Antmicro"
			(at -2.406 -5.168 0)
			(layer "B.Fab")
			(effects
				(font
					(size 0.7 0.7)
					(thickness 0.15)
				)
				(justify left bottom mirror)
			)
		)
		(fp_text user "License: Apache-2.0"
			(at -2.406 -6.368 0)
			(layer "B.Fab")
			(effects
				(font
					(size 0.7 0.7)
					(thickness 0.15)
				)
				(justify left bottom mirror)
			)
		)
		(fp_text user "${REFERENCE}"
			(at -2.406 -3.967 0)
			(layer "B.Fab")
			(effects
				(font
					(size 0.7 0.7)
					(thickness 0.15)
				)
				(justify left bottom mirror)
			)
		)
		(pad "1" smd roundrect
			(at -1.43 0 180)
			(size 1.34 1.8)
			(layers "B.Cu" "B.Mask" "B.Paste")
			(roundrect_rratio 0.14)
			(net 43 "VCC")
			(pinfunction "C")
			(pintype "passive")
		)
		(pad "2" smd roundrect
			(at 1.429 0 180)
			(size 1.34 1.8)
			(layers "B.Cu" "B.Mask" "B.Paste")
			(roundrect_rratio 0.14)
			(net 3 "GND")
			(pinfunction "A")
			(pintype "passive")
		)
	)
	(footprint "antmicro-footprints:C_0402_1005Metric"
		(layer "B.Cu")
		(at 71.942962 129.9365 180)
		(descr "Capacitor SMD 0402")
		(tags "capacitor SMD 0402")
		(property "Reference" "C403"
			(at -2.005 -2.3 0)
			(layer "B.SilkS")
			(effects
				(font
					(size 0.7 0.7)
					(thickness 0.15)
				)
				(justify left bottom mirror)
			)
		)
		(property "Value" "C_100n_0402"
			(at -1.022927 -2.155213 0)
			(layer "B.Fab")
			(effects
				(font
					(size 0.7 0.7)
					(thickness 0.15)
				)
				(justify left bottom mirror)
			)
		)
		(property "Datasheet" "https://www.murata.com/products/productdetail?partno=GRM155R61H104KE14%23"
			(at 0 0 180)
			(layer "B.Fab")
			(hide yes)
			(effects
				(font
					(size 1.27 1.27)
					(thickness 0.15)
				)
			)
		)
		(property "Manufacturer" "Murata"
			(at 0 0 180)
			(unlocked yes)
			(layer "B.Fab")
			(hide yes)
			(effects
				(font
					(size 1 1)
					(thickness 0.15)
				)
				(justify mirror)
			)
		)
		(property "MPN" "GRM155R61H104KE14D"
			(at 0 0 180)
			(unlocked yes)
			(layer "B.Fab")
			(hide yes)
			(effects
				(font
					(size 1 1)
					(thickness 0.15)
				)
				(justify mirror)
			)
		)
		(property "Val" "100n"
			(at 0 0 180)
			(unlocked yes)
			(layer "B.Fab")
			(hide yes)
			(effects
				(font
					(size 1 1)
					(thickness 0.15)
				)
				(justify mirror)
			)
		)
		(property "License" "Apache-2.0"
			(at 0 0 180)
			(unlocked yes)
			(layer "B.Fab")
			(hide yes)
			(effects
				(font
					(size 1 1)
					(thickness 0.15)
				)
				(justify mirror)
			)
		)
		(property "Author" "Antmicro"
			(at 0 0 180)
			(unlocked yes)
			(layer "B.Fab")
			(hide yes)
			(effects
				(font
					(size 1 1)
					(thickness 0.15)
				)
				(justify mirror)
			)
		)
		(property "Voltage" "50V"
			(at 0 0 180)
			(unlocked yes)
			(layer "B.Fab")
			(hide yes)
			(effects
				(font
					(size 1 1)
					(thickness 0.15)
				)
				(justify mirror)
			)
		)
		(property "Dielectric" "X5R"
			(at 0 0 180)
			(unlocked yes)
			(layer "B.Fab")
			(hide yes)
			(effects
				(font
					(size 1 1)
					(thickness 0.15)
				)
				(justify mirror)
			)
		)
		(sheetname "/Ethernet/")
		(sheetfile "ethernet.kicad_sch")
		(attr smd)
		(fp_rect
			(start -0.925 0.47)
			(end 0.925 -0.47)
			(stroke
				(width 0.05)
				(type default)
			)
			(fill no)
			(layer "B.CrtYd")
		)
		(fp_line
			(start 0.504 0.25)
			(end 0.504 -0.248)
			(stroke
				(width 0.15)
				(type solid)
			)
			(layer "B.Fab")
		)
		(fp_line
			(start 0.504 -0.248)
			(end -0.494 -0.248)
			(stroke
				(width 0.15)
				(type solid)
			)
			(layer "B.Fab")
		)
		(fp_line
			(start -0.494 0.25)
			(end 0.504 0.25)
			(stroke
				(width 0.15)
				(type solid)
			)
			(layer "B.Fab")
		)
		(fp_line
			(start -0.494 -0.248)
			(end -0.494 0.25)
			(stroke
				(width 0.15)
				(type solid)
			)
			(layer "B.Fab")
		)
		(fp_text user "Author: Antmicro"
			(at -0.939 -3.399 0)
			(layer "B.Fab")
			(effects
				(font
					(size 0.7 0.7)
					(thickness 0.15)
				)
				(justify left bottom mirror)
			)
		)
		(fp_text user "${REFERENCE}"
			(at -0.939 -4.599 0)
			(layer "B.Fab")
			(effects
				(font
					(size 0.7 0.7)
					(thickness 0.15)
				)
				(justify left bottom mirror)
			)
		)
		(fp_text user "License: Apache-2.0"
			(at -0.939 -5.799 0)
			(layer "B.Fab")
			(effects
				(font
					(size 0.7 0.7)
					(thickness 0.15)
				)
				(justify left bottom mirror)
			)
		)
		(pad "1" smd roundrect
			(at -0.48 0 180)
			(size 0.59 0.64)
			(layers "B.Cu" "B.Mask" "B.Paste")
			(roundrect_rratio 0.25)
			(net 92 "Net-(C403-Pad1)")
			(pintype "passive")
		)
		(pad "2" smd roundrect
			(at 0.48 0 180)
			(size 0.59 0.64)
			(layers "B.Cu" "B.Mask" "B.Paste")
			(roundrect_rratio 0.25)
			(net 3 "GND")
			(pintype "passive")
		)
	)
	(footprint "antmicro-footprints:R_0402_1005Metric"
		(layer "B.Cu")
		(at 76.45 152.67 90)
		(descr "Resistor SMD 0402")
		(tags "resistor SMD 0402")
		(property "Reference" "R263"
			(at -3.73 0.5 90)
			(layer "B.SilkS")
			(effects
				(font
					(size 0.7 0.7)
					(thickness 0.15)
				)
				(justify right bottom mirror)
			)
		)
		(property "Value" "R_100k_0402"
			(at -1.011843 -1.772047 90)
			(layer "B.Fab")
			(effects
				(font
					(size 0.7 0.7)
					(thickness 0.15)
				)
				(justify right bottom mirror)
			)
		)
		(property "Datasheet" "https://www.bourns.com/docs/product-datasheets/cr.pdf"
			(at 0 0 90)
			(layer "B.Fab")
			(hide yes)
			(effects
				(font
					(size 1.27 1.27)
					(thickness 0.15)
				)
			)
		)
		(property "Manufacturer" "Bourns"
			(at 0 0 90)
			(unlocked yes)
			(layer "B.Fab")
			(hide yes)
			(effects
				(font
					(size 1 1)
					(thickness 0.15)
				)
				(justify mirror)
			)
		)
		(property "MPN" "CR0402-FX-1003GLF"
			(at 0 0 90)
			(unlocked yes)
			(layer "B.Fab")
			(hide yes)
			(effects
				(font
					(size 1 1)
					(thickness 0.15)
				)
				(justify mirror)
			)
		)
		(property "Val" "100k"
			(at 0 0 90)
			(unlocked yes)
			(layer "B.Fab")
			(hide yes)
			(effects
				(font
					(size 1 1)
					(thickness 0.15)
				)
				(justify mirror)
			)
		)
		(property "License" "Apache-2.0"
			(at 0 0 90)
			(unlocked yes)
			(layer "B.Fab")
			(hide yes)
			(effects
				(font
					(size 1 1)
					(thickness 0.15)
				)
				(justify mirror)
			)
		)
		(property "Author" "Antmicro"
			(at 0 0 90)
			(unlocked yes)
			(layer "B.Fab")
			(hide yes)
			(effects
				(font
					(size 1 1)
					(thickness 0.15)
				)
				(justify mirror)
			)
		)
		(property "Tolerance" "1%"
			(at 0 0 90)
			(unlocked yes)
			(layer "B.Fab")
			(hide yes)
			(effects
				(font
					(size 1 1)
					(thickness 0.15)
				)
				(justify mirror)
			)
		)
		(sheetname "/Compute module/")
		(sheetfile "compute-module.kicad_sch")
		(attr smd)
		(fp_rect
			(start -0.925 0.47)
			(end 0.925 -0.47)
			(stroke
				(width 0.05)
				(type default)
			)
			(fill no)
			(layer "B.CrtYd")
		)
		(fp_rect
			(start -0.5 0.25)
			(end 0.5 -0.25)
			(stroke
				(width 0.15)
				(type solid)
			)
			(fill no)
			(layer "B.Fab")
		)
		(fp_text user "Author: Antmicro"
			(at -0.95 -4.169 270)
			(layer "B.Fab")
			(effects
				(font
					(size 0.7 0.7)
					(thickness 0.15)
				)
				(justify left bottom mirror)
			)
		)
		(fp_text user "License: Apache-2.0"
			(at -0.95 -5.169 270)
			(layer "B.Fab")
			(effects
				(font
					(size 0.7 0.7)
					(thickness 0.15)
				)
				(justify left bottom mirror)
			)
		)
		(fp_text user "${REFERENCE}"
			(at -0.95 -3.168 270)
			(layer "B.Fab")
			(effects
				(font
					(size 0.7 0.7)
					(thickness 0.15)
				)
				(justify left bottom mirror)
			)
		)
		(pad "1" smd roundrect
			(at -0.48 0 90)
			(size 0.59 0.64)
			(layers "B.Cu" "B.Mask" "B.Paste")
			(roundrect_rratio 0.25)
			(net 3 "GND")
			(pintype "passive")
		)
		(pad "2" smd roundrect
			(at 0.48 0 90)
			(size 0.59 0.64)
			(layers "B.Cu" "B.Mask" "B.Paste")
			(roundrect_rratio 0.25)
			(net 18 "V_{IO}")
			(pintype "passive")
		)
	)
	(footprint "antmicro-footprints:SOIC-8_3.9x4.9x1.75mm_P1.27mm"
		(layer "B.Cu")
		(at 120.523 176.276 180)
		(property "Reference" "U802"
			(at -1.727 2.846 0)
			(layer "B.SilkS")
			(effects
				(font
					(size 0.7 0.7)
					(thickness 0.15)
				)
				(justify left bottom mirror)
			)
		)
		(property "Value" "DS1338_SOIC"
			(at 0 -3.65 0)
			(layer "B.Fab")
			(effects
				(font
					(size 0.7 0.7)
					(thickness 0.15)
				)
				(justify left bottom mirror)
			)
		)
		(property "Datasheet" "https://www.analog.com/media/en/technical-documentation/data-sheets/DS1338-DS1338Z.pdf"
			(at 0 0 0)
			(layer "B.Fab")
			(hide yes)
			(effects
				(font
					(size 1.27 1.27)
					(thickness 0.15)
				)
				(justify mirror)
			)
		)
		(property "Description" "Real-time clock/calendar,  1.71V-5.5V supply, I2C, SOIC-8"
			(at 0 0 0)
			(layer "B.Fab")
			(hide yes)
			(effects
				(font
					(size 1.27 1.27)
					(thickness 0.15)
				)
				(justify mirror)
			)
		)
		(property "MPN" "DS1338Z-18+"
			(at 0 0 180)
			(unlocked yes)
			(layer "B.Fab")
			(hide yes)
			(effects
				(font
					(size 1 1)
					(thickness 0.15)
				)
				(justify mirror)
			)
		)
		(property "Manufacturer" "Maxim Integrated Products"
			(at 0 0 180)
			(unlocked yes)
			(layer "B.Fab")
			(hide yes)
			(effects
				(font
					(size 1 1)
					(thickness 0.15)
				)
				(justify mirror)
			)
		)
		(property "Author" "Antmicro"
			(at 0 0 180)
			(unlocked yes)
			(layer "B.Fab")
			(hide yes)
			(effects
				(font
					(size 1 1)
					(thickness 0.15)
				)
				(justify mirror)
			)
		)
		(property "License" "Apache-2.0"
			(at 0 0 180)
			(unlocked yes)
			(layer "B.Fab")
			(hide yes)
			(effects
				(font
					(size 1 1)
					(thickness 0.15)
				)
				(justify mirror)
			)
		)
		(sheetname "/Peripherals/")
		(sheetfile "peripherals.kicad_sch")
		(attr smd)
		(fp_line
			(start -1.95 2.452)
			(end 1.95 2.45)
			(stroke
				(width 0.15)
				(type solid)
			)
			(layer "B.SilkS")
		)
		(fp_line
			(start -1.95 -2.45)
			(end 1.95 -2.45)
			(stroke
				(width 0.15)
				(type solid)
			)
			(layer "B.SilkS")
		)
		(fp_circle
			(center -2.4 2.45)
			(end -2.35 2.4)
			(stroke
				(width 0.15)
				(type solid)
			)
			(fill yes)
			(layer "B.SilkS")
		)
		(fp_rect
			(start -3.625 2.7)
			(end 3.625 -2.7)
			(stroke
				(width 0.05)
				(type solid)
			)
			(fill no)
			(layer "B.CrtYd")
		)
		(fp_line
			(start 1.949 2.452)
			(end 1.949 -2.45)
			(stroke
				(width 0.15)
				(type solid)
			)
			(layer "B.Fab")
		)
		(fp_line
			(start 1.949 -2.45)
			(end -1.95 -2.45)
			(stroke
				(width 0.15)
				(type solid)
			)
			(layer "B.Fab")
		)
		(fp_line
			(start -0.683 2.452)
			(end 1.949 2.452)
			(stroke
				(width 0.15)
				(type solid)
			)
			(layer "B.Fab")
		)
		(fp_line
			(start -1.95 1.18)
			(end -0.683 2.452)
			(stroke
				(width 0.15)
				(type solid)
			)
			(layer "B.Fab")
		)
		(fp_line
			(start -1.95 -2.45)
			(end -1.95 1.18)
			(stroke
				(width 0.15)
				(type solid)
			)
			(layer "B.Fab")
		)
		(fp_text user "${REFERENCE}"
			(at -3.476 -7.099 0)
			(layer "B.Fab")
			(effects
				(font
					(size 0.7 0.7)
					(thickness 0.15)
				)
				(justify left bottom mirror)
			)
		)
		(fp_text user "Author: Antmicro"
			(at -3.476 -6.099 0)
			(layer "B.Fab")
			(effects
				(font
					(size 0.7 0.7)
					(thickness 0.15)
				)
				(justify left bottom mirror)
			)
		)
		(fp_text user "License: Apache-2.0"
			(at -3.476 -5.099 0)
			(layer "B.Fab")
			(effects
				(font
					(size 0.7 0.7)
					(thickness 0.15)
				)
				(justify left bottom mirror)
			)
		)
		(pad "1" smd roundrect
			(at -2.714 1.905 90)
			(size 0.65 1.525)
			(layers "B.Cu" "B.Mask" "B.Paste")
			(roundrect_rratio 0.25)
			(net 505 "Net-(U802-X1)")
			(pinfunction "X1")
			(pintype "input")
		)
		(pad "2" smd roundrect
			(at -2.714 0.635 90)
			(size 0.65 1.525)
			(layers "B.Cu" "B.Mask" "B.Paste")
			(roundrect_rratio 0.25)
			(net 506 "Net-(U802-X2)")
			(pinfunction "X2")
			(pintype "output")
		)
		(pad "3" smd roundrect
			(at -2.714 -0.632 90)
			(size 0.65 1.525)
			(layers "B.Cu" "B.Mask" "B.Paste")
			(roundrect_rratio 0.25)
			(net 503 "Net-(D811-C)")
			(pinfunction "V_{bat}")
			(pintype "power_in")
		)
		(pad "4" smd roundrect
			(at -2.714 -1.902 90)
			(size 0.65 1.525)
			(layers "B.Cu" "B.Mask" "B.Paste")
			(roundrect_rratio 0.25)
			(net 3 "GND")
			(pinfunction "GND")
			(pintype "power_in")
		)
		(pad "5" smd roundrect
			(at 2.712 -1.902 90)
			(size 0.65 1.525)
			(layers "B.Cu" "B.Mask" "B.Paste")
			(roundrect_rratio 0.25)
			(net 143 "/CSI/I_{2}C1.SDA")
			(pinfunction "SDA")
			(pintype "bidirectional")
		)
		(pad "6" smd roundrect
			(at 2.712 -0.632 90)
			(size 0.65 1.525)
			(layers "B.Cu" "B.Mask" "B.Paste")
			(roundrect_rratio 0.25)
			(net 142 "/CSI/I_{2}C1.SCL")
			(pinfunction "SCL")
			(pintype "input")
		)
		(pad "7" smd roundrect
			(at 2.712 0.635 90)
			(size 0.65 1.525)
			(layers "B.Cu" "B.Mask" "B.Paste")
			(roundrect_rratio 0.25)
			(net 504 "unconnected-(U802-SQW{slash}OUT-Pad7)")
			(pinfunction "SQW/OUT")
			(pintype "output+no_connect")
		)
		(pad "8" smd roundrect
			(at 2.712 1.905 90)
			(size 0.65 1.525)
			(layers "B.Cu" "B.Mask" "B.Paste")
			(roundrect_rratio 0.25)
			(net 9 "+3V3")
			(pinfunction "V_{CC}")
			(pintype "power_in")
		)
	)
	(footprint "antmicro-footprints:R_0402_1005Metric"
		(layer "B.Cu")
		(at 52.487962 153.2565 180)
		(descr "Resistor SMD 0402")
		(tags "resistor SMD 0402")
		(property "Reference" "R313"
			(at -2.04 1.78 0)
			(layer "B.SilkS")
			(effects
				(font
					(size 0.7 0.7)
					(thickness 0.15)
				)
				(justify left bottom mirror)
			)
		)
		(property "Value" "R_33k_0402"
			(at -1.011843 -1.772047 0)
			(layer "B.Fab")
			(effects
				(font
					(size 0.7 0.7)
					(thickness 0.15)
				)
				(justify left bottom mirror)
			)
		)
		(property "Datasheet" "https://www.bourns.com/docs/product-datasheets/cr.pdf"
			(at 0 0 180)
			(layer "B.Fab")
			(hide yes)
			(effects
				(font
					(size 1.27 1.27)
					(thickness 0.15)
				)
			)
		)
		(property "MPN" "CR0402-FX-3302GLF"
			(at 0 0 180)
			(unlocked yes)
			(layer "B.Fab")
			(hide yes)
			(effects
				(font
					(size 1 1)
					(thickness 0.15)
				)
				(justify mirror)
			)
		)
		(property "Manufacturer" "Bourns"
			(at 0 0 180)
			(unlocked yes)
			(layer "B.Fab")
			(hide yes)
			(effects
				(font
					(size 1 1)
					(thickness 0.15)
				)
				(justify mirror)
			)
		)
		(property "License" "Apache-2.0"
			(at 0 0 180)
			(unlocked yes)
			(layer "B.Fab")
			(hide yes)
			(effects
				(font
					(size 1 1)
					(thickness 0.15)
				)
				(justify mirror)
			)
		)
		(property "Author" "Antmicro"
			(at 0 0 180)
			(unlocked yes)
			(layer "B.Fab")
			(hide yes)
			(effects
				(font
					(size 1 1)
					(thickness 0.15)
				)
				(justify mirror)
			)
		)
		(property "Val" "33k"
			(at 0 0 180)
			(unlocked yes)
			(layer "B.Fab")
			(hide yes)
			(effects
				(font
					(size 1 1)
					(thickness 0.15)
				)
				(justify mirror)
			)
		)
		(property "Tolerance" "1%"
			(at 0 0 180)
			(unlocked yes)
			(layer "B.Fab")
			(hide yes)
			(effects
				(font
					(size 1 1)
					(thickness 0.15)
				)
				(justify mirror)
			)
		)
		(sheetname "/Supply/")
		(sheetfile "supply.kicad_sch")
		(attr smd)
		(fp_rect
			(start -0.925 0.47)
			(end 0.925 -0.47)
			(stroke
				(width 0.05)
				(type default)
			)
			(fill no)
			(layer "B.CrtYd")
		)
		(fp_rect
			(start -0.5 0.25)
			(end 0.5 -0.25)
			(stroke
				(width 0.15)
				(type solid)
			)
			(fill no)
			(layer "B.Fab")
		)
		(fp_text user "License: Apache-2.0"
			(at -0.95 -5.169 0)
			(layer "B.Fab")
			(effects
				(font
					(size 0.7 0.7)
					(thickness 0.15)
				)
				(justify left bottom mirror)
			)
		)
		(fp_text user "Author: Antmicro"
			(at -0.95 -4.169 0)
			(layer "B.Fab")
			(effects
				(font
					(size 0.7 0.7)
					(thickness 0.15)
				)
				(justify left bottom mirror)
			)
		)
		(fp_text user "${REFERENCE}"
			(at -0.95 -3.168 0)
			(layer "B.Fab")
			(effects
				(font
					(size 0.7 0.7)
					(thickness 0.15)
				)
				(justify left bottom mirror)
			)
		)
		(pad "1" smd roundrect
			(at -0.48 0 180)
			(size 0.59 0.64)
			(layers "B.Cu" "B.Mask" "B.Paste")
			(roundrect_rratio 0.25)
			(net 351 "/Supply/EN_5V")
			(pintype "passive")
		)
		(pad "2" smd roundrect
			(at 0.48 0 180)
			(size 0.59 0.64)
			(layers "B.Cu" "B.Mask" "B.Paste")
			(roundrect_rratio 0.25)
			(net 43 "VCC")
			(pintype "passive")
		)
	)
	(footprint "antmicro-footprints:R_0402_1005Metric"
		(layer "B.Cu")
		(at 84.937962 165.0965)
		(descr "Resistor SMD 0402")
		(tags "resistor SMD 0402")
		(property "Reference" "R209"
			(at -3.62 0.53 0)
			(layer "B.SilkS")
			(effects
				(font
					(size 0.7 0.7)
					(thickness 0.15)
				)
				(justify right bottom mirror)
			)
		)
		(property "Value" "R_0R_0402"
			(at -1.011843 -1.772047 0)
			(layer "B.Fab")
			(effects
				(font
					(size 0.7 0.7)
					(thickness 0.15)
				)
				(justify right bottom mirror)
			)
		)
		(property "Datasheet" "https://industrial.panasonic.com/cdbs/www-data/pdf/RDA0000/AOA0000C301.pdf"
			(at 0 0 0)
			(layer "B.Fab")
			(hide yes)
			(effects
				(font
					(size 1.27 1.27)
					(thickness 0.15)
				)
			)
		)
		(property "Manufacturer" "Panasonic"
			(at 0 0 0)
			(unlocked yes)
			(layer "B.Fab")
			(hide yes)
			(effects
				(font
					(size 1 1)
					(thickness 0.15)
				)
				(justify mirror)
			)
		)
		(property "MPN" "ERJ2GE0R00X"
			(at 0 0 0)
			(unlocked yes)
			(layer "B.Fab")
			(hide yes)
			(effects
				(font
					(size 1 1)
					(thickness 0.15)
				)
				(justify mirror)
			)
		)
		(property "Val" "0R"
			(at 0 0 0)
			(unlocked yes)
			(layer "B.Fab")
			(hide yes)
			(effects
				(font
					(size 1 1)
					(thickness 0.15)
				)
				(justify mirror)
			)
		)
		(property "License" "Apache-2.0"
			(at 0 0 0)
			(unlocked yes)
			(layer "B.Fab")
			(hide yes)
			(effects
				(font
					(size 1 1)
					(thickness 0.15)
				)
				(justify mirror)
			)
		)
		(property "Author" "Antmicro"
			(at 0 0 0)
			(unlocked yes)
			(layer "B.Fab")
			(hide yes)
			(effects
				(font
					(size 1 1)
					(thickness 0.15)
				)
				(justify mirror)
			)
		)
		(property "Tolerance" "~"
			(at 0 0 0)
			(unlocked yes)
			(layer "B.Fab")
			(hide yes)
			(effects
				(font
					(size 1 1)
					(thickness 0.15)
				)
				(justify mirror)
			)
		)
		(property "Current" "1A"
			(at 0 0 0)
			(unlocked yes)
			(layer "B.Fab")
			(hide yes)
			(effects
				(font
					(size 1 1)
					(thickness 0.15)
				)
				(justify mirror)
			)
		)
		(sheetname "/Compute module/")
		(sheetfile "compute-module.kicad_sch")
		(attr smd exclude_from_pos_files exclude_from_bom dnp)
		(fp_rect
			(start -0.925 0.47)
			(end 0.925 -0.47)
			(stroke
				(width 0.05)
				(type default)
			)
			(fill no)
			(layer "B.CrtYd")
		)
		(fp_rect
			(start -0.5 0.25)
			(end 0.5 -0.25)
			(stroke
				(width 0.15)
				(type solid)
			)
			(fill no)
			(layer "B.Fab")
		)
		(fp_text user "Author: Antmicro"
			(at -0.95 -4.169 180)
			(layer "B.Fab")
			(effects
				(font
					(size 0.7 0.7)
					(thickness 0.15)
				)
				(justify left bottom mirror)
			)
		)
		(fp_text user "${REFERENCE}"
			(at -0.95 -3.168 180)
			(layer "B.Fab")
			(effects
				(font
					(size 0.7 0.7)
					(thickness 0.15)
				)
				(justify left bottom mirror)
			)
		)
		(fp_text user "License: Apache-2.0"
			(at -0.95 -5.169 180)
			(layer "B.Fab")
			(effects
				(font
					(size 0.7 0.7)
					(thickness 0.15)
				)
				(justify left bottom mirror)
			)
		)
		(pad "1" smd roundrect
			(at -0.48 0)
			(size 0.59 0.64)
			(layers "B.Cu" "B.Mask" "B.Paste")
			(roundrect_rratio 0.25)
			(net 254 "/Compute module/CAM_GPIO")
			(pintype "passive")
		)
		(pad "2" smd roundrect
			(at 0.48 0)
			(size 0.59 0.64)
			(layers "B.Cu" "B.Mask" "B.Paste")
			(roundrect_rratio 0.25)
			(net 275 "/CSI/CamCtrl.VSYNC1")
			(pintype "passive")
		)
	)
	(footprint "antmicro-footprints:Vishay_PowerPAK_1212-8_Single"
		(layer "B.Cu")
		(at 56.917962 163.3165 -90)
		(descr "PowerPAK 1212-8 Single")
		(tags "Vishay PowerPAK 1212-8 Single")
		(property "Reference" "Q305"
			(at -2.05 2 0)
			(layer "B.SilkS")
			(effects
				(font
					(size 0.7 0.7)
					(thickness 0.15)
				)
				(justify right bottom mirror)
			)
		)
		(property "Value" "SQS401EN-T1_BE3"
			(at 0 -2.7 90)
			(layer "B.Fab")
			(effects
				(font
					(size 0.7 0.7)
					(thickness 0.15)
				)
				(justify left bottom mirror)
			)
		)
		(property "Datasheet" "https://www.vishay.com/docs/65529/sqs401en.pdf"
			(at 0 0 270)
			(layer "B.Fab")
			(hide yes)
			(effects
				(font
					(size 1.27 1.27)
					(thickness 0.15)
				)
			)
		)
		(property "MPN" "SQS401EN-T1_BE3"
			(at 0 0 270)
			(unlocked yes)
			(layer "B.Fab")
			(hide yes)
			(effects
				(font
					(size 1 1)
					(thickness 0.15)
				)
				(justify mirror)
			)
		)
		(property "Manufacturer" "Vishay"
			(at 0 0 270)
			(unlocked yes)
			(layer "B.Fab")
			(hide yes)
			(effects
				(font
					(size 1 1)
					(thickness 0.15)
				)
				(justify mirror)
			)
		)
		(property "Author" "Antmicro"
			(at 0 0 270)
			(unlocked yes)
			(layer "B.Fab")
			(hide yes)
			(effects
				(font
					(size 1 1)
					(thickness 0.15)
				)
				(justify mirror)
			)
		)
		(property "License" "Apache-2.0"
			(at 0 0 270)
			(unlocked yes)
			(layer "B.Fab")
			(hide yes)
			(effects
				(font
					(size 1 1)
					(thickness 0.15)
				)
				(justify mirror)
			)
		)
		(sheetname "/Supply/")
		(sheetfile "supply.kicad_sch")
		(attr smd)
		(fp_line
			(start -1.651 1.651)
			(end 1.648 1.651)
			(stroke
				(width 0.15)
				(type solid)
			)
			(layer "B.SilkS")
		)
		(fp_line
			(start -1.651 1.651)
			(end -1.651 1.317)
			(stroke
				(width 0.15)
				(type solid)
			)
			(layer "B.SilkS")
		)
		(fp_line
			(start 1.648 1.651)
			(end 1.648 1.317)
			(stroke
				(width 0.15)
				(type solid)
			)
			(layer "B.SilkS")
		)
		(fp_line
			(start -1.635 -1.3)
			(end -1.635 -1.634)
			(stroke
				(width 0.15)
				(type solid)
			)
			(layer "B.SilkS")
		)
		(fp_line
			(start 1.634 -1.3)
			(end 1.634 -1.634)
			(stroke
				(width 0.15)
				(type solid)
			)
			(layer "B.SilkS")
		)
		(fp_line
			(start -1.635 -1.634)
			(end 1.634 -1.634)
			(stroke
				(width 0.15)
				(type solid)
			)
			(layer "B.SilkS")
		)
		(fp_circle
			(center -1.9 1.4)
			(end -1.85 1.4)
			(stroke
				(width 0.15)
				(type solid)
			)
			(fill yes)
			(layer "B.SilkS")
		)
		(fp_rect
			(start -2 1.8)
			(end 2 -1.798)
			(stroke
				(width 0.05)
				(type solid)
			)
			(fill no)
			(layer "B.CrtYd")
		)
		(fp_line
			(start -1.6425 1.4175)
			(end -1.4175 1.6425)
			(stroke
				(width 0.15)
				(type solid)
			)
			(layer "B.Fab")
		)
		(fp_rect
			(start -1.651 1.651)
			(end 1.648 -1.648)
			(stroke
				(width 0.15)
				(type solid)
			)
			(fill no)
			(layer "B.Fab")
		)
		(fp_text user "Author: Antmicro"
			(at -8 -5.9 90)
			(layer "B.Fab")
			(effects
				(font
					(size 0.7 0.7)
					(thickness 0.15)
				)
				(justify left bottom mirror)
			)
		)
		(fp_text user "License: Apache-2.0"
			(at -8 -7.1 90)
			(layer "B.Fab")
			(effects
				(font
					(size 0.7 0.7)
					(thickness 0.15)
				)
				(justify left bottom mirror)
			)
		)
		(fp_text user "${REFERENCE}"
			(at -8 -4.7 90)
			(layer "B.Fab")
			(effects
				(font
					(size 0.7 0.7)
					(thickness 0.15)
				)
				(justify left bottom mirror)
			)
		)
		(pad "1" smd rect
			(at -1.436 0.99 270)
			(size 0.99 0.405)
			(layers "B.Cu" "B.Mask" "B.Paste")
			(net 21 "/Supply/VCC_IN")
			(pinfunction "S")
			(pintype "passive")
		)
		(pad "2" smd rect
			(at -1.436 0.332 270)
			(size 0.99 0.405)
			(layers "B.Cu" "B.Mask" "B.Paste")
			(net 21 "/Supply/VCC_IN")
			(pinfunction "S")
			(pintype "passive")
		)
		(pad "3" smd rect
			(at -1.436 -0.33 270)
			(size 0.99 0.405)
			(layers "B.Cu" "B.Mask" "B.Paste")
			(net 21 "/Supply/VCC_IN")
			(pinfunction "S")
			(pintype "passive")
		)
		(pad "4" smd rect
			(at -1.436 -0.988 270)
			(size 0.99 0.405)
			(layers "B.Cu" "B.Mask" "B.Paste")
			(net 335 "Net-(Q302-BIAS)")
			(pinfunction "G")
			(pintype "input")
		)
		(pad "5" smd custom
			(at 0.557 0 270)
			(size 1.725 2.235)
			(layers "B.Cu" "B.Mask" "B.Paste")
			(net 47 "/Ethernet/POE_12V")
			(pinfunction "D")
			(pintype "passive")
			(zone_connect 2)
			(options
				(clearance outline)
				(anchor rect)
			)
			(primitives
				(gr_poly
					(pts
						(xy 0.8625 -0.1275) (xy 0.8625 0.1275) (xy 1.3725 0.1275) (xy 1.3725 0.5325) (xy 0.8625 0.5325)
						(xy 0.8625 0.7875) (xy 1.3725 0.7875) (xy 1.3725 1.195) (xy 0.6125 1.195) (xy 0.6125 -1.195) (xy 1.3725 -1.195)
						(xy 1.3725 -0.7875) (xy 0.8625 -0.7875) (xy 0.8625 -0.5325) (xy 1.3725 -0.5325) (xy 1.3725 -0.1275)
					)
					(width 0)
					(fill yes)
				)
			)
		)
	)
	(footprint "antmicro-footprints:C_0805_2012Metric"
		(layer "B.Cu")
		(at 116.217962 134.7165 90)
		(descr "Capacitor SMD 0805")
		(tags "capacitor SMD 0805")
		(property "Reference" "C313"
			(at -4.58 0.69 90)
			(layer "B.SilkS")
			(effects
				(font
					(size 0.7 0.7)
					(thickness 0.15)
				)
				(justify right bottom mirror)
			)
		)
		(property "Value" "C_22u_25V_0805"
			(at -2.055717 -1.963152 90)
			(layer "B.Fab")
			(effects
				(font
					(size 0.7 0.7)
					(thickness 0.15)
				)
				(justify right bottom mirror)
			)
		)
		(property "Datasheet" "https://product.samsungsem.com/mlcc/CL21A226MAYNNN.do"
			(at 0 0 90)
			(layer "B.Fab")
			(hide yes)
			(effects
				(font
					(size 1.27 1.27)
					(thickness 0.15)
				)
			)
		)
		(property "Manufacturer" "Samsung Electro-Mechanics"
			(at 0 0 90)
			(unlocked yes)
			(layer "B.Fab")
			(hide yes)
			(effects
				(font
					(size 1 1)
					(thickness 0.15)
				)
				(justify mirror)
			)
		)
		(property "MPN" "CL21A226MAYNNNE"
			(at 0 0 90)
			(unlocked yes)
			(layer "B.Fab")
			(hide yes)
			(effects
				(font
					(size 1 1)
					(thickness 0.15)
				)
				(justify mirror)
			)
		)
		(property "Val" "22u"
			(at 0 0 90)
			(unlocked yes)
			(layer "B.Fab")
			(hide yes)
			(effects
				(font
					(size 1 1)
					(thickness 0.15)
				)
				(justify mirror)
			)
		)
		(property "License" "Apache-2.0"
			(at 0 0 90)
			(unlocked yes)
			(layer "B.Fab")
			(hide yes)
			(effects
				(font
					(size 1 1)
					(thickness 0.15)
				)
				(justify mirror)
			)
		)
		(property "Author" "Antmicro"
			(at 0 0 90)
			(unlocked yes)
			(layer "B.Fab")
			(hide yes)
			(effects
				(font
					(size 1 1)
					(thickness 0.15)
				)
				(justify mirror)
			)
		)
		(property "Voltage" "25V"
			(at 0 0 90)
			(unlocked yes)
			(layer "B.Fab")
			(hide yes)
			(effects
				(font
					(size 1 1)
					(thickness 0.15)
				)
				(justify mirror)
			)
		)
		(property "Dielectric" "X5R"
			(at 0 0 90)
			(unlocked yes)
			(layer "B.Fab")
			(hide yes)
			(effects
				(font
					(size 1 1)
					(thickness 0.15)
				)
				(justify mirror)
			)
		)
		(property "Public" "False"
			(at 0 0 90)
			(unlocked yes)
			(layer "B.Fab")
			(hide yes)
			(effects
				(font
					(size 1 1)
					(thickness 0.15)
				)
				(justify mirror)
			)
		)
		(sheetname "/Supply/")
		(sheetfile "supply.kicad_sch")
		(attr smd)
		(fp_line
			(start -0.3 -0.7)
			(end 0.3 -0.7)
			(stroke
				(width 0.15)
				(type solid)
			)
			(layer "B.SilkS")
		)
		(fp_line
			(start -0.3 0.7)
			(end 0.3 0.7)
			(stroke
				(width 0.15)
				(type solid)
			)
			(layer "B.SilkS")
		)
		(fp_rect
			(start 1.95 0.9)
			(end -1.95 -0.9)
			(stroke
				(width 0.05)
				(type default)
			)
			(fill no)
			(layer "B.CrtYd")
		)
		(fp_rect
			(start -0.95 0.675)
			(end 0.95 -0.675)
			(stroke
				(width 0.15)
				(type solid)
			)
			(fill no)
			(layer "B.Fab")
		)
		(fp_text user "License: Apache-2.0"
			(at -1.9 -4.947 270)
			(layer "B.Fab")
			(effects
				(font
					(size 0.7 0.7)
					(thickness 0.15)
				)
				(justify left bottom mirror)
			)
		)
		(fp_text user "Author: Antmicro"
			(at -1.9 -5.947 270)
			(layer "B.Fab")
			(effects
				(font
					(size 0.7 0.7)
					(thickness 0.15)
				)
				(justify left bottom mirror)
			)
		)
		(fp_text user "${REFERENCE}"
			(at -1.9 -3.947 270)
			(layer "B.Fab")
			(effects
				(font
					(size 0.7 0.7)
					(thickness 0.15)
				)
				(justify left bottom mirror)
			)
		)
		(pad "1" smd roundrect
			(at -1.1 0 90)
			(size 1.2 1.3)
			(layers "B.Cu" "B.Mask" "B.Paste")
			(roundrect_rratio 0.25)
			(net 78 "/Supply/OUT_M2")
			(pintype "passive")
		)
		(pad "2" smd roundrect
			(at 1.1 0 90)
			(size 1.2 1.3)
			(layers "B.Cu" "B.Mask" "B.Paste")
			(roundrect_rratio 0.25)
			(net 3 "GND")
			(pintype "passive")
		)
	)
	(footprint "antmicro-footprints:Vishay_PowerPAK_1212-8_Single"
		(layer "B.Cu")
		(at 42.602962 163.2805 -90)
		(descr "PowerPAK 1212-8 Single")
		(tags "Vishay PowerPAK 1212-8 Single")
		(property "Reference" "Q304"
			(at -1.964 1.485 0)
			(layer "B.SilkS")
			(effects
				(font
					(size 0.7 0.7)
					(thickness 0.15)
				)
				(justify right bottom mirror)
			)
		)
		(property "Value" "SQS401EN-T1_BE3"
			(at 0 -2.7 90)
			(layer "B.Fab")
			(effects
				(font
					(size 0.7 0.7)
					(thickness 0.15)
				)
				(justify left bottom mirror)
			)
		)
		(property "Datasheet" "https://www.vishay.com/docs/65529/sqs401en.pdf"
			(at 0 0 270)
			(layer "B.Fab")
			(hide yes)
			(effects
				(font
					(size 1.27 1.27)
					(thickness 0.15)
				)
			)
		)
		(property "MPN" "SQS401EN-T1_BE3"
			(at 0 0 270)
			(unlocked yes)
			(layer "B.Fab")
			(hide yes)
			(effects
				(font
					(size 1 1)
					(thickness 0.15)
				)
				(justify mirror)
			)
		)
		(property "Manufacturer" "Vishay"
			(at 0 0 270)
			(unlocked yes)
			(layer "B.Fab")
			(hide yes)
			(effects
				(font
					(size 1 1)
					(thickness 0.15)
				)
				(justify mirror)
			)
		)
		(property "Author" "Antmicro"
			(at 0 0 270)
			(unlocked yes)
			(layer "B.Fab")
			(hide yes)
			(effects
				(font
					(size 1 1)
					(thickness 0.15)
				)
				(justify mirror)
			)
		)
		(property "License" "Apache-2.0"
			(at 0 0 270)
			(unlocked yes)
			(layer "B.Fab")
			(hide yes)
			(effects
				(font
					(size 1 1)
					(thickness 0.15)
				)
				(justify mirror)
			)
		)
		(sheetname "/Supply/")
		(sheetfile "supply.kicad_sch")
		(attr smd)
		(fp_line
			(start -1.651 1.651)
			(end 1.648 1.651)
			(stroke
				(width 0.15)
				(type solid)
			)
			(layer "B.SilkS")
		)
		(fp_line
			(start -1.651 1.651)
			(end -1.651 1.317)
			(stroke
				(width 0.15)
				(type solid)
			)
			(layer "B.SilkS")
		)
		(fp_line
			(start 1.648 1.651)
			(end 1.648 1.317)
			(stroke
				(width 0.15)
				(type solid)
			)
			(layer "B.SilkS")
		)
		(fp_line
			(start -1.635 -1.3)
			(end -1.635 -1.634)
			(stroke
				(width 0.15)
				(type solid)
			)
			(layer "B.SilkS")
		)
		(fp_line
			(start 1.634 -1.3)
			(end 1.634 -1.634)
			(stroke
				(width 0.15)
				(type solid)
			)
			(layer "B.SilkS")
		)
		(fp_line
			(start -1.635 -1.634)
			(end 1.634 -1.634)
			(stroke
				(width 0.15)
				(type solid)
			)
			(layer "B.SilkS")
		)
		(fp_circle
			(center -1.9 1.4)
			(end -1.85 1.4)
			(stroke
				(width 0.15)
				(type solid)
			)
			(fill yes)
			(layer "B.SilkS")
		)
		(fp_rect
			(start -2 1.8)
			(end 2 -1.798)
			(stroke
				(width 0.05)
				(type solid)
			)
			(fill no)
			(layer "B.CrtYd")
		)
		(fp_line
			(start -1.6425 1.4175)
			(end -1.4175 1.6425)
			(stroke
				(width 0.15)
				(type solid)
			)
			(layer "B.Fab")
		)
		(fp_rect
			(start -1.651 1.651)
			(end 1.648 -1.648)
			(stroke
				(width 0.15)
				(type solid)
			)
			(fill no)
			(layer "B.Fab")
		)
		(fp_text user "Author: Antmicro"
			(at -8 -5.9 90)
			(layer "B.Fab")
			(effects
				(font
					(size 0.7 0.7)
					(thickness 0.15)
				)
				(justify left bottom mirror)
			)
		)
		(fp_text user "License: Apache-2.0"
			(at -8 -7.1 90)
			(layer "B.Fab")
			(effects
				(font
					(size 0.7 0.7)
					(thickness 0.15)
				)
				(justify left bottom mirror)
			)
		)
		(fp_text user "${REFERENCE}"
			(at -8 -4.7 90)
			(layer "B.Fab")
			(effects
				(font
					(size 0.7 0.7)
					(thickness 0.15)
				)
				(justify left bottom mirror)
			)
		)
		(pad "1" smd rect
			(at -1.436 0.99 270)
			(size 0.99 0.405)
			(layers "B.Cu" "B.Mask" "B.Paste")
			(net 21 "/Supply/VCC_IN")
			(pinfunction "S")
			(pintype "passive")
		)
		(pad "2" smd rect
			(at -1.436 0.332 270)
			(size 0.99 0.405)
			(layers "B.Cu" "B.Mask" "B.Paste")
			(net 21 "/Supply/VCC_IN")
			(pinfunction "S")
			(pintype "passive")
		)
		(pad "3" smd rect
			(at -1.436 -0.33 270)
			(size 0.99 0.405)
			(layers "B.Cu" "B.Mask" "B.Paste")
			(net 21 "/Supply/VCC_IN")
			(pinfunction "S")
			(pintype "passive")
		)
		(pad "4" smd rect
			(at -1.436 -0.988 270)
			(size 0.99 0.405)
			(layers "B.Cu" "B.Mask" "B.Paste")
			(net 333 "Net-(Q301-BIAS)")
			(pinfunction "G")
			(pintype "input")
		)
		(pad "5" smd custom
			(at 0.557 0 270)
			(size 1.725 2.235)
			(layers "B.Cu" "B.Mask" "B.Paste")
			(net 472 "Net-(D301-C)")
			(pinfunction "D")
			(pintype "passive")
			(zone_connect 2)
			(options
				(clearance outline)
				(anchor rect)
			)
			(primitives
				(gr_poly
					(pts
						(xy 0.8625 -0.1275) (xy 0.8625 0.1275) (xy 1.3725 0.1275) (xy 1.3725 0.5325) (xy 0.8625 0.5325)
						(xy 0.8625 0.7875) (xy 1.3725 0.7875) (xy 1.3725 1.195) (xy 0.6125 1.195) (xy 0.6125 -1.195) (xy 1.3725 -1.195)
						(xy 1.3725 -0.7875) (xy 0.8625 -0.7875) (xy 0.8625 -0.5325) (xy 1.3725 -0.5325) (xy 1.3725 -0.1275)
					)
					(width 0)
					(fill yes)
				)
			)
		)
	)
	(footprint "antmicro-footprints:C_0402_1005Metric"
		(layer "B.Cu")
		(at 68.837962 162.1365 180)
		(descr "Capacitor SMD 0402")
		(tags "capacitor SMD 0402")
		(property "Reference" "C309"
			(at -3.77 -0.35 0)
			(layer "B.SilkS")
			(effects
				(font
					(size 0.7 0.7)
					(thickness 0.15)
				)
				(justify left bottom mirror)
			)
		)
		(property "Value" "C_100n_0402"
			(at -1.022927 -2.155213 0)
			(layer "B.Fab")
			(effects
				(font
					(size 0.7 0.7)
					(thickness 0.15)
				)
				(justify left bottom mirror)
			)
		)
		(property "Datasheet" "https://www.murata.com/products/productdetail?partno=GRM155R61H104KE14%23"
			(at 0 0 180)
			(layer "B.Fab")
			(hide yes)
			(effects
				(font
					(size 1.27 1.27)
					(thickness 0.15)
				)
			)
		)
		(property "Manufacturer" "Murata"
			(at 0 0 180)
			(unlocked yes)
			(layer "B.Fab")
			(hide yes)
			(effects
				(font
					(size 1 1)
					(thickness 0.15)
				)
				(justify mirror)
			)
		)
		(property "MPN" "GRM155R61H104KE14D"
			(at 0 0 180)
			(unlocked yes)
			(layer "B.Fab")
			(hide yes)
			(effects
				(font
					(size 1 1)
					(thickness 0.15)
				)
				(justify mirror)
			)
		)
		(property "Val" "100n"
			(at 0 0 180)
			(unlocked yes)
			(layer "B.Fab")
			(hide yes)
			(effects
				(font
					(size 1 1)
					(thickness 0.15)
				)
				(justify mirror)
			)
		)
		(property "License" "Apache-2.0"
			(at 0 0 180)
			(unlocked yes)
			(layer "B.Fab")
			(hide yes)
			(effects
				(font
					(size 1 1)
					(thickness 0.15)
				)
				(justify mirror)
			)
		)
		(property "Author" "Antmicro"
			(at 0 0 180)
			(unlocked yes)
			(layer "B.Fab")
			(hide yes)
			(effects
				(font
					(size 1 1)
					(thickness 0.15)
				)
				(justify mirror)
			)
		)
		(property "Voltage" "50V"
			(at 0 0 180)
			(unlocked yes)
			(layer "B.Fab")
			(hide yes)
			(effects
				(font
					(size 1 1)
					(thickness 0.15)
				)
				(justify mirror)
			)
		)
		(property "Dielectric" "X5R"
			(at 0 0 180)
			(unlocked yes)
			(layer "B.Fab")
			(hide yes)
			(effects
				(font
					(size 1 1)
					(thickness 0.15)
				)
				(justify mirror)
			)
		)
		(sheetname "/Supply/")
		(sheetfile "supply.kicad_sch")
		(attr smd)
		(fp_rect
			(start -0.925 0.47)
			(end 0.925 -0.47)
			(stroke
				(width 0.05)
				(type default)
			)
			(fill no)
			(layer "B.CrtYd")
		)
		(fp_line
			(start 0.504 0.25)
			(end 0.504 -0.248)
			(stroke
				(width 0.15)
				(type solid)
			)
			(layer "B.Fab")
		)
		(fp_line
			(start 0.504 -0.248)
			(end -0.494 -0.248)
			(stroke
				(width 0.15)
				(type solid)
			)
			(layer "B.Fab")
		)
		(fp_line
			(start -0.494 0.25)
			(end 0.504 0.25)
			(stroke
				(width 0.15)
				(type solid)
			)
			(layer "B.Fab")
		)
		(fp_line
			(start -0.494 -0.248)
			(end -0.494 0.25)
			(stroke
				(width 0.15)
				(type solid)
			)
			(layer "B.Fab")
		)
		(fp_text user "License: Apache-2.0"
			(at -0.939 -5.799 0)
			(layer "B.Fab")
			(effects
				(font
					(size 0.7 0.7)
					(thickness 0.15)
				)
				(justify left bottom mirror)
			)
		)
		(fp_text user "${REFERENCE}"
			(at -0.939 -4.599 0)
			(layer "B.Fab")
			(effects
				(font
					(size 0.7 0.7)
					(thickness 0.15)
				)
				(justify left bottom mirror)
			)
		)
		(fp_text user "Author: Antmicro"
			(at -0.939 -3.399 0)
			(layer "B.Fab")
			(effects
				(font
					(size 0.7 0.7)
					(thickness 0.15)
				)
				(justify left bottom mirror)
			)
		)
		(pad "1" smd roundrect
			(at -0.48 0 180)
			(size 0.59 0.64)
			(layers "B.Cu" "B.Mask" "B.Paste")
			(roundrect_rratio 0.25)
			(net 49 "/Supply/SW_3V3")
			(pintype "passive")
		)
		(pad "2" smd roundrect
			(at 0.48 0 180)
			(size 0.59 0.64)
			(layers "B.Cu" "B.Mask" "B.Paste")
			(roundrect_rratio 0.25)
			(net 51 "Net-(U302-BST)")
			(pintype "passive")
		)
	)
	(footprint "antmicro-footprints:C_0805_2012Metric"
		(layer "B.Cu")
		(at 84.667962 127.1165 -90)
		(descr "Capacitor SMD 0805")
		(tags "capacitor SMD 0805")
		(property "Reference" "C905"
			(at 1.81 -0.24 90)
			(layer "B.SilkS")
			(effects
				(font
					(size 0.7 0.7)
					(thickness 0.15)
				)
				(justify left bottom mirror)
			)
		)
		(property "Value" "C_22u_25V_0805"
			(at -2.055717 -1.963152 90)
			(layer "B.Fab")
			(effects
				(font
					(size 0.7 0.7)
					(thickness 0.15)
				)
				(justify left bottom mirror)
			)
		)
		(property "Datasheet" "https://product.samsungsem.com/mlcc/CL21A226MAYNNN.do"
			(at 0 0 270)
			(layer "B.Fab")
			(hide yes)
			(effects
				(font
					(size 1.27 1.27)
					(thickness 0.15)
				)
			)
		)
		(property "Manufacturer" "Samsung Electro-Mechanics"
			(at 0 0 270)
			(unlocked yes)
			(layer "B.Fab")
			(hide yes)
			(effects
				(font
					(size 1 1)
					(thickness 0.15)
				)
				(justify mirror)
			)
		)
		(property "MPN" "CL21A226MAYNNNE"
			(at 0 0 270)
			(unlocked yes)
			(layer "B.Fab")
			(hide yes)
			(effects
				(font
					(size 1 1)
					(thickness 0.15)
				)
				(justify mirror)
			)
		)
		(property "Val" "22u"
			(at 0 0 270)
			(unlocked yes)
			(layer "B.Fab")
			(hide yes)
			(effects
				(font
					(size 1 1)
					(thickness 0.15)
				)
				(justify mirror)
			)
		)
		(property "License" "Apache-2.0"
			(at 0 0 270)
			(unlocked yes)
			(layer "B.Fab")
			(hide yes)
			(effects
				(font
					(size 1 1)
					(thickness 0.15)
				)
				(justify mirror)
			)
		)
		(property "Author" "Antmicro"
			(at 0 0 270)
			(unlocked yes)
			(layer "B.Fab")
			(hide yes)
			(effects
				(font
					(size 1 1)
					(thickness 0.15)
				)
				(justify mirror)
			)
		)
		(property "Voltage" "25V"
			(at 0 0 270)
			(unlocked yes)
			(layer "B.Fab")
			(hide yes)
			(effects
				(font
					(size 1 1)
					(thickness 0.15)
				)
				(justify mirror)
			)
		)
		(property "Dielectric" "X5R"
			(at 0 0 270)
			(unlocked yes)
			(layer "B.Fab")
			(hide yes)
			(effects
				(font
					(size 1 1)
					(thickness 0.15)
				)
				(justify mirror)
			)
		)
		(property "Public" "False"
			(at 0 0 270)
			(unlocked yes)
			(layer "B.Fab")
			(hide yes)
			(effects
				(font
					(size 1 1)
					(thickness 0.15)
				)
				(justify mirror)
			)
		)
		(sheetname "/USB/")
		(sheetfile "usb.kicad_sch")
		(attr smd)
		(fp_line
			(start -0.3 0.7)
			(end 0.3 0.7)
			(stroke
				(width 0.15)
				(type solid)
			)
			(layer "B.SilkS")
		)
		(fp_line
			(start -0.3 -0.7)
			(end 0.3 -0.7)
			(stroke
				(width 0.15)
				(type solid)
			)
			(layer "B.SilkS")
		)
		(fp_rect
			(start 1.95 0.9)
			(end -1.95 -0.9)
			(stroke
				(width 0.05)
				(type default)
			)
			(fill no)
			(layer "B.CrtYd")
		)
		(fp_rect
			(start -0.95 0.675)
			(end 0.95 -0.675)
			(stroke
				(width 0.15)
				(type solid)
			)
			(fill no)
			(layer "B.Fab")
		)
		(fp_text user "${REFERENCE}"
			(at -1.9 -3.947 90)
			(layer "B.Fab")
			(effects
				(font
					(size 0.7 0.7)
					(thickness 0.15)
				)
				(justify left bottom mirror)
			)
		)
		(fp_text user "Author: Antmicro"
			(at -1.9 -5.947 90)
			(layer "B.Fab")
			(effects
				(font
					(size 0.7 0.7)
					(thickness 0.15)
				)
				(justify left bottom mirror)
			)
		)
		(fp_text user "License: Apache-2.0"
			(at -1.9 -4.947 90)
			(layer "B.Fab")
			(effects
				(font
					(size 0.7 0.7)
					(thickness 0.15)
				)
				(justify left bottom mirror)
			)
		)
		(pad "1" smd roundrect
			(at -1.1 0 270)
			(size 1.2 1.3)
			(layers "B.Cu" "B.Mask" "B.Paste")
			(roundrect_rratio 0.25)
			(net 26 "/USB/USBD_VBUS")
			(pintype "passive")
		)
		(pad "2" smd roundrect
			(at 1.1 0 270)
			(size 1.2 1.3)
			(layers "B.Cu" "B.Mask" "B.Paste")
			(roundrect_rratio 0.25)
			(net 3 "GND")
			(pintype "passive")
		)
	)
	(footprint "antmicro-footprints:R_0402_1005Metric"
		(layer "B.Cu")
		(at 52.842962 158.4265)
		(descr "Resistor SMD 0402")
		(tags "resistor SMD 0402")
		(property "Reference" "R317"
			(at -4.215 1.07 0)
			(layer "B.SilkS")
			(effects
				(font
					(size 0.7 0.7)
					(thickness 0.15)
				)
				(justify right bottom mirror)
			)
		)
		(property "Value" "R_2k_0402"
			(at -1.011843 -1.772047 0)
			(layer "B.Fab")
			(effects
				(font
					(size 0.7 0.7)
					(thickness 0.15)
				)
				(justify right bottom mirror)
			)
		)
		(property "Datasheet" "https://www.bourns.com/docs/product-datasheets/cr.pdf"
			(at 0 0 0)
			(layer "B.Fab")
			(hide yes)
			(effects
				(font
					(size 1.27 1.27)
					(thickness 0.15)
				)
			)
		)
		(property "MPN" "CR0402-FX-2001GLF"
			(at 0 0 0)
			(unlocked yes)
			(layer "B.Fab")
			(hide yes)
			(effects
				(font
					(size 1 1)
					(thickness 0.15)
				)
				(justify mirror)
			)
		)
		(property "Manufacturer" "Bourns"
			(at 0 0 0)
			(unlocked yes)
			(layer "B.Fab")
			(hide yes)
			(effects
				(font
					(size 1 1)
					(thickness 0.15)
				)
				(justify mirror)
			)
		)
		(property "License" "Apache-2.0"
			(at 0 0 0)
			(unlocked yes)
			(layer "B.Fab")
			(hide yes)
			(effects
				(font
					(size 1 1)
					(thickness 0.15)
				)
				(justify mirror)
			)
		)
		(property "Author" "Antmicro"
			(at 0 0 0)
			(unlocked yes)
			(layer "B.Fab")
			(hide yes)
			(effects
				(font
					(size 1 1)
					(thickness 0.15)
				)
				(justify mirror)
			)
		)
		(property "Val" "2k"
			(at 0 0 0)
			(unlocked yes)
			(layer "B.Fab")
			(hide yes)
			(effects
				(font
					(size 1 1)
					(thickness 0.15)
				)
				(justify mirror)
			)
		)
		(property "Tolerance" "1%"
			(at 0 0 0)
			(unlocked yes)
			(layer "B.Fab")
			(hide yes)
			(effects
				(font
					(size 1 1)
					(thickness 0.15)
				)
				(justify mirror)
			)
		)
		(sheetname "/Supply/")
		(sheetfile "supply.kicad_sch")
		(attr smd)
		(fp_rect
			(start -0.925 0.47)
			(end 0.925 -0.47)
			(stroke
				(width 0.05)
				(type default)
			)
			(fill no)
			(layer "B.CrtYd")
		)
		(fp_rect
			(start -0.5 0.25)
			(end 0.5 -0.25)
			(stroke
				(width 0.15)
				(type solid)
			)
			(fill no)
			(layer "B.Fab")
		)
		(fp_text user "${REFERENCE}"
			(at -0.95 -3.168 180)
			(layer "B.Fab")
			(effects
				(font
					(size 0.7 0.7)
					(thickness 0.15)
				)
				(justify left bottom mirror)
			)
		)
		(fp_text user "Author: Antmicro"
			(at -0.95 -4.169 180)
			(layer "B.Fab")
			(effects
				(font
					(size 0.7 0.7)
					(thickness 0.15)
				)
				(justify left bottom mirror)
			)
		)
		(fp_text user "License: Apache-2.0"
			(at -0.95 -5.169 180)
			(layer "B.Fab")
			(effects
				(font
					(size 0.7 0.7)
					(thickness 0.15)
				)
				(justify left bottom mirror)
			)
		)
		(pad "1" smd roundrect
			(at -0.48 0)
			(size 0.59 0.64)
			(layers "B.Cu" "B.Mask" "B.Paste")
			(roundrect_rratio 0.25)
			(net 3 "GND")
			(pintype "passive")
		)
		(pad "2" smd roundrect
			(at 0.48 0)
			(size 0.59 0.64)
			(layers "B.Cu" "B.Mask" "B.Paste")
			(roundrect_rratio 0.25)
			(net 353 "/Supply/FB_5V")
			(pintype "passive")
		)
	)
	(footprint "antmicro-footprints:C_0805_2012Metric"
		(layer "B.Cu")
		(at 58.617962 171.3165 -90)
		(descr "Capacitor SMD 0805")
		(tags "capacitor SMD 0805")
		(property "Reference" "C409"
			(at 1.76 -0.4 90)
			(layer "B.SilkS")
			(effects
				(font
					(size 0.7 0.7)
					(thickness 0.15)
				)
				(justify left bottom mirror)
			)
		)
		(property "Value" "C_22u_25V_0805"
			(at -2.055717 -1.963152 90)
			(layer "B.Fab")
			(effects
				(font
					(size 0.7 0.7)
					(thickness 0.15)
				)
				(justify left bottom mirror)
			)
		)
		(property "Datasheet" "https://product.samsungsem.com/mlcc/CL21A226MAYNNN.do"
			(at 0 0 270)
			(layer "B.Fab")
			(hide yes)
			(effects
				(font
					(size 1.27 1.27)
					(thickness 0.15)
				)
			)
		)
		(property "Manufacturer" "Samsung Electro-Mechanics"
			(at 0 0 270)
			(unlocked yes)
			(layer "B.Fab")
			(hide yes)
			(effects
				(font
					(size 1 1)
					(thickness 0.15)
				)
				(justify mirror)
			)
		)
		(property "MPN" "CL21A226MAYNNNE"
			(at 0 0 270)
			(unlocked yes)
			(layer "B.Fab")
			(hide yes)
			(effects
				(font
					(size 1 1)
					(thickness 0.15)
				)
				(justify mirror)
			)
		)
		(property "Val" "22u"
			(at 0 0 270)
			(unlocked yes)
			(layer "B.Fab")
			(hide yes)
			(effects
				(font
					(size 1 1)
					(thickness 0.15)
				)
				(justify mirror)
			)
		)
		(property "License" "Apache-2.0"
			(at 0 0 270)
			(unlocked yes)
			(layer "B.Fab")
			(hide yes)
			(effects
				(font
					(size 1 1)
					(thickness 0.15)
				)
				(justify mirror)
			)
		)
		(property "Author" "Antmicro"
			(at 0 0 270)
			(unlocked yes)
			(layer "B.Fab")
			(hide yes)
			(effects
				(font
					(size 1 1)
					(thickness 0.15)
				)
				(justify mirror)
			)
		)
		(property "Voltage" "25V"
			(at 0 0 270)
			(unlocked yes)
			(layer "B.Fab")
			(hide yes)
			(effects
				(font
					(size 1 1)
					(thickness 0.15)
				)
				(justify mirror)
			)
		)
		(property "Dielectric" "X5R"
			(at 0 0 270)
			(unlocked yes)
			(layer "B.Fab")
			(hide yes)
			(effects
				(font
					(size 1 1)
					(thickness 0.15)
				)
				(justify mirror)
			)
		)
		(property "Public" "False"
			(at 0 0 270)
			(unlocked yes)
			(layer "B.Fab")
			(hide yes)
			(effects
				(font
					(size 1 1)
					(thickness 0.15)
				)
				(justify mirror)
			)
		)
		(sheetname "/Ethernet/")
		(sheetfile "ethernet.kicad_sch")
		(attr smd)
		(fp_line
			(start -0.3 0.7)
			(end 0.3 0.7)
			(stroke
				(width 0.15)
				(type solid)
			)
			(layer "B.SilkS")
		)
		(fp_line
			(start -0.3 -0.7)
			(end 0.3 -0.7)
			(stroke
				(width 0.15)
				(type solid)
			)
			(layer "B.SilkS")
		)
		(fp_rect
			(start 1.95 0.9)
			(end -1.95 -0.9)
			(stroke
				(width 0.05)
				(type default)
			)
			(fill no)
			(layer "B.CrtYd")
		)
		(fp_rect
			(start -0.95 0.675)
			(end 0.95 -0.675)
			(stroke
				(width 0.15)
				(type solid)
			)
			(fill no)
			(layer "B.Fab")
		)
		(fp_text user "Author: Antmicro"
			(at -1.9 -5.947 90)
			(layer "B.Fab")
			(effects
				(font
					(size 0.7 0.7)
					(thickness 0.15)
				)
				(justify left bottom mirror)
			)
		)
		(fp_text user "License: Apache-2.0"
			(at -1.9 -4.947 90)
			(layer "B.Fab")
			(effects
				(font
					(size 0.7 0.7)
					(thickness 0.15)
				)
				(justify left bottom mirror)
			)
		)
		(fp_text user "${REFERENCE}"
			(at -1.9 -3.947 90)
			(layer "B.Fab")
			(effects
				(font
					(size 0.7 0.7)
					(thickness 0.15)
				)
				(justify left bottom mirror)
			)
		)
		(pad "1" smd roundrect
			(at -1.1 0 270)
			(size 1.2 1.3)
			(layers "B.Cu" "B.Mask" "B.Paste")
			(roundrect_rratio 0.25)
			(net 47 "/Ethernet/POE_12V")
			(pintype "passive")
		)
		(pad "2" smd roundrect
			(at 1.1 0 270)
			(size 1.2 1.3)
			(layers "B.Cu" "B.Mask" "B.Paste")
			(roundrect_rratio 0.25)
			(net 3 "GND")
			(pintype "passive")
		)
	)
	(footprint "antmicro-footprints:C_0805_2012Metric"
		(layer "B.Cu")
		(at 107.617962 135.9365 -90)
		(descr "Capacitor SMD 0805")
		(tags "capacitor SMD 0805")
		(property "Reference" "C305"
			(at -0.1 1.12 90)
			(layer "B.SilkS")
			(effects
				(font
					(size 0.7 0.7)
					(thickness 0.15)
				)
				(justify left bottom mirror)
			)
		)
		(property "Value" "C_22u_25V_0805"
			(at -2.055717 -1.963152 90)
			(layer "B.Fab")
			(effects
				(font
					(size 0.7 0.7)
					(thickness 0.15)
				)
				(justify left bottom mirror)
			)
		)
		(property "Datasheet" "https://product.samsungsem.com/mlcc/CL21A226MAYNNN.do"
			(at 0 0 270)
			(layer "B.Fab")
			(hide yes)
			(effects
				(font
					(size 1.27 1.27)
					(thickness 0.15)
				)
			)
		)
		(property "Manufacturer" "Samsung Electro-Mechanics"
			(at 0 0 270)
			(unlocked yes)
			(layer "B.Fab")
			(hide yes)
			(effects
				(font
					(size 1 1)
					(thickness 0.15)
				)
				(justify mirror)
			)
		)
		(property "MPN" "CL21A226MAYNNNE"
			(at 0 0 270)
			(unlocked yes)
			(layer "B.Fab")
			(hide yes)
			(effects
				(font
					(size 1 1)
					(thickness 0.15)
				)
				(justify mirror)
			)
		)
		(property "Val" "22u"
			(at 0 0 270)
			(unlocked yes)
			(layer "B.Fab")
			(hide yes)
			(effects
				(font
					(size 1 1)
					(thickness 0.15)
				)
				(justify mirror)
			)
		)
		(property "License" "Apache-2.0"
			(at 0 0 270)
			(unlocked yes)
			(layer "B.Fab")
			(hide yes)
			(effects
				(font
					(size 1 1)
					(thickness 0.15)
				)
				(justify mirror)
			)
		)
		(property "Author" "Antmicro"
			(at 0 0 270)
			(unlocked yes)
			(layer "B.Fab")
			(hide yes)
			(effects
				(font
					(size 1 1)
					(thickness 0.15)
				)
				(justify mirror)
			)
		)
		(property "Voltage" "25V"
			(at 0 0 270)
			(unlocked yes)
			(layer "B.Fab")
			(hide yes)
			(effects
				(font
					(size 1 1)
					(thickness 0.15)
				)
				(justify mirror)
			)
		)
		(property "Dielectric" "X5R"
			(at 0 0 270)
			(unlocked yes)
			(layer "B.Fab")
			(hide yes)
			(effects
				(font
					(size 1 1)
					(thickness 0.15)
				)
				(justify mirror)
			)
		)
		(property "Public" "False"
			(at 0 0 270)
			(unlocked yes)
			(layer "B.Fab")
			(hide yes)
			(effects
				(font
					(size 1 1)
					(thickness 0.15)
				)
				(justify mirror)
			)
		)
		(sheetname "/Supply/")
		(sheetfile "supply.kicad_sch")
		(attr smd)
		(fp_line
			(start -0.3 0.7)
			(end 0.3 0.7)
			(stroke
				(width 0.15)
				(type solid)
			)
			(layer "B.SilkS")
		)
		(fp_line
			(start -0.3 -0.7)
			(end 0.3 -0.7)
			(stroke
				(width 0.15)
				(type solid)
			)
			(layer "B.SilkS")
		)
		(fp_rect
			(start 1.95 0.9)
			(end -1.95 -0.9)
			(stroke
				(width 0.05)
				(type default)
			)
			(fill no)
			(layer "B.CrtYd")
		)
		(fp_rect
			(start -0.95 0.675)
			(end 0.95 -0.675)
			(stroke
				(width 0.15)
				(type solid)
			)
			(fill no)
			(layer "B.Fab")
		)
		(fp_text user "${REFERENCE}"
			(at -1.9 -3.947 90)
			(layer "B.Fab")
			(effects
				(font
					(size 0.7 0.7)
					(thickness 0.15)
				)
				(justify left bottom mirror)
			)
		)
		(fp_text user "Author: Antmicro"
			(at -1.9 -5.947 90)
			(layer "B.Fab")
			(effects
				(font
					(size 0.7 0.7)
					(thickness 0.15)
				)
				(justify left bottom mirror)
			)
		)
		(fp_text user "License: Apache-2.0"
			(at -1.9 -4.947 90)
			(layer "B.Fab")
			(effects
				(font
					(size 0.7 0.7)
					(thickness 0.15)
				)
				(justify left bottom mirror)
			)
		)
		(pad "1" smd roundrect
			(at -1.1 0 270)
			(size 1.2 1.3)
			(layers "B.Cu" "B.Mask" "B.Paste")
			(roundrect_rratio 0.25)
			(net 43 "VCC")
			(pintype "passive")
		)
		(pad "2" smd roundrect
			(at 1.1 0 270)
			(size 1.2 1.3)
			(layers "B.Cu" "B.Mask" "B.Paste")
			(roundrect_rratio 0.25)
			(net 3 "GND")
			(pintype "passive")
		)
	)
	(footprint "antmicro-footprints:R_0402_1005Metric"
		(layer "B.Cu")
		(at 62.117962 136.1165)
		(descr "Resistor SMD 0402")
		(tags "resistor SMD 0402")
		(property "Reference" "R421"
			(at -1.16 1.39 0)
			(layer "B.SilkS")
			(effects
				(font
					(size 0.7 0.7)
					(thickness 0.15)
				)
				(justify right bottom mirror)
			)
		)
		(property "Value" "R_470R_0402"
			(at -1.011843 -1.772047 0)
			(layer "B.Fab")
			(effects
				(font
					(size 0.7 0.7)
					(thickness 0.15)
				)
				(justify right bottom mirror)
			)
		)
		(property "Datasheet" "https://www.bourns.com/docs/product-datasheets/cr.pdf"
			(at 0 0 0)
			(layer "B.Fab")
			(hide yes)
			(effects
				(font
					(size 1.27 1.27)
					(thickness 0.15)
				)
			)
		)
		(property "Manufacturer" "Bourns"
			(at 0 0 0)
			(unlocked yes)
			(layer "B.Fab")
			(hide yes)
			(effects
				(font
					(size 1 1)
					(thickness 0.15)
				)
				(justify mirror)
			)
		)
		(property "MPN" "CR0402-FX-4700GLF"
			(at 0 0 0)
			(unlocked yes)
			(layer "B.Fab")
			(hide yes)
			(effects
				(font
					(size 1 1)
					(thickness 0.15)
				)
				(justify mirror)
			)
		)
		(property "Val" "470R"
			(at 0 0 0)
			(unlocked yes)
			(layer "B.Fab")
			(hide yes)
			(effects
				(font
					(size 1 1)
					(thickness 0.15)
				)
				(justify mirror)
			)
		)
		(property "License" "Apache-2.0"
			(at 0 0 0)
			(unlocked yes)
			(layer "B.Fab")
			(hide yes)
			(effects
				(font
					(size 1 1)
					(thickness 0.15)
				)
				(justify mirror)
			)
		)
		(property "Author" "Antmicro"
			(at 0 0 0)
			(unlocked yes)
			(layer "B.Fab")
			(hide yes)
			(effects
				(font
					(size 1 1)
					(thickness 0.15)
				)
				(justify mirror)
			)
		)
		(property "Tolerance" "1%"
			(at 0 0 0)
			(unlocked yes)
			(layer "B.Fab")
			(hide yes)
			(effects
				(font
					(size 1 1)
					(thickness 0.15)
				)
				(justify mirror)
			)
		)
		(sheetname "/Ethernet/")
		(sheetfile "ethernet.kicad_sch")
		(attr smd)
		(fp_rect
			(start -0.925 0.47)
			(end 0.925 -0.47)
			(stroke
				(width 0.05)
				(type default)
			)
			(fill no)
			(layer "B.CrtYd")
		)
		(fp_rect
			(start -0.5 0.25)
			(end 0.5 -0.25)
			(stroke
				(width 0.15)
				(type solid)
			)
			(fill no)
			(layer "B.Fab")
		)
		(fp_text user "${REFERENCE}"
			(at -0.95 -3.168 180)
			(layer "B.Fab")
			(effects
				(font
					(size 0.7 0.7)
					(thickness 0.15)
				)
				(justify left bottom mirror)
			)
		)
		(fp_text user "Author: Antmicro"
			(at -0.95 -4.169 180)
			(layer "B.Fab")
			(effects
				(font
					(size 0.7 0.7)
					(thickness 0.15)
				)
				(justify left bottom mirror)
			)
		)
		(fp_text user "License: Apache-2.0"
			(at -0.95 -5.169 180)
			(layer "B.Fab")
			(effects
				(font
					(size 0.7 0.7)
					(thickness 0.15)
				)
				(justify left bottom mirror)
			)
		)
		(pad "1" smd roundrect
			(at -0.48 0)
			(size 0.59 0.64)
			(layers "B.Cu" "B.Mask" "B.Paste")
			(roundrect_rratio 0.25)
			(net 367 "Net-(R421-Pad1)")
			(pintype "passive")
		)
		(pad "2" smd roundrect
			(at 0.48 0)
			(size 0.59 0.64)
			(layers "B.Cu" "B.Mask" "B.Paste")
			(roundrect_rratio 0.25)
			(net 3 "GND")
			(pintype "passive")
		)
	)
	(footprint "antmicro-footprints:SOT-363"
		(layer "B.Cu")
		(at 52.992962 163.6145)
		(property "Reference" "Q303"
			(at 2.125038 1.777 90)
			(layer "B.SilkS")
			(effects
				(font
					(size 0.7 0.7)
					(thickness 0.15)
				)
				(justify right bottom mirror)
			)
		)
		(property "Value" "DZDH0401DW"
			(at 0 -2.2 0)
			(layer "B.Fab")
			(effects
				(font
					(size 0.7 0.7)
					(thickness 0.15)
				)
				(justify right bottom mirror)
			)
		)
		(property "Datasheet" "https://www.mouser.com/datasheet/2/115/DIOD_S_A0011803041_1-2543705.pdf"
			(at 0 0 0)
			(layer "B.Fab")
			(hide yes)
			(effects
				(font
					(size 1.27 1.27)
					(thickness 0.15)
				)
			)
		)
		(property "MPN" "DZDH0401DW"
			(at 0 0 0)
			(unlocked yes)
			(layer "B.Fab")
			(hide yes)
			(effects
				(font
					(size 1 1)
					(thickness 0.15)
				)
				(justify mirror)
			)
		)
		(property "Manufacturer" "Diodes Incorporated"
			(at 0 0 0)
			(unlocked yes)
			(layer "B.Fab")
			(hide yes)
			(effects
				(font
					(size 1 1)
					(thickness 0.15)
				)
				(justify mirror)
			)
		)
		(property "Author" "Antmicro"
			(at 0 0 0)
			(unlocked yes)
			(layer "B.Fab")
			(hide yes)
			(effects
				(font
					(size 1 1)
					(thickness 0.15)
				)
				(justify mirror)
			)
		)
		(property "License" "Apache-2.0"
			(at 0 0 0)
			(unlocked yes)
			(layer "B.Fab")
			(hide yes)
			(effects
				(font
					(size 1 1)
					(thickness 0.15)
				)
				(justify mirror)
			)
		)
		(sheetname "/Supply/")
		(sheetfile "supply.kicad_sch")
		(attr smd)
		(fp_line
			(start -0.8 -1.223)
			(end 0.803 -1.223)
			(stroke
				(width 0.15)
				(type solid)
			)
			(layer "B.SilkS")
		)
		(fp_line
			(start -0.8 -1.146)
			(end -0.8 -1.223)
			(stroke
				(width 0.15)
				(type solid)
			)
			(layer "B.SilkS")
		)
		(fp_line
			(start -0.72 1.153)
			(end -0.72 1.228)
			(stroke
				(width 0.15)
				(type solid)
			)
			(layer "B.SilkS")
		)
		(fp_line
			(start 0.803 -1.146)
			(end 0.803 -1.223)
			(stroke
				(width 0.15)
				(type solid)
			)
			(layer "B.SilkS")
		)
		(fp_line
			(start 0.803 1.153)
			(end 0.803 1.228)
			(stroke
				(width 0.15)
				(type solid)
			)
			(layer "B.SilkS")
		)
		(fp_line
			(start 0.803 1.228)
			(end -0.72 1.228)
			(stroke
				(width 0.15)
				(type solid)
			)
			(layer "B.SilkS")
		)
		(fp_circle
			(center -0.978102 1.2)
			(end -0.928102 1.2)
			(stroke
				(width 0.15)
				(type solid)
			)
			(fill yes)
			(layer "B.SilkS")
		)
		(fp_rect
			(start 1.3 1.3)
			(end -1.3 -1.3)
			(stroke
				(width 0.05)
				(type solid)
			)
			(fill no)
			(layer "B.CrtYd")
		)
		(fp_line
			(start -0.1 1.1)
			(end -0.68 0.52)
			(stroke
				(width 0.15)
				(type solid)
			)
			(layer "B.Fab")
		)
		(fp_rect
			(start 0.68 -1.1)
			(end -0.68 1.1)
			(stroke
				(width 0.15)
				(type solid)
			)
			(fill no)
			(layer "B.Fab")
		)
		(fp_text user "Author: Antmicro"
			(at -1.3 -6.4 180)
			(layer "B.Fab")
			(effects
				(font
					(size 0.7 0.7)
					(thickness 0.15)
				)
				(justify left bottom mirror)
			)
		)
		(fp_text user "License: Apache-2.0"
			(at -1.3 -5.2 180)
			(layer "B.Fab")
			(effects
				(font
					(size 0.7 0.7)
					(thickness 0.15)
				)
				(justify left bottom mirror)
			)
		)
		(fp_text user "${REFERENCE}"
			(at -1.3 -4 180)
			(layer "B.Fab")
			(effects
				(font
					(size 0.7 0.7)
					(thickness 0.15)
				)
				(justify left bottom mirror)
			)
		)
		(pad "1" smd custom
			(at -0.948 0.752 90)
			(size 0.6 0.6)
			(layers "B.Cu" "B.Mask" "B.Paste")
			(net 496 "unconnected-(Q303-NC-Pad1)")
			(pinfunction "NC")
			(pintype "no_connect")
			(options
				(clearance outline)
				(anchor rect)
			)
			(primitives)
		)
		(pad "2" smd rect
			(at -0.948 0.002 90)
			(size 0.4 0.6)
			(layers "B.Cu" "B.Mask" "B.Paste")
			(net 336 "Net-(Q303-REF)")
			(pinfunction "REF")
			(pintype "input")
		)
		(pad "3" smd custom
			(at -0.948 -0.745 90)
			(size 0.6 0.6)
			(layers "B.Cu" "B.Mask" "B.Paste")
			(net 337 "Net-(Q303-BIAS)")
			(pinfunction "BIAS")
			(pintype "output")
			(options
				(clearance outline)
				(anchor rect)
			)
			(primitives)
		)
		(pad "4" smd custom
			(at 0.951 -0.745 90)
			(size 0.6 0.6)
			(layers "B.Cu" "B.Mask" "B.Paste")
			(net 21 "/Supply/VCC_IN")
			(pinfunction "S")
			(pintype "power_in")
			(options
				(clearance outline)
				(anchor rect)
			)
			(primitives)
		)
		(pad "5" smd rect
			(at 0.951 0.002 90)
			(size 0.4 0.6)
			(layers "B.Cu" "B.Mask" "B.Paste")
			(net 497 "unconnected-(Q303-NC-Pad5)")
			(pinfunction "NC")
			(pintype "no_connect")
		)
		(pad "6" smd custom
			(at 0.951 0.752 90)
			(size 0.6 0.6)
			(layers "B.Cu" "B.Mask" "B.Paste")
			(net 443 "/Supply/V_{BUS}")
			(pinfunction "D")
			(pintype "power_in")
			(options
				(clearance outline)
				(anchor rect)
			)
			(primitives)
		)
	)
	(footprint "antmicro-footprints:R_0402_1005Metric"
		(layer "B.Cu")
		(at 92.537962 154.3665)
		(descr "Resistor SMD 0402")
		(tags "resistor SMD 0402")
		(property "Reference" "R230"
			(at -0.99 3.96 0)
			(layer "B.SilkS")
			(effects
				(font
					(size 0.7 0.7)
					(thickness 0.15)
				)
				(justify right bottom mirror)
			)
		)
		(property "Value" "R_10k_0402"
			(at -1.011843 -1.772047 0)
			(layer "B.Fab")
			(effects
				(font
					(size 0.7 0.7)
					(thickness 0.15)
				)
				(justify right bottom mirror)
			)
		)
		(property "Datasheet" "https://www.bourns.com/docs/product-datasheets/cr.pdf"
			(at 0 0 0)
			(layer "B.Fab")
			(hide yes)
			(effects
				(font
					(size 1.27 1.27)
					(thickness 0.15)
				)
			)
		)
		(property "MPN" "CR0402-FX-1002GLF"
			(at 0 0 0)
			(unlocked yes)
			(layer "B.Fab")
			(hide yes)
			(effects
				(font
					(size 1 1)
					(thickness 0.15)
				)
				(justify mirror)
			)
		)
		(property "Manufacturer" "Bourns"
			(at 0 0 0)
			(unlocked yes)
			(layer "B.Fab")
			(hide yes)
			(effects
				(font
					(size 1 1)
					(thickness 0.15)
				)
				(justify mirror)
			)
		)
		(property "License" "Apache-2.0"
			(at 0 0 0)
			(unlocked yes)
			(layer "B.Fab")
			(hide yes)
			(effects
				(font
					(size 1 1)
					(thickness 0.15)
				)
				(justify mirror)
			)
		)
		(property "Author" "Antmicro"
			(at 0 0 0)
			(unlocked yes)
			(layer "B.Fab")
			(hide yes)
			(effects
				(font
					(size 1 1)
					(thickness 0.15)
				)
				(justify mirror)
			)
		)
		(property "Val" "10k"
			(at 0 0 0)
			(unlocked yes)
			(layer "B.Fab")
			(hide yes)
			(effects
				(font
					(size 1 1)
					(thickness 0.15)
				)
				(justify mirror)
			)
		)
		(property "Tolerance" "1%"
			(at 0 0 0)
			(unlocked yes)
			(layer "B.Fab")
			(hide yes)
			(effects
				(font
					(size 1 1)
					(thickness 0.15)
				)
				(justify mirror)
			)
		)
		(sheetname "/Compute module/")
		(sheetfile "compute-module.kicad_sch")
		(attr smd exclude_from_pos_files exclude_from_bom dnp)
		(fp_rect
			(start -0.925 0.47)
			(end 0.925 -0.47)
			(stroke
				(width 0.05)
				(type default)
			)
			(fill no)
			(layer "B.CrtYd")
		)
		(fp_rect
			(start -0.5 0.25)
			(end 0.5 -0.25)
			(stroke
				(width 0.15)
				(type solid)
			)
			(fill no)
			(layer "B.Fab")
		)
		(fp_text user "License: Apache-2.0"
			(at -0.95 -5.169 180)
			(layer "B.Fab")
			(effects
				(font
					(size 0.7 0.7)
					(thickness 0.15)
				)
				(justify left bottom mirror)
			)
		)
		(fp_text user "${REFERENCE}"
			(at -0.95 -3.168 180)
			(layer "B.Fab")
			(effects
				(font
					(size 0.7 0.7)
					(thickness 0.15)
				)
				(justify left bottom mirror)
			)
		)
		(fp_text user "Author: Antmicro"
			(at -0.95 -4.169 180)
			(layer "B.Fab")
			(effects
				(font
					(size 0.7 0.7)
					(thickness 0.15)
				)
				(justify left bottom mirror)
			)
		)
		(pad "1" smd roundrect
			(at -0.48 0)
			(size 0.59 0.64)
			(layers "B.Cu" "B.Mask" "B.Paste")
			(roundrect_rratio 0.25)
			(net 345 "Net-(U204-A2)")
			(pintype "passive")
		)
		(pad "2" smd roundrect
			(at 0.48 0)
			(size 0.59 0.64)
			(layers "B.Cu" "B.Mask" "B.Paste")
			(roundrect_rratio 0.25)
			(net 9 "+3V3")
			(pintype "passive")
		)
	)
	(footprint "antmicro-footprints:C_0805_2012Metric"
		(layer "B.Cu")
		(at 89.627962 130.7365 180)
		(descr "Capacitor SMD 0805")
		(tags "capacitor SMD 0805")
		(property "Reference" "C911"
			(at -1.85 -2.76 0)
			(layer "B.SilkS")
			(effects
				(font
					(size 0.7 0.7)
					(thickness 0.15)
				)
				(justify left bottom mirror)
			)
		)
		(property "Value" "C_22u_25V_0805"
			(at -2.055717 -1.963152 0)
			(layer "B.Fab")
			(effects
				(font
					(size 0.7 0.7)
					(thickness 0.15)
				)
				(justify left bottom mirror)
			)
		)
		(property "Datasheet" "https://product.samsungsem.com/mlcc/CL21A226MAYNNN.do"
			(at 0 0 180)
			(layer "B.Fab")
			(hide yes)
			(effects
				(font
					(size 1.27 1.27)
					(thickness 0.15)
				)
			)
		)
		(property "Manufacturer" "Samsung Electro-Mechanics"
			(at 0 0 180)
			(unlocked yes)
			(layer "B.Fab")
			(hide yes)
			(effects
				(font
					(size 1 1)
					(thickness 0.15)
				)
				(justify mirror)
			)
		)
		(property "MPN" "CL21A226MAYNNNE"
			(at 0 0 180)
			(unlocked yes)
			(layer "B.Fab")
			(hide yes)
			(effects
				(font
					(size 1 1)
					(thickness 0.15)
				)
				(justify mirror)
			)
		)
		(property "Val" "22u"
			(at 0 0 180)
			(unlocked yes)
			(layer "B.Fab")
			(hide yes)
			(effects
				(font
					(size 1 1)
					(thickness 0.15)
				)
				(justify mirror)
			)
		)
		(property "License" "Apache-2.0"
			(at 0 0 180)
			(unlocked yes)
			(layer "B.Fab")
			(hide yes)
			(effects
				(font
					(size 1 1)
					(thickness 0.15)
				)
				(justify mirror)
			)
		)
		(property "Author" "Antmicro"
			(at 0 0 180)
			(unlocked yes)
			(layer "B.Fab")
			(hide yes)
			(effects
				(font
					(size 1 1)
					(thickness 0.15)
				)
				(justify mirror)
			)
		)
		(property "Voltage" "25V"
			(at 0 0 180)
			(unlocked yes)
			(layer "B.Fab")
			(hide yes)
			(effects
				(font
					(size 1 1)
					(thickness 0.15)
				)
				(justify mirror)
			)
		)
		(property "Dielectric" "X5R"
			(at 0 0 180)
			(unlocked yes)
			(layer "B.Fab")
			(hide yes)
			(effects
				(font
					(size 1 1)
					(thickness 0.15)
				)
				(justify mirror)
			)
		)
		(property "Public" "False"
			(at 0 0 180)
			(unlocked yes)
			(layer "B.Fab")
			(hide yes)
			(effects
				(font
					(size 1 1)
					(thickness 0.15)
				)
				(justify mirror)
			)
		)
		(sheetname "/USB/")
		(sheetfile "usb.kicad_sch")
		(attr smd)
		(fp_line
			(start -0.3 0.7)
			(end 0.3 0.7)
			(stroke
				(width 0.15)
				(type solid)
			)
			(layer "B.SilkS")
		)
		(fp_line
			(start -0.3 -0.7)
			(end 0.3 -0.7)
			(stroke
				(width 0.15)
				(type solid)
			)
			(layer "B.SilkS")
		)
		(fp_rect
			(start 1.95 0.9)
			(end -1.95 -0.9)
			(stroke
				(width 0.05)
				(type default)
			)
			(fill no)
			(layer "B.CrtYd")
		)
		(fp_rect
			(start -0.95 0.675)
			(end 0.95 -0.675)
			(stroke
				(width 0.15)
				(type solid)
			)
			(fill no)
			(layer "B.Fab")
		)
		(fp_text user "Author: Antmicro"
			(at -1.9 -5.947 0)
			(layer "B.Fab")
			(effects
				(font
					(size 0.7 0.7)
					(thickness 0.15)
				)
				(justify left bottom mirror)
			)
		)
		(fp_text user "License: Apache-2.0"
			(at -1.9 -4.947 0)
			(layer "B.Fab")
			(effects
				(font
					(size 0.7 0.7)
					(thickness 0.15)
				)
				(justify left bottom mirror)
			)
		)
		(fp_text user "${REFERENCE}"
			(at -1.9 -3.947 0)
			(layer "B.Fab")
			(effects
				(font
					(size 0.7 0.7)
					(thickness 0.15)
				)
				(justify left bottom mirror)
			)
		)
		(pad "1" smd roundrect
			(at -1.1 0 180)
			(size 1.2 1.3)
			(layers "B.Cu" "B.Mask" "B.Paste")
			(roundrect_rratio 0.25)
			(net 113 "/USB/OUT_FTDI")
			(pintype "passive")
		)
		(pad "2" smd roundrect
			(at 1.1 0 180)
			(size 1.2 1.3)
			(layers "B.Cu" "B.Mask" "B.Paste")
			(roundrect_rratio 0.25)
			(net 3 "GND")
			(pintype "passive")
		)
	)
	(footprint "antmicro-footprints:R_0402_1005Metric"
		(layer "B.Cu")
		(at 80.817962 133.7915 180)
		(descr "Resistor SMD 0402")
		(tags "resistor SMD 0402")
		(property "Reference" "R908"
			(at -3.66 -0.445 0)
			(layer "B.SilkS")
			(effects
				(font
					(size 0.7 0.7)
					(thickness 0.15)
				)
				(justify left bottom mirror)
			)
		)
		(property "Value" "R_10k_0402"
			(at -1.011843 -1.772047 0)
			(layer "B.Fab")
			(effects
				(font
					(size 0.7 0.7)
					(thickness 0.15)
				)
				(justify left bottom mirror)
			)
		)
		(property "Datasheet" "https://www.bourns.com/docs/product-datasheets/cr.pdf"
			(at 0 0 180)
			(layer "B.Fab")
			(hide yes)
			(effects
				(font
					(size 1.27 1.27)
					(thickness 0.15)
				)
			)
		)
		(property "Manufacturer" "Bourns"
			(at 0 0 180)
			(unlocked yes)
			(layer "B.Fab")
			(hide yes)
			(effects
				(font
					(size 1 1)
					(thickness 0.15)
				)
				(justify mirror)
			)
		)
		(property "MPN" "CR0402-FX-1002GLF"
			(at 0 0 180)
			(unlocked yes)
			(layer "B.Fab")
			(hide yes)
			(effects
				(font
					(size 1 1)
					(thickness 0.15)
				)
				(justify mirror)
			)
		)
		(property "Val" "10k"
			(at 0 0 180)
			(unlocked yes)
			(layer "B.Fab")
			(hide yes)
			(effects
				(font
					(size 1 1)
					(thickness 0.15)
				)
				(justify mirror)
			)
		)
		(property "License" "Apache-2.0"
			(at 0 0 180)
			(unlocked yes)
			(layer "B.Fab")
			(hide yes)
			(effects
				(font
					(size 1 1)
					(thickness 0.15)
				)
				(justify mirror)
			)
		)
		(property "Author" "Antmicro"
			(at 0 0 180)
			(unlocked yes)
			(layer "B.Fab")
			(hide yes)
			(effects
				(font
					(size 1 1)
					(thickness 0.15)
				)
				(justify mirror)
			)
		)
		(property "Tolerance" "1%"
			(at 0 0 180)
			(unlocked yes)
			(layer "B.Fab")
			(hide yes)
			(effects
				(font
					(size 1 1)
					(thickness 0.15)
				)
				(justify mirror)
			)
		)
		(sheetname "/USB/")
		(sheetfile "usb.kicad_sch")
		(attr smd exclude_from_pos_files exclude_from_bom dnp)
		(fp_rect
			(start -0.925 0.47)
			(end 0.925 -0.47)
			(stroke
				(width 0.05)
				(type default)
			)
			(fill no)
			(layer "B.CrtYd")
		)
		(fp_rect
			(start -0.5 0.25)
			(end 0.5 -0.25)
			(stroke
				(width 0.15)
				(type solid)
			)
			(fill no)
			(layer "B.Fab")
		)
		(fp_text user "Author: Antmicro"
			(at -0.95 -4.169 0)
			(layer "B.Fab")
			(effects
				(font
					(size 0.7 0.7)
					(thickness 0.15)
				)
				(justify left bottom mirror)
			)
		)
		(fp_text user "${REFERENCE}"
			(at -0.95 -3.168 0)
			(layer "B.Fab")
			(effects
				(font
					(size 0.7 0.7)
					(thickness 0.15)
				)
				(justify left bottom mirror)
			)
		)
		(fp_text user "License: Apache-2.0"
			(at -0.95 -5.169 0)
			(layer "B.Fab")
			(effects
				(font
					(size 0.7 0.7)
					(thickness 0.15)
				)
				(justify left bottom mirror)
			)
		)
		(pad "1" smd roundrect
			(at -0.48 0 180)
			(size 0.59 0.64)
			(layers "B.Cu" "B.Mask" "B.Paste")
			(roundrect_rratio 0.25)
			(net 27 "/USB/USB_3V3")
			(pintype "passive")
		)
		(pad "2" smd roundrect
			(at 0.48 0 180)
			(size 0.59 0.64)
			(layers "B.Cu" "B.Mask" "B.Paste")
			(roundrect_rratio 0.25)
			(net 282 "/USB/EECLK")
			(pintype "passive")
		)
	)
	(footprint "antmicro-footprints:C_0402_1005Metric"
		(layer "B.Cu")
		(at 66.417962 133.9165)
		(descr "Capacitor SMD 0402")
		(tags "capacitor SMD 0402")
		(property "Reference" "C402"
			(at -1.33 1.55 0)
			(layer "B.SilkS")
			(effects
				(font
					(size 0.7 0.7)
					(thickness 0.15)
				)
				(justify right bottom mirror)
			)
		)
		(property "Value" "C_10n_0402"
			(at -1.022927 -2.155213 0)
			(layer "B.Fab")
			(effects
				(font
					(size 0.7 0.7)
					(thickness 0.15)
				)
				(justify right bottom mirror)
			)
		)
		(property "Datasheet" "https://www.murata.com/products/productdetail?partno=GRM155R71H103KA88%23"
			(at 0 0 0)
			(layer "B.Fab")
			(hide yes)
			(effects
				(font
					(size 1.27 1.27)
					(thickness 0.15)
				)
			)
		)
		(property "Manufacturer" "Murata"
			(at 0 0 0)
			(unlocked yes)
			(layer "B.Fab")
			(hide yes)
			(effects
				(font
					(size 1 1)
					(thickness 0.15)
				)
				(justify mirror)
			)
		)
		(property "MPN" "GRM155R71H103KA88D"
			(at 0 0 0)
			(unlocked yes)
			(layer "B.Fab")
			(hide yes)
			(effects
				(font
					(size 1 1)
					(thickness 0.15)
				)
				(justify mirror)
			)
		)
		(property "Val" "10n"
			(at 0 0 0)
			(unlocked yes)
			(layer "B.Fab")
			(hide yes)
			(effects
				(font
					(size 1 1)
					(thickness 0.15)
				)
				(justify mirror)
			)
		)
		(property "License" "Apache-2.0"
			(at 0 0 0)
			(unlocked yes)
			(layer "B.Fab")
			(hide yes)
			(effects
				(font
					(size 1 1)
					(thickness 0.15)
				)
				(justify mirror)
			)
		)
		(property "Author" "Antmicro"
			(at 0 0 0)
			(unlocked yes)
			(layer "B.Fab")
			(hide yes)
			(effects
				(font
					(size 1 1)
					(thickness 0.15)
				)
				(justify mirror)
			)
		)
		(property "Voltage" "50V"
			(at 0 0 0)
			(unlocked yes)
			(layer "B.Fab")
			(hide yes)
			(effects
				(font
					(size 1 1)
					(thickness 0.15)
				)
				(justify mirror)
			)
		)
		(property "Dielectric" "X7R"
			(at 0 0 0)
			(unlocked yes)
			(layer "B.Fab")
			(hide yes)
			(effects
				(font
					(size 1 1)
					(thickness 0.15)
				)
				(justify mirror)
			)
		)
		(sheetname "/Ethernet/")
		(sheetfile "ethernet.kicad_sch")
		(attr smd)
		(fp_rect
			(start -0.925 0.47)
			(end 0.925 -0.47)
			(stroke
				(width 0.05)
				(type default)
			)
			(fill no)
			(layer "B.CrtYd")
		)
		(fp_line
			(start -0.494 -0.248)
			(end -0.494 0.25)
			(stroke
				(width 0.15)
				(type solid)
			)
			(layer "B.Fab")
		)
		(fp_line
			(start -0.494 0.25)
			(end 0.504 0.25)
			(stroke
				(width 0.15)
				(type solid)
			)
			(layer "B.Fab")
		)
		(fp_line
			(start 0.504 -0.248)
			(end -0.494 -0.248)
			(stroke
				(width 0.15)
				(type solid)
			)
			(layer "B.Fab")
		)
		(fp_line
			(start 0.504 0.25)
			(end 0.504 -0.248)
			(stroke
				(width 0.15)
				(type solid)
			)
			(layer "B.Fab")
		)
		(fp_text user "Author: Antmicro"
			(at -0.939 -3.399 180)
			(layer "B.Fab")
			(effects
				(font
					(size 0.7 0.7)
					(thickness 0.15)
				)
				(justify left bottom mirror)
			)
		)
		(fp_text user "${REFERENCE}"
			(at -0.939 -4.599 180)
			(layer "B.Fab")
			(effects
				(font
					(size 0.7 0.7)
					(thickness 0.15)
				)
				(justify left bottom mirror)
			)
		)
		(fp_text user "License: Apache-2.0"
			(at -0.939 -5.799 180)
			(layer "B.Fab")
			(effects
				(font
					(size 0.7 0.7)
					(thickness 0.15)
				)
				(justify left bottom mirror)
			)
		)
		(pad "1" smd roundrect
			(at -0.48 0)
			(size 0.59 0.64)
			(layers "B.Cu" "B.Mask" "B.Paste")
			(roundrect_rratio 0.25)
			(net 91 "Net-(J401-P4)")
			(pintype "passive")
		)
		(pad "2" smd roundrect
			(at 0.48 0)
			(size 0.59 0.64)
			(layers "B.Cu" "B.Mask" "B.Paste")
			(roundrect_rratio 0.25)
			(net 3 "GND")
			(pintype "passive")
		)
	)
	(footprint "antmicro-footprints:R_0402_1005Metric"
		(layer "B.Cu")
		(at 126.4 170 180)
		(descr "Resistor SMD 0402")
		(tags "resistor SMD 0402")
		(property "Reference" "R513"
			(at 1.01 -0.435 0)
			(layer "B.SilkS")
			(effects
				(font
					(size 0.7 0.7)
					(thickness 0.15)
				)
				(justify left bottom mirror)
			)
		)
		(property "Value" "R_10k_0402"
			(at -1.011843 -1.772047 0)
			(layer "B.Fab")
			(effects
				(font
					(size 0.7 0.7)
					(thickness 0.15)
				)
				(justify left bottom mirror)
			)
		)
		(property "Datasheet" "https://www.bourns.com/docs/product-datasheets/cr.pdf"
			(at 0 0 180)
			(layer "B.Fab")
			(hide yes)
			(effects
				(font
					(size 1.27 1.27)
					(thickness 0.15)
				)
			)
		)
		(property "Manufacturer" "Bourns"
			(at 0 0 180)
			(unlocked yes)
			(layer "B.Fab")
			(hide yes)
			(effects
				(font
					(size 1 1)
					(thickness 0.15)
				)
				(justify mirror)
			)
		)
		(property "MPN" "CR0402-FX-1002GLF"
			(at 0 0 180)
			(unlocked yes)
			(layer "B.Fab")
			(hide yes)
			(effects
				(font
					(size 1 1)
					(thickness 0.15)
				)
				(justify mirror)
			)
		)
		(property "Val" "10k"
			(at 0 0 180)
			(unlocked yes)
			(layer "B.Fab")
			(hide yes)
			(effects
				(font
					(size 1 1)
					(thickness 0.15)
				)
				(justify mirror)
			)
		)
		(property "License" "Apache-2.0"
			(at 0 0 180)
			(unlocked yes)
			(layer "B.Fab")
			(hide yes)
			(effects
				(font
					(size 1 1)
					(thickness 0.15)
				)
				(justify mirror)
			)
		)
		(property "Author" "Antmicro"
			(at 0 0 180)
			(unlocked yes)
			(layer "B.Fab")
			(hide yes)
			(effects
				(font
					(size 1 1)
					(thickness 0.15)
				)
				(justify mirror)
			)
		)
		(property "Tolerance" "1%"
			(at 0 0 180)
			(unlocked yes)
			(layer "B.Fab")
			(hide yes)
			(effects
				(font
					(size 1 1)
					(thickness 0.15)
				)
				(justify mirror)
			)
		)
		(sheetname "/NVMe & microSD/")
		(sheetfile "nvme-micro-sd.kicad_sch")
		(attr smd)
		(fp_rect
			(start -0.925 0.47)
			(end 0.925 -0.47)
			(stroke
				(width 0.05)
				(type default)
			)
			(fill no)
			(layer "B.CrtYd")
		)
		(fp_rect
			(start -0.5 0.25)
			(end 0.5 -0.25)
			(stroke
				(width 0.15)
				(type solid)
			)
			(fill no)
			(layer "B.Fab")
		)
		(fp_text user "${REFERENCE}"
			(at -0.95 -3.168 0)
			(layer "B.Fab")
			(effects
				(font
					(size 0.7 0.7)
					(thickness 0.15)
				)
				(justify left bottom mirror)
			)
		)
		(fp_text user "Author: Antmicro"
			(at -0.95 -4.169 0)
			(layer "B.Fab")
			(effects
				(font
					(size 0.7 0.7)
					(thickness 0.15)
				)
				(justify left bottom mirror)
			)
		)
		(fp_text user "License: Apache-2.0"
			(at -0.95 -5.169 0)
			(layer "B.Fab")
			(effects
				(font
					(size 0.7 0.7)
					(thickness 0.15)
				)
				(justify left bottom mirror)
			)
		)
		(pad "1" smd roundrect
			(at -0.48 0 180)
			(size 0.59 0.64)
			(layers "B.Cu" "B.Mask" "B.Paste")
			(roundrect_rratio 0.25)
			(net 263 "Net-(J502-CD2)")
			(pintype "passive")
		)
		(pad "2" smd roundrect
			(at 0.48 0 180)
			(size 0.59 0.64)
			(layers "B.Cu" "B.Mask" "B.Paste")
			(roundrect_rratio 0.25)
			(net 3 "GND")
			(pintype "passive")
		)
	)
	(footprint "antmicro-footprints:C_0402_1005Metric"
		(layer "B.Cu")
		(at 56.167962 155.3165 90)
		(descr "Capacitor SMD 0402")
		(tags "capacitor SMD 0402")
		(property "Reference" "C310"
			(at 1.505 3.17 90)
			(layer "B.SilkS")
			(effects
				(font
					(size 0.7 0.7)
					(thickness 0.15)
				)
				(justify right bottom mirror)
			)
		)
		(property "Value" "C_100n_0402"
			(at -1.022927 -2.155213 90)
			(layer "B.Fab")
			(effects
				(font
					(size 0.7 0.7)
					(thickness 0.15)
				)
				(justify right bottom mirror)
			)
		)
		(property "Datasheet" "https://www.murata.com/products/productdetail?partno=GRM155R61H104KE14%23"
			(at 0 0 90)
			(layer "B.Fab")
			(hide yes)
			(effects
				(font
					(size 1.27 1.27)
					(thickness 0.15)
				)
			)
		)
		(property "Manufacturer" "Murata"
			(at 0 0 90)
			(unlocked yes)
			(layer "B.Fab")
			(hide yes)
			(effects
				(font
					(size 1 1)
					(thickness 0.15)
				)
				(justify mirror)
			)
		)
		(property "MPN" "GRM155R61H104KE14D"
			(at 0 0 90)
			(unlocked yes)
			(layer "B.Fab")
			(hide yes)
			(effects
				(font
					(size 1 1)
					(thickness 0.15)
				)
				(justify mirror)
			)
		)
		(property "Val" "100n"
			(at 0 0 90)
			(unlocked yes)
			(layer "B.Fab")
			(hide yes)
			(effects
				(font
					(size 1 1)
					(thickness 0.15)
				)
				(justify mirror)
			)
		)
		(property "License" "Apache-2.0"
			(at 0 0 90)
			(unlocked yes)
			(layer "B.Fab")
			(hide yes)
			(effects
				(font
					(size 1 1)
					(thickness 0.15)
				)
				(justify mirror)
			)
		)
		(property "Author" "Antmicro"
			(at 0 0 90)
			(unlocked yes)
			(layer "B.Fab")
			(hide yes)
			(effects
				(font
					(size 1 1)
					(thickness 0.15)
				)
				(justify mirror)
			)
		)
		(property "Voltage" "50V"
			(at 0 0 90)
			(unlocked yes)
			(layer "B.Fab")
			(hide yes)
			(effects
				(font
					(size 1 1)
					(thickness 0.15)
				)
				(justify mirror)
			)
		)
		(property "Dielectric" "X5R"
			(at 0 0 90)
			(unlocked yes)
			(layer "B.Fab")
			(hide yes)
			(effects
				(font
					(size 1 1)
					(thickness 0.15)
				)
				(justify mirror)
			)
		)
		(sheetname "/Supply/")
		(sheetfile "supply.kicad_sch")
		(attr smd)
		(fp_rect
			(start -0.925 0.47)
			(end 0.925 -0.47)
			(stroke
				(width 0.05)
				(type default)
			)
			(fill no)
			(layer "B.CrtYd")
		)
		(fp_line
			(start 0.504 -0.248)
			(end -0.494 -0.248)
			(stroke
				(width 0.15)
				(type solid)
			)
			(layer "B.Fab")
		)
		(fp_line
			(start -0.494 -0.248)
			(end -0.494 0.25)
			(stroke
				(width 0.15)
				(type solid)
			)
			(layer "B.Fab")
		)
		(fp_line
			(start 0.504 0.25)
			(end 0.504 -0.248)
			(stroke
				(width 0.15)
				(type solid)
			)
			(layer "B.Fab")
		)
		(fp_line
			(start -0.494 0.25)
			(end 0.504 0.25)
			(stroke
				(width 0.15)
				(type solid)
			)
			(layer "B.Fab")
		)
		(fp_text user "License: Apache-2.0"
			(at -0.939 -5.799 270)
			(layer "B.Fab")
			(effects
				(font
					(size 0.7 0.7)
					(thickness 0.15)
				)
				(justify left bottom mirror)
			)
		)
		(fp_text user "${REFERENCE}"
			(at -0.939 -4.599 270)
			(layer "B.Fab")
			(effects
				(font
					(size 0.7 0.7)
					(thickness 0.15)
				)
				(justify left bottom mirror)
			)
		)
		(fp_text user "Author: Antmicro"
			(at -0.939 -3.399 270)
			(layer "B.Fab")
			(effects
				(font
					(size 0.7 0.7)
					(thickness 0.15)
				)
				(justify left bottom mirror)
			)
		)
		(pad "1" smd roundrect
			(at -0.48 0 90)
			(size 0.59 0.64)
			(layers "B.Cu" "B.Mask" "B.Paste")
			(roundrect_rratio 0.25)
			(net 59 "/Supply/SW_5V")
			(pintype "passive")
		)
		(pad "2" smd roundrect
			(at 0.48 0 90)
			(size 0.59 0.64)
			(layers "B.Cu" "B.Mask" "B.Paste")
			(roundrect_rratio 0.25)
			(net 60 "Net-(U303-BST)")
			(pintype "passive")
		)
	)
	(footprint "antmicro-footprints:Nexperia_DFN-10_2.5x1mm_P0.5mm"
		(layer "B.Cu")
		(at 101.080962 172.6785 90)
		(property "Reference" "D704"
			(at -0.608 2.597 90)
			(layer "B.SilkS")
			(effects
				(font
					(size 0.7 0.7)
					(thickness 0.15)
				)
				(justify right bottom mirror)
			)
		)
		(property "Value" "PUSB3F96X_PASS"
			(at -0.016 -1.705 90)
			(layer "B.Fab")
			(effects
				(font
					(size 0.7 0.7)
					(thickness 0.15)
				)
				(justify right bottom mirror)
			)
		)
		(property "Datasheet" "https://mouser.com/datasheet/2/916/PUSB3F96-1600324.pdf"
			(at 0 0 90)
			(layer "B.Fab")
			(hide yes)
			(effects
				(font
					(size 1.27 1.27)
					(thickness 0.15)
				)
			)
		)
		(property "Manufacturer" "Nexperia"
			(at 0 0 90)
			(unlocked yes)
			(layer "B.Fab")
			(hide yes)
			(effects
				(font
					(size 1 1)
					(thickness 0.15)
				)
				(justify mirror)
			)
		)
		(property "MPN" "PUSB3F96X"
			(at 0 0 90)
			(unlocked yes)
			(layer "B.Fab")
			(hide yes)
			(effects
				(font
					(size 1 1)
					(thickness 0.15)
				)
				(justify mirror)
			)
		)
		(property "Author" "Antmicro"
			(at 0 0 90)
			(unlocked yes)
			(layer "B.Fab")
			(hide yes)
			(effects
				(font
					(size 1 1)
					(thickness 0.15)
				)
				(justify mirror)
			)
		)
		(property "License" "Apache-2.0"
			(at 0 0 90)
			(unlocked yes)
			(layer "B.Fab")
			(hide yes)
			(effects
				(font
					(size 1 1)
					(thickness 0.15)
				)
				(justify mirror)
			)
		)
		(sheetname "/Display/")
		(sheetfile "display.kicad_sch")
		(attr smd)
		(fp_line
			(start 1.375 -0.4)
			(end 1.375 0.4)
			(stroke
				(width 0.15)
				(type solid)
			)
			(layer "B.SilkS")
		)
		(fp_line
			(start -1.375 0.4)
			(end -1.375 -0.4)
			(stroke
				(width 0.15)
				(type solid)
			)
			(layer "B.SilkS")
		)
		(fp_circle
			(center -1.4 -0.7)
			(end -1.349 -0.7)
			(stroke
				(width 0.15)
				(type solid)
			)
			(fill yes)
			(layer "B.SilkS")
		)
		(fp_rect
			(start -1.4 0.725)
			(end 1.4 -0.725)
			(stroke
				(width 0.05)
				(type solid)
			)
			(fill no)
			(layer "B.CrtYd")
		)
		(fp_line
			(start 1.25 -0.5)
			(end 1.25 0.5)
			(stroke
				(width 0.15)
				(type solid)
			)
			(layer "B.Fab")
		)
		(fp_line
			(start -0.9 -0.5)
			(end 1.25 -0.5)
			(stroke
				(width 0.15)
				(type solid)
			)
			(layer "B.Fab")
		)
		(fp_line
			(start -1.25 -0.15)
			(end -0.9 -0.5)
			(stroke
				(width 0.15)
				(type solid)
			)
			(layer "B.Fab")
		)
		(fp_line
			(start 1.25 0.5)
			(end -1.25 0.5)
			(stroke
				(width 0.15)
				(type solid)
			)
			(layer "B.Fab")
		)
		(fp_line
			(start -1.25 0.5)
			(end -1.25 -0.15)
			(stroke
				(width 0.15)
				(type solid)
			)
			(layer "B.Fab")
		)
		(fp_text user "${REFERENCE}"
			(at -1.367 -3.704 270)
			(layer "B.Fab")
			(effects
				(font
					(size 0.7 0.7)
					(thickness 0.15)
				)
				(justify left bottom mirror)
			)
		)
		(fp_text user "Author: Antmicro"
			(at -1.367 -4.905 270)
			(layer "B.Fab")
			(effects
				(font
					(size 0.7 0.7)
					(thickness 0.15)
				)
				(justify left bottom mirror)
			)
		)
		(fp_text user "License: Apache-2.0"
			(at -1.367 -6.105 270)
			(layer "B.Fab")
			(effects
				(font
					(size 0.7 0.7)
					(thickness 0.15)
				)
				(justify left bottom mirror)
			)
		)
		(pad "1" smd rect
			(at -1 -0.3875 90)
			(size 0.2 0.475)
			(layers "B.Cu" "B.Mask" "B.Paste")
			(net 143 "/CSI/I_{2}C1.SDA")
			(pinfunction "CH1")
			(pintype "passive")
			(solder_mask_margin 0.05)
		)
		(pad "2" smd rect
			(at -0.5 -0.3875 90)
			(size 0.2 0.475)
			(layers "B.Cu" "B.Mask" "B.Paste")
			(net 142 "/CSI/I_{2}C1.SCL")
			(pinfunction "CH2")
			(pintype "passive")
			(solder_mask_margin 0.05)
		)
		(pad "3" smd rect
			(at 0 -0.3875 90)
			(size 0.2 0.475)
			(layers "B.Cu" "B.Mask" "B.Paste")
			(net 3 "GND")
			(pinfunction "GND")
			(pintype "passive")
			(solder_mask_margin 0.05)
		)
		(pad "4" smd rect
			(at 0.5 -0.3875 90)
			(size 0.2 0.475)
			(layers "B.Cu" "B.Mask" "B.Paste")
			(net 120 "/Compute module/DSICtrl.IRQ1")
			(pinfunction "CH3")
			(pintype "passive")
			(solder_mask_margin 0.05)
		)
		(pad "5" smd rect
			(at 1 -0.3875 90)
			(size 0.2 0.475)
			(layers "B.Cu" "B.Mask" "B.Paste")
			(net 121 "/Compute module/DSICtrl.~{IRQ2}")
			(pinfunction "CH4")
			(pintype "passive")
			(solder_mask_margin 0.05)
		)
		(pad "6" smd rect
			(at 1 0.3875 90)
			(size 0.2 0.475)
			(layers "B.Cu" "B.Mask" "B.Paste")
			(net 121 "/Compute module/DSICtrl.~{IRQ2}")
			(pinfunction "CH4")
			(pintype "passive")
			(solder_mask_margin 0.05)
		)
		(pad "7" smd rect
			(at 0.5 0.3875 90)
			(size 0.2 0.475)
			(layers "B.Cu" "B.Mask" "B.Paste")
			(net 120 "/Compute module/DSICtrl.IRQ1")
			(pinfunction "CH3")
			(pintype "passive")
			(solder_mask_margin 0.05)
		)
		(pad "8" smd rect
			(at 0 0.3875 90)
			(size 0.2 0.475)
			(layers "B.Cu" "B.Mask" "B.Paste")
			(net 3 "GND")
			(pinfunction "GND")
			(pintype "passive")
			(solder_mask_margin 0.05)
		)
		(pad "9" smd rect
			(at -0.501 0.3875 90)
			(size 0.2 0.475)
			(layers "B.Cu" "B.Mask" "B.Paste")
			(net 142 "/CSI/I_{2}C1.SCL")
			(pinfunction "CH2")
			(pintype "passive")
			(solder_mask_margin 0.05)
		)
		(pad "10" smd rect
			(at -1 0.3875 90)
			(size 0.2 0.475)
			(layers "B.Cu" "B.Mask" "B.Paste")
			(net 143 "/CSI/I_{2}C1.SDA")
			(pinfunction "CH1")
			(pintype "passive")
			(solder_mask_margin 0.05)
		)
	)
	(footprint "antmicro-footprints:R_0402_1005Metric"
		(layer "B.Cu")
		(at 80.817962 132.5165 180)
		(descr "Resistor SMD 0402")
		(tags "resistor SMD 0402")
		(property "Reference" "R911"
			(at -3.63 -0.41 0)
			(layer "B.SilkS")
			(effects
				(font
					(size 0.7 0.7)
					(thickness 0.15)
				)
				(justify left bottom mirror)
			)
		)
		(property "Value" "R_10k_0402"
			(at -1.011843 -1.772047 0)
			(layer "B.Fab")
			(effects
				(font
					(size 0.7 0.7)
					(thickness 0.15)
				)
				(justify left bottom mirror)
			)
		)
		(property "Datasheet" "https://www.bourns.com/docs/product-datasheets/cr.pdf"
			(at 0 0 180)
			(layer "B.Fab")
			(hide yes)
			(effects
				(font
					(size 1.27 1.27)
					(thickness 0.15)
				)
			)
		)
		(property "Manufacturer" "Bourns"
			(at 0 0 180)
			(unlocked yes)
			(layer "B.Fab")
			(hide yes)
			(effects
				(font
					(size 1 1)
					(thickness 0.15)
				)
				(justify mirror)
			)
		)
		(property "MPN" "CR0402-FX-1002GLF"
			(at 0 0 180)
			(unlocked yes)
			(layer "B.Fab")
			(hide yes)
			(effects
				(font
					(size 1 1)
					(thickness 0.15)
				)
				(justify mirror)
			)
		)
		(property "Val" "10k"
			(at 0 0 180)
			(unlocked yes)
			(layer "B.Fab")
			(hide yes)
			(effects
				(font
					(size 1 1)
					(thickness 0.15)
				)
				(justify mirror)
			)
		)
		(property "License" "Apache-2.0"
			(at 0 0 180)
			(unlocked yes)
			(layer "B.Fab")
			(hide yes)
			(effects
				(font
					(size 1 1)
					(thickness 0.15)
				)
				(justify mirror)
			)
		)
		(property "Author" "Antmicro"
			(at 0 0 180)
			(unlocked yes)
			(layer "B.Fab")
			(hide yes)
			(effects
				(font
					(size 1 1)
					(thickness 0.15)
				)
				(justify mirror)
			)
		)
		(property "Tolerance" "1%"
			(at 0 0 180)
			(unlocked yes)
			(layer "B.Fab")
			(hide yes)
			(effects
				(font
					(size 1 1)
					(thickness 0.15)
				)
				(justify mirror)
			)
		)
		(sheetname "/USB/")
		(sheetfile "usb.kicad_sch")
		(attr smd exclude_from_pos_files exclude_from_bom dnp)
		(fp_rect
			(start -0.925 0.47)
			(end 0.925 -0.47)
			(stroke
				(width 0.05)
				(type default)
			)
			(fill no)
			(layer "B.CrtYd")
		)
		(fp_rect
			(start -0.5 0.25)
			(end 0.5 -0.25)
			(stroke
				(width 0.15)
				(type solid)
			)
			(fill no)
			(layer "B.Fab")
		)
		(fp_text user "Author: Antmicro"
			(at -0.95 -4.169 0)
			(layer "B.Fab")
			(effects
				(font
					(size 0.7 0.7)
					(thickness 0.15)
				)
				(justify left bottom mirror)
			)
		)
		(fp_text user "${REFERENCE}"
			(at -0.95 -3.168 0)
			(layer "B.Fab")
			(effects
				(font
					(size 0.7 0.7)
					(thickness 0.15)
				)
				(justify left bottom mirror)
			)
		)
		(fp_text user "License: Apache-2.0"
			(at -0.95 -5.169 0)
			(layer "B.Fab")
			(effects
				(font
					(size 0.7 0.7)
					(thickness 0.15)
				)
				(justify left bottom mirror)
			)
		)
		(pad "1" smd roundrect
			(at -0.48 0 180)
			(size 0.59 0.64)
			(layers "B.Cu" "B.Mask" "B.Paste")
			(roundrect_rratio 0.25)
			(net 27 "/USB/USB_3V3")
			(pintype "passive")
		)
		(pad "2" smd roundrect
			(at 0.48 0 180)
			(size 0.59 0.64)
			(layers "B.Cu" "B.Mask" "B.Paste")
			(roundrect_rratio 0.25)
			(net 283 "/USB/EECS")
			(pintype "passive")
		)
	)
	(footprint "antmicro-footprints:R_0402_1005Metric"
		(layer "B.Cu")
		(at 41.857962 158.6385)
		(descr "Resistor SMD 0402")
		(tags "resistor SMD 0402")
		(property "Reference" "R309"
			(at -3.61 0.968 0)
			(layer "B.SilkS")
			(effects
				(font
					(size 0.7 0.7)
					(thickness 0.15)
				)
				(justify right bottom mirror)
			)
		)
		(property "Value" "R_4k7_0402"
			(at -1.011843 -1.772047 0)
			(layer "B.Fab")
			(effects
				(font
					(size 0.7 0.7)
					(thickness 0.15)
				)
				(justify right bottom mirror)
			)
		)
		(property "Datasheet" "https://www.bourns.com/docs/product-datasheets/cr.pdf"
			(at 0 0 0)
			(layer "B.Fab")
			(hide yes)
			(effects
				(font
					(size 1.27 1.27)
					(thickness 0.15)
				)
			)
		)
		(property "Manufacturer" "Bourns"
			(at 0 0 0)
			(unlocked yes)
			(layer "B.Fab")
			(hide yes)
			(effects
				(font
					(size 1 1)
					(thickness 0.15)
				)
				(justify mirror)
			)
		)
		(property "MPN" "CR0402-FX-4701GLF"
			(at 0 0 0)
			(unlocked yes)
			(layer "B.Fab")
			(hide yes)
			(effects
				(font
					(size 1 1)
					(thickness 0.15)
				)
				(justify mirror)
			)
		)
		(property "Val" "4k7"
			(at 0 0 0)
			(unlocked yes)
			(layer "B.Fab")
			(hide yes)
			(effects
				(font
					(size 1 1)
					(thickness 0.15)
				)
				(justify mirror)
			)
		)
		(property "License" "Apache-2.0"
			(at 0 0 0)
			(unlocked yes)
			(layer "B.Fab")
			(hide yes)
			(effects
				(font
					(size 1 1)
					(thickness 0.15)
				)
				(justify mirror)
			)
		)
		(property "Author" "Antmicro"
			(at 0 0 0)
			(unlocked yes)
			(layer "B.Fab")
			(hide yes)
			(effects
				(font
					(size 1 1)
					(thickness 0.15)
				)
				(justify mirror)
			)
		)
		(property "Tolerance" "1%"
			(at 0 0 0)
			(unlocked yes)
			(layer "B.Fab")
			(hide yes)
			(effects
				(font
					(size 1 1)
					(thickness 0.15)
				)
				(justify mirror)
			)
		)
		(sheetname "/Supply/")
		(sheetfile "supply.kicad_sch")
		(attr smd)
		(fp_rect
			(start -0.925 0.47)
			(end 0.925 -0.47)
			(stroke
				(width 0.05)
				(type default)
			)
			(fill no)
			(layer "B.CrtYd")
		)
		(fp_rect
			(start -0.5 0.25)
			(end 0.5 -0.25)
			(stroke
				(width 0.15)
				(type solid)
			)
			(fill no)
			(layer "B.Fab")
		)
		(fp_text user "License: Apache-2.0"
			(at -0.95 -5.169 180)
			(layer "B.Fab")
			(effects
				(font
					(size 0.7 0.7)
					(thickness 0.15)
				)
				(justify left bottom mirror)
			)
		)
		(fp_text user "${REFERENCE}"
			(at -0.95 -3.168 180)
			(layer "B.Fab")
			(effects
				(font
					(size 0.7 0.7)
					(thickness 0.15)
				)
				(justify left bottom mirror)
			)
		)
		(fp_text user "Author: Antmicro"
			(at -0.95 -4.169 180)
			(layer "B.Fab")
			(effects
				(font
					(size 0.7 0.7)
					(thickness 0.15)
				)
				(justify left bottom mirror)
			)
		)
		(pad "1" smd roundrect
			(at -0.48 0)
			(size 0.59 0.64)
			(layers "B.Cu" "B.Mask" "B.Paste")
			(roundrect_rratio 0.25)
			(net 3 "GND")
			(pintype "passive")
		)
		(pad "2" smd roundrect
			(at 0.48 0)
			(size 0.59 0.64)
			(layers "B.Cu" "B.Mask" "B.Paste")
			(roundrect_rratio 0.25)
			(net 17 "Net-(Q307-G)")
			(pintype "passive")
		)
	)
	(footprint "antmicro-footprints:C_0402_1005Metric"
		(layer "B.Cu")
		(at 119.142962 129.7665 -90)
		(descr "Capacitor SMD 0402")
		(tags "capacitor SMD 0402")
		(property "Reference" "C504"
			(at -4.01 -0.535 90)
			(layer "B.SilkS")
			(effects
				(font
					(size 0.7 0.7)
					(thickness 0.15)
				)
				(justify left bottom mirror)
			)
		)
		(property "Value" "C_1u_0402"
			(at -1.022927 -2.155213 90)
			(layer "B.Fab")
			(effects
				(font
					(size 0.7 0.7)
					(thickness 0.15)
				)
				(justify left bottom mirror)
			)
		)
		(property "Datasheet" "https://product.tdk.com/en/search/capacitor/ceramic/mlcc/info?part_no=C1005X6S1A105K050BC"
			(at 0 0 270)
			(layer "B.Fab")
			(hide yes)
			(effects
				(font
					(size 1.27 1.27)
					(thickness 0.15)
				)
			)
		)
		(property "Manufacturer" "TDK"
			(at 0 0 270)
			(unlocked yes)
			(layer "B.Fab")
			(hide yes)
			(effects
				(font
					(size 1 1)
					(thickness 0.15)
				)
				(justify mirror)
			)
		)
		(property "MPN" "C1005X6S1A105K050BC"
			(at 0 0 270)
			(unlocked yes)
			(layer "B.Fab")
			(hide yes)
			(effects
				(font
					(size 1 1)
					(thickness 0.15)
				)
				(justify mirror)
			)
		)
		(property "Val" "1u"
			(at 0 0 270)
			(unlocked yes)
			(layer "B.Fab")
			(hide yes)
			(effects
				(font
					(size 1 1)
					(thickness 0.15)
				)
				(justify mirror)
			)
		)
		(property "License" "Apache-2.0"
			(at 0 0 270)
			(unlocked yes)
			(layer "B.Fab")
			(hide yes)
			(effects
				(font
					(size 1 1)
					(thickness 0.15)
				)
				(justify mirror)
			)
		)
		(property "Author" "Antmicro"
			(at 0 0 270)
			(unlocked yes)
			(layer "B.Fab")
			(hide yes)
			(effects
				(font
					(size 1 1)
					(thickness 0.15)
				)
				(justify mirror)
			)
		)
		(property "Voltage" ""
			(at 0 0 270)
			(unlocked yes)
			(layer "B.Fab")
			(hide yes)
			(effects
				(font
					(size 1 1)
					(thickness 0.15)
				)
				(justify mirror)
			)
		)
		(property "Dielectric" ""
			(at 0 0 270)
			(unlocked yes)
			(layer "B.Fab")
			(hide yes)
			(effects
				(font
					(size 1 1)
					(thickness 0.15)
				)
				(justify mirror)
			)
		)
		(sheetname "/NVMe & microSD/")
		(sheetfile "nvme-micro-sd.kicad_sch")
		(attr smd)
		(fp_rect
			(start -0.925 0.47)
			(end 0.925 -0.47)
			(stroke
				(width 0.05)
				(type default)
			)
			(fill no)
			(layer "B.CrtYd")
		)
		(fp_line
			(start -0.494 0.25)
			(end 0.504 0.25)
			(stroke
				(width 0.15)
				(type solid)
			)
			(layer "B.Fab")
		)
		(fp_line
			(start 0.504 0.25)
			(end 0.504 -0.248)
			(stroke
				(width 0.15)
				(type solid)
			)
			(layer "B.Fab")
		)
		(fp_line
			(start -0.494 -0.248)
			(end -0.494 0.25)
			(stroke
				(width 0.15)
				(type solid)
			)
			(layer "B.Fab")
		)
		(fp_line
			(start 0.504 -0.248)
			(end -0.494 -0.248)
			(stroke
				(width 0.15)
				(type solid)
			)
			(layer "B.Fab")
		)
		(fp_text user "License: Apache-2.0"
			(at -0.939 -5.799 90)
			(layer "B.Fab")
			(effects
				(font
					(size 0.7 0.7)
					(thickness 0.15)
				)
				(justify left bottom mirror)
			)
		)
		(fp_text user "Author: Antmicro"
			(at -0.939 -3.399 90)
			(layer "B.Fab")
			(effects
				(font
					(size 0.7 0.7)
					(thickness 0.15)
				)
				(justify left bottom mirror)
			)
		)
		(fp_text user "${REFERENCE}"
			(at -0.939 -4.599 90)
			(layer "B.Fab")
			(effects
				(font
					(size 0.7 0.7)
					(thickness 0.15)
				)
				(justify left bottom mirror)
			)
		)
		(pad "1" smd roundrect
			(at -0.48 0 270)
			(size 0.59 0.64)
			(layers "B.Cu" "B.Mask" "B.Paste")
			(roundrect_rratio 0.25)
			(net 3 "GND")
			(pintype "passive")
		)
		(pad "2" smd roundrect
			(at 0.48 0 270)
			(size 0.59 0.64)
			(layers "B.Cu" "B.Mask" "B.Paste")
			(roundrect_rratio 0.25)
			(net 65 "3V3_SSD")
			(pintype "passive")
		)
	)
	(footprint "antmicro-footprints:TP_SMD_0.75mm"
		(layer "B.Cu")
		(at 83.5 136 180)
		(property "Reference" "TP906"
			(at -3.045 0.52 0)
			(layer "B.SilkS")
			(effects
				(font
					(size 0.7 0.7)
					(thickness 0.15)
				)
				(justify left bottom mirror)
			)
		)
		(property "Value" "TP_0.75mm_SMD"
			(at 0 -1.2 0)
			(layer "B.Fab")
			(effects
				(font
					(size 0.7 0.7)
					(thickness 0.15)
				)
				(justify left bottom mirror)
			)
		)
		(property "MPN" ""
			(at 0 0 180)
			(unlocked yes)
			(layer "B.Fab")
			(hide yes)
			(effects
				(font
					(size 1 1)
					(thickness 0.15)
				)
				(justify mirror)
			)
		)
		(property "Manufacturer" ""
			(at 0 0 180)
			(unlocked yes)
			(layer "B.Fab")
			(hide yes)
			(effects
				(font
					(size 1 1)
					(thickness 0.15)
				)
				(justify mirror)
			)
		)
		(property "Author" "Antmicro"
			(at 0 0 180)
			(unlocked yes)
			(layer "B.Fab")
			(hide yes)
			(effects
				(font
					(size 1 1)
					(thickness 0.15)
				)
				(justify mirror)
			)
		)
		(property "License" "Apache-2.0"
			(at 0 0 180)
			(unlocked yes)
			(layer "B.Fab")
			(hide yes)
			(effects
				(font
					(size 1 1)
					(thickness 0.15)
				)
				(justify mirror)
			)
		)
		(sheetname "/USB/")
		(sheetfile "usb.kicad_sch")
		(attr exclude_from_pos_files exclude_from_bom)
		(fp_circle
			(center 0 0)
			(end 0.475 0)
			(stroke
				(width 0.05)
				(type default)
			)
			(fill no)
			(layer "B.CrtYd")
		)
		(fp_text user "Author: Antmicro"
			(at -0.4 -3.901 0)
			(layer "B.Fab")
			(effects
				(font
					(size 0.7 0.7)
					(thickness 0.15)
				)
				(justify left bottom mirror)
			)
		)
		(fp_text user "${REFERENCE}"
			(at -0.4 -2.7 0)
			(layer "B.Fab")
			(effects
				(font
					(size 0.7 0.7)
					(thickness 0.15)
				)
				(justify left bottom mirror)
			)
		)
		(fp_text user "License: Apache-2.0"
			(at -0.4 -5.101 0)
			(layer "B.Fab")
			(effects
				(font
					(size 0.7 0.7)
					(thickness 0.15)
				)
				(justify left bottom mirror)
			)
		)
		(pad "1" smd circle
			(at 0 0 180)
			(size 0.75 0.75)
			(layers "B.Cu" "B.Mask")
			(net 379 "Net-(U905-~{RESET})")
			(pinfunction "1")
			(pintype "passive")
		)
	)
	(footprint "antmicro-footprints:R_0402_1005Metric"
		(layer "B.Cu")
		(at 81.292962 135.5415 -90)
		(descr "Resistor SMD 0402")
		(tags "resistor SMD 0402")
		(property "Reference" "R906"
			(at 0.655 -0.415 90)
			(layer "B.SilkS")
			(effects
				(font
					(size 0.7 0.7)
					(thickness 0.15)
				)
				(justify left bottom mirror)
			)
		)
		(property "Value" "R_10k_0402"
			(at -1.011843 -1.772047 90)
			(layer "B.Fab")
			(effects
				(font
					(size 0.7 0.7)
					(thickness 0.15)
				)
				(justify left bottom mirror)
			)
		)
		(property "Datasheet" "https://www.bourns.com/docs/product-datasheets/cr.pdf"
			(at 0 0 270)
			(layer "B.Fab")
			(hide yes)
			(effects
				(font
					(size 1.27 1.27)
					(thickness 0.15)
				)
			)
		)
		(property "Manufacturer" "Bourns"
			(at 0 0 270)
			(unlocked yes)
			(layer "B.Fab")
			(hide yes)
			(effects
				(font
					(size 1 1)
					(thickness 0.15)
				)
				(justify mirror)
			)
		)
		(property "MPN" "CR0402-FX-1002GLF"
			(at 0 0 270)
			(unlocked yes)
			(layer "B.Fab")
			(hide yes)
			(effects
				(font
					(size 1 1)
					(thickness 0.15)
				)
				(justify mirror)
			)
		)
		(property "Val" "10k"
			(at 0 0 270)
			(unlocked yes)
			(layer "B.Fab")
			(hide yes)
			(effects
				(font
					(size 1 1)
					(thickness 0.15)
				)
				(justify mirror)
			)
		)
		(property "License" "Apache-2.0"
			(at 0 0 270)
			(unlocked yes)
			(layer "B.Fab")
			(hide yes)
			(effects
				(font
					(size 1 1)
					(thickness 0.15)
				)
				(justify mirror)
			)
		)
		(property "Author" "Antmicro"
			(at 0 0 270)
			(unlocked yes)
			(layer "B.Fab")
			(hide yes)
			(effects
				(font
					(size 1 1)
					(thickness 0.15)
				)
				(justify mirror)
			)
		)
		(property "Tolerance" "1%"
			(at 0 0 270)
			(unlocked yes)
			(layer "B.Fab")
			(hide yes)
			(effects
				(font
					(size 1 1)
					(thickness 0.15)
				)
				(justify mirror)
			)
		)
		(sheetname "/USB/")
		(sheetfile "usb.kicad_sch")
		(attr smd)
		(fp_rect
			(start -0.925 0.47)
			(end 0.925 -0.47)
			(stroke
				(width 0.05)
				(type default)
			)
			(fill no)
			(layer "B.CrtYd")
		)
		(fp_rect
			(start -0.5 0.25)
			(end 0.5 -0.25)
			(stroke
				(width 0.15)
				(type solid)
			)
			(fill no)
			(layer "B.Fab")
		)
		(fp_text user "Author: Antmicro"
			(at -0.95 -4.169 90)
			(layer "B.Fab")
			(effects
				(font
					(size 0.7 0.7)
					(thickness 0.15)
				)
				(justify left bottom mirror)
			)
		)
		(fp_text user "${REFERENCE}"
			(at -0.95 -3.168 90)
			(layer "B.Fab")
			(effects
				(font
					(size 0.7 0.7)
					(thickness 0.15)
				)
				(justify left bottom mirror)
			)
		)
		(fp_text user "License: Apache-2.0"
			(at -0.95 -5.169 90)
			(layer "B.Fab")
			(effects
				(font
					(size 0.7 0.7)
					(thickness 0.15)
				)
				(justify left bottom mirror)
			)
		)
		(pad "1" smd roundrect
			(at -0.48 0 270)
			(size 0.59 0.64)
			(layers "B.Cu" "B.Mask" "B.Paste")
			(roundrect_rratio 0.25)
			(net 27 "/USB/USB_3V3")
			(pintype "passive")
		)
		(pad "2" smd roundrect
			(at 0.48 0 270)
			(size 0.59 0.64)
			(layers "B.Cu" "B.Mask" "B.Paste")
			(roundrect_rratio 0.25)
			(net 377 "Net-(U902-DO)")
			(pintype "passive")
		)
	)
	(footprint "antmicro-footprints:C_0402_1005Metric"
		(layer "B.Cu")
		(at 118.117962 115.7665 -90)
		(descr "Capacitor SMD 0402")
		(tags "capacitor SMD 0402")
		(property "Reference" "C505"
			(at 1.33 1.88 90)
			(layer "B.SilkS")
			(effects
				(font
					(size 0.7 0.7)
					(thickness 0.15)
				)
				(justify left bottom mirror)
			)
		)
		(property "Value" "C_10u_0402"
			(at -1.022927 -2.155213 90)
			(layer "B.Fab")
			(effects
				(font
					(size 0.7 0.7)
					(thickness 0.15)
				)
				(justify left bottom mirror)
			)
		)
		(property "Datasheet" "https://www.yageo.com/en/Chart/Download/pdf/CC0402MRX5R5BB106"
			(at 0 0 270)
			(layer "B.Fab")
			(hide yes)
			(effects
				(font
					(size 1.27 1.27)
					(thickness 0.15)
				)
			)
		)
		(property "MPN" "CC0402MRX5R5BB106"
			(at 0 0 270)
			(unlocked yes)
			(layer "B.Fab")
			(hide yes)
			(effects
				(font
					(size 1 1)
					(thickness 0.15)
				)
				(justify mirror)
			)
		)
		(property "Manufacturer" "YAGEO"
			(at 0 0 270)
			(unlocked yes)
			(layer "B.Fab")
			(hide yes)
			(effects
				(font
					(size 1 1)
					(thickness 0.15)
				)
				(justify mirror)
			)
		)
		(property "License" "Apache-2.0"
			(at 0 0 270)
			(unlocked yes)
			(layer "B.Fab")
			(hide yes)
			(effects
				(font
					(size 1 1)
					(thickness 0.15)
				)
				(justify mirror)
			)
		)
		(property "Author" "Antmicro"
			(at 0 0 270)
			(unlocked yes)
			(layer "B.Fab")
			(hide yes)
			(effects
				(font
					(size 1 1)
					(thickness 0.15)
				)
				(justify mirror)
			)
		)
		(property "Val" "10u"
			(at 0 0 270)
			(unlocked yes)
			(layer "B.Fab")
			(hide yes)
			(effects
				(font
					(size 1 1)
					(thickness 0.15)
				)
				(justify mirror)
			)
		)
		(property "Voltage" ""
			(at 0 0 270)
			(unlocked yes)
			(layer "B.Fab")
			(hide yes)
			(effects
				(font
					(size 1 1)
					(thickness 0.15)
				)
				(justify mirror)
			)
		)
		(property "Dielectric" ""
			(at 0 0 270)
			(unlocked yes)
			(layer "B.Fab")
			(hide yes)
			(effects
				(font
					(size 1 1)
					(thickness 0.15)
				)
				(justify mirror)
			)
		)
		(sheetname "/NVMe & microSD/")
		(sheetfile "nvme-micro-sd.kicad_sch")
		(attr smd)
		(fp_rect
			(start -0.925 0.47)
			(end 0.925 -0.47)
			(stroke
				(width 0.05)
				(type default)
			)
			(fill no)
			(layer "B.CrtYd")
		)
		(fp_line
			(start -0.494 0.25)
			(end 0.504 0.25)
			(stroke
				(width 0.15)
				(type solid)
			)
			(layer "B.Fab")
		)
		(fp_line
			(start 0.504 0.25)
			(end 0.504 -0.248)
			(stroke
				(width 0.15)
				(type solid)
			)
			(layer "B.Fab")
		)
		(fp_line
			(start -0.494 -0.248)
			(end -0.494 0.25)
			(stroke
				(width 0.15)
				(type solid)
			)
			(layer "B.Fab")
		)
		(fp_line
			(start 0.504 -0.248)
			(end -0.494 -0.248)
			(stroke
				(width 0.15)
				(type solid)
			)
			(layer "B.Fab")
		)
		(fp_text user "${REFERENCE}"
			(at -0.939 -4.599 90)
			(layer "B.Fab")
			(effects
				(font
					(size 0.7 0.7)
					(thickness 0.15)
				)
				(justify left bottom mirror)
			)
		)
		(fp_text user "Author: Antmicro"
			(at -0.939 -3.399 90)
			(layer "B.Fab")
			(effects
				(font
					(size 0.7 0.7)
					(thickness 0.15)
				)
				(justify left bottom mirror)
			)
		)
		(fp_text user "License: Apache-2.0"
			(at -0.939 -5.799 90)
			(layer "B.Fab")
			(effects
				(font
					(size 0.7 0.7)
					(thickness 0.15)
				)
				(justify left bottom mirror)
			)
		)
		(pad "1" smd roundrect
			(at -0.48 0 270)
			(size 0.59 0.64)
			(layers "B.Cu" "B.Mask" "B.Paste")
			(roundrect_rratio 0.25)
			(net 3 "GND")
			(pintype "passive")
		)
		(pad "2" smd roundrect
			(at 0.48 0 270)
			(size 0.59 0.64)
			(layers "B.Cu" "B.Mask" "B.Paste")
			(roundrect_rratio 0.25)
			(net 65 "3V3_SSD")
			(pintype "passive")
		)
	)
	(footprint "antmicro-footprints:C_0402_1005Metric"
		(layer "B.Cu")
		(at 113.817962 118.3665)
		(descr "Capacitor SMD 0402")
		(tags "capacitor SMD 0402")
		(property "Reference" "C702"
			(at -0.78 5.69 0)
			(layer "B.SilkS")
			(effects
				(font
					(size 0.7 0.7)
					(thickness 0.15)
				)
				(justify right bottom mirror)
			)
		)
		(property "Value" "C_10u_0402"
			(at -1.022927 -2.155213 0)
			(layer "B.Fab")
			(effects
				(font
					(size 0.7 0.7)
					(thickness 0.15)
				)
				(justify right bottom mirror)
			)
		)
		(property "Datasheet" "https://www.yageo.com/en/Chart/Download/pdf/CC0402MRX5R5BB106"
			(at 0 0 0)
			(layer "B.Fab")
			(hide yes)
			(effects
				(font
					(size 1.27 1.27)
					(thickness 0.15)
				)
			)
		)
		(property "MPN" "CC0402MRX5R5BB106"
			(at 0 0 0)
			(unlocked yes)
			(layer "B.Fab")
			(hide yes)
			(effects
				(font
					(size 1 1)
					(thickness 0.15)
				)
				(justify mirror)
			)
		)
		(property "Manufacturer" "YAGEO"
			(at 0 0 0)
			(unlocked yes)
			(layer "B.Fab")
			(hide yes)
			(effects
				(font
					(size 1 1)
					(thickness 0.15)
				)
				(justify mirror)
			)
		)
		(property "License" "Apache-2.0"
			(at 0 0 0)
			(unlocked yes)
			(layer "B.Fab")
			(hide yes)
			(effects
				(font
					(size 1 1)
					(thickness 0.15)
				)
				(justify mirror)
			)
		)
		(property "Author" "Antmicro"
			(at 0 0 0)
			(unlocked yes)
			(layer "B.Fab")
			(hide yes)
			(effects
				(font
					(size 1 1)
					(thickness 0.15)
				)
				(justify mirror)
			)
		)
		(property "Val" "10u"
			(at 0 0 0)
			(unlocked yes)
			(layer "B.Fab")
			(hide yes)
			(effects
				(font
					(size 1 1)
					(thickness 0.15)
				)
				(justify mirror)
			)
		)
		(property "Voltage" ""
			(at 0 0 0)
			(unlocked yes)
			(layer "B.Fab")
			(hide yes)
			(effects
				(font
					(size 1 1)
					(thickness 0.15)
				)
				(justify mirror)
			)
		)
		(property "Dielectric" ""
			(at 0 0 0)
			(unlocked yes)
			(layer "B.Fab")
			(hide yes)
			(effects
				(font
					(size 1 1)
					(thickness 0.15)
				)
				(justify mirror)
			)
		)
		(sheetname "/Display/")
		(sheetfile "display.kicad_sch")
		(attr smd)
		(fp_rect
			(start -0.925 0.47)
			(end 0.925 -0.47)
			(stroke
				(width 0.05)
				(type default)
			)
			(fill no)
			(layer "B.CrtYd")
		)
		(fp_line
			(start -0.494 -0.248)
			(end -0.494 0.25)
			(stroke
				(width 0.15)
				(type solid)
			)
			(layer "B.Fab")
		)
		(fp_line
			(start -0.494 0.25)
			(end 0.504 0.25)
			(stroke
				(width 0.15)
				(type solid)
			)
			(layer "B.Fab")
		)
		(fp_line
			(start 0.504 -0.248)
			(end -0.494 -0.248)
			(stroke
				(width 0.15)
				(type solid)
			)
			(layer "B.Fab")
		)
		(fp_line
			(start 0.504 0.25)
			(end 0.504 -0.248)
			(stroke
				(width 0.15)
				(type solid)
			)
			(layer "B.Fab")
		)
		(fp_text user "Author: Antmicro"
			(at -0.939 -3.399 180)
			(layer "B.Fab")
			(effects
				(font
					(size 0.7 0.7)
					(thickness 0.15)
				)
				(justify left bottom mirror)
			)
		)
		(fp_text user "License: Apache-2.0"
			(at -0.939 -5.799 180)
			(layer "B.Fab")
			(effects
				(font
					(size 0.7 0.7)
					(thickness 0.15)
				)
				(justify left bottom mirror)
			)
		)
		(fp_text user "${REFERENCE}"
			(at -0.939 -4.599 180)
			(layer "B.Fab")
			(effects
				(font
					(size 0.7 0.7)
					(thickness 0.15)
				)
				(justify left bottom mirror)
			)
		)
		(pad "1" smd roundrect
			(at -0.48 0)
			(size 0.59 0.64)
			(layers "B.Cu" "B.Mask" "B.Paste")
			(roundrect_rratio 0.25)
			(net 3 "GND")
			(pintype "passive")
		)
		(pad "2" smd roundrect
			(at 0.48 0)
			(size 0.59 0.64)
			(layers "B.Cu" "B.Mask" "B.Paste")
			(roundrect_rratio 0.25)
			(net 119 "Net-(D710-C)")
			(pintype "passive")
		)
	)
	(footprint "antmicro-footprints:Nexperia_DFN-10_2.5x1mm_P0.5mm"
		(layer "B.Cu")
		(at 126.467962 166.9915 90)
		(property "Reference" "D501"
			(at -1.365 -1.7 90)
			(layer "B.SilkS")
			(effects
				(font
					(size 0.7 0.7)
					(thickness 0.15)
				)
				(justify right bottom mirror)
			)
		)
		(property "Value" "PUSB3F96X_PASS"
			(at -0.016 -1.705 90)
			(layer "B.Fab")
			(effects
				(font
					(size 0.7 0.7)
					(thickness 0.15)
				)
				(justify right bottom mirror)
			)
		)
		(property "Datasheet" "https://mouser.com/datasheet/2/916/PUSB3F96-1600324.pdf"
			(at 0 0 90)
			(layer "B.Fab")
			(hide yes)
			(effects
				(font
					(size 1.27 1.27)
					(thickness 0.15)
				)
			)
		)
		(property "Manufacturer" "Nexperia"
			(at 0 0 90)
			(unlocked yes)
			(layer "B.Fab")
			(hide yes)
			(effects
				(font
					(size 1 1)
					(thickness 0.15)
				)
				(justify mirror)
			)
		)
		(property "MPN" "PUSB3F96X"
			(at 0 0 90)
			(unlocked yes)
			(layer "B.Fab")
			(hide yes)
			(effects
				(font
					(size 1 1)
					(thickness 0.15)
				)
				(justify mirror)
			)
		)
		(property "Author" "Antmicro"
			(at 0 0 90)
			(unlocked yes)
			(layer "B.Fab")
			(hide yes)
			(effects
				(font
					(size 1 1)
					(thickness 0.15)
				)
				(justify mirror)
			)
		)
		(property "License" "Apache-2.0"
			(at 0 0 90)
			(unlocked yes)
			(layer "B.Fab")
			(hide yes)
			(effects
				(font
					(size 1 1)
					(thickness 0.15)
				)
				(justify mirror)
			)
		)
		(sheetname "/NVMe & microSD/")
		(sheetfile "nvme-micro-sd.kicad_sch")
		(attr smd)
		(fp_line
			(start 1.375 -0.4)
			(end 1.375 0.4)
			(stroke
				(width 0.15)
				(type solid)
			)
			(layer "B.SilkS")
		)
		(fp_line
			(start -1.375 0.4)
			(end -1.375 -0.4)
			(stroke
				(width 0.15)
				(type solid)
			)
			(layer "B.SilkS")
		)
		(fp_circle
			(center -1.4 -0.7)
			(end -1.349 -0.7)
			(stroke
				(width 0.15)
				(type solid)
			)
			(fill yes)
			(layer "B.SilkS")
		)
		(fp_rect
			(start -1.4 0.725)
			(end 1.4 -0.725)
			(stroke
				(width 0.05)
				(type solid)
			)
			(fill no)
			(layer "B.CrtYd")
		)
		(fp_line
			(start 1.25 -0.5)
			(end 1.25 0.5)
			(stroke
				(width 0.15)
				(type solid)
			)
			(layer "B.Fab")
		)
		(fp_line
			(start -0.9 -0.5)
			(end 1.25 -0.5)
			(stroke
				(width 0.15)
				(type solid)
			)
			(layer "B.Fab")
		)
		(fp_line
			(start -1.25 -0.15)
			(end -0.9 -0.5)
			(stroke
				(width 0.15)
				(type solid)
			)
			(layer "B.Fab")
		)
		(fp_line
			(start 1.25 0.5)
			(end -1.25 0.5)
			(stroke
				(width 0.15)
				(type solid)
			)
			(layer "B.Fab")
		)
		(fp_line
			(start -1.25 0.5)
			(end -1.25 -0.15)
			(stroke
				(width 0.15)
				(type solid)
			)
			(layer "B.Fab")
		)
		(fp_text user "${REFERENCE}"
			(at -1.367 -3.704 270)
			(layer "B.Fab")
			(effects
				(font
					(size 0.7 0.7)
					(thickness 0.15)
				)
				(justify left bottom mirror)
			)
		)
		(fp_text user "License: Apache-2.0"
			(at -1.367 -6.105 270)
			(layer "B.Fab")
			(effects
				(font
					(size 0.7 0.7)
					(thickness 0.15)
				)
				(justify left bottom mirror)
			)
		)
		(fp_text user "Author: Antmicro"
			(at -1.367 -4.905 270)
			(layer "B.Fab")
			(effects
				(font
					(size 0.7 0.7)
					(thickness 0.15)
				)
				(justify left bottom mirror)
			)
		)
		(pad "1" smd rect
			(at -1 -0.3875 90)
			(size 0.2 0.475)
			(layers "B.Cu" "B.Mask" "B.Paste")
			(net 118 "/Compute module/SDIO.CD")
			(pinfunction "CH1")
			(pintype "passive")
			(solder_mask_margin 0.05)
		)
		(pad "2" smd rect
			(at -0.5 -0.3875 90)
			(size 0.2 0.475)
			(layers "B.Cu" "B.Mask" "B.Paste")
			(net 12 "/Compute module/SDIO.D2")
			(pinfunction "CH2")
			(pintype "passive")
			(solder_mask_margin 0.05)
		)
		(pad "3" smd rect
			(at 0 -0.3875 90)
			(size 0.2 0.475)
			(layers "B.Cu" "B.Mask" "B.Paste")
			(net 3 "GND")
			(pinfunction "GND")
			(pintype "passive")
			(solder_mask_margin 0.05)
		)
		(pad "4" smd rect
			(at 0.5 -0.3875 90)
			(size 0.2 0.475)
			(layers "B.Cu" "B.Mask" "B.Paste")
			(net 11 "/Compute module/SDIO.D3")
			(pinfunction "CH3")
			(pintype "passive")
			(solder_mask_margin 0.05)
		)
		(pad "5" smd rect
			(at 1 -0.3875 90)
			(size 0.2 0.475)
			(layers "B.Cu" "B.Mask" "B.Paste")
			(net 8 "/Compute module/SDIO.CMD")
			(pinfunction "CH4")
			(pintype "passive")
			(solder_mask_margin 0.05)
		)
		(pad "6" smd rect
			(at 1 0.3875 90)
			(size 0.2 0.475)
			(layers "B.Cu" "B.Mask" "B.Paste")
			(net 8 "/Compute module/SDIO.CMD")
			(pinfunction "CH4")
			(pintype "passive")
			(solder_mask_margin 0.05)
		)
		(pad "7" smd rect
			(at 0.5 0.3875 90)
			(size 0.2 0.475)
			(layers "B.Cu" "B.Mask" "B.Paste")
			(net 11 "/Compute module/SDIO.D3")
			(pinfunction "CH3")
			(pintype "passive")
			(solder_mask_margin 0.05)
		)
		(pad "8" smd rect
			(at 0 0.3875 90)
			(size 0.2 0.475)
			(layers "B.Cu" "B.Mask" "B.Paste")
			(net 3 "GND")
			(pinfunction "GND")
			(pintype "passive")
			(solder_mask_margin 0.05)
		)
		(pad "9" smd rect
			(at -0.501 0.3875 90)
			(size 0.2 0.475)
			(layers "B.Cu" "B.Mask" "B.Paste")
			(net 12 "/Compute module/SDIO.D2")
			(pinfunction "CH2")
			(pintype "passive")
			(solder_mask_margin 0.05)
		)
		(pad "10" smd rect
			(at -1 0.3875 90)
			(size 0.2 0.475)
			(layers "B.Cu" "B.Mask" "B.Paste")
			(net 118 "/Compute module/SDIO.CD")
			(pinfunction "CH1")
			(pintype "passive")
			(solder_mask_margin 0.05)
		)
	)
	(footprint "antmicro-footprints:C_2220_5650Metric"
		(layer "B.Cu")
		(at 61.067962 145.6465 90)
		(descr "Capacitor SMD 2220")
		(tags "capacitor SMD 2220")
		(property "Reference" "C406"
			(at -4.58 -1.42 180)
			(layer "B.SilkS")
			(effects
				(font
					(size 0.7 0.7)
					(thickness 0.15)
				)
				(justify right bottom mirror)
			)
		)
		(property "Value" "C_22u_100V_2220"
			(at 0 -3.9 90)
			(layer "B.Fab")
			(effects
				(font
					(size 0.7 0.7)
					(thickness 0.15)
				)
				(justify right bottom mirror)
			)
		)
		(property "Datasheet" "https://product.tdk.com/en/search/capacitor/ceramic/mlcc/info?part_no=C5750X7S2A226M280KB"
			(at 0 0 90)
			(layer "B.Fab")
			(hide yes)
			(effects
				(font
					(size 1.27 1.27)
					(thickness 0.15)
				)
			)
		)
		(property "Manufacturer" "TDK"
			(at 0 0 90)
			(unlocked yes)
			(layer "B.Fab")
			(hide yes)
			(effects
				(font
					(size 1 1)
					(thickness 0.15)
				)
				(justify mirror)
			)
		)
		(property "MPN" "C5750X7S2A226M280KB"
			(at 0 0 90)
			(unlocked yes)
			(layer "B.Fab")
			(hide yes)
			(effects
				(font
					(size 1 1)
					(thickness 0.15)
				)
				(justify mirror)
			)
		)
		(property "Val" "22u"
			(at 0 0 90)
			(unlocked yes)
			(layer "B.Fab")
			(hide yes)
			(effects
				(font
					(size 1 1)
					(thickness 0.15)
				)
				(justify mirror)
			)
		)
		(property "License" "Apache-2.0"
			(at 0 0 90)
			(unlocked yes)
			(layer "B.Fab")
			(hide yes)
			(effects
				(font
					(size 1 1)
					(thickness 0.15)
				)
				(justify mirror)
			)
		)
		(property "Author" "Antmicro"
			(at 0 0 90)
			(unlocked yes)
			(layer "B.Fab")
			(hide yes)
			(effects
				(font
					(size 1 1)
					(thickness 0.15)
				)
				(justify mirror)
			)
		)
		(property "Voltage" "100V"
			(at 0 0 90)
			(unlocked yes)
			(layer "B.Fab")
			(hide yes)
			(effects
				(font
					(size 1 1)
					(thickness 0.15)
				)
				(justify mirror)
			)
		)
		(property "Dielectric" "X7S"
			(at 0 0 90)
			(unlocked yes)
			(layer "B.Fab")
			(hide yes)
			(effects
				(font
					(size 1 1)
					(thickness 0.15)
				)
				(justify mirror)
			)
		)
		(property "Public" "False"
			(at 0 0 90)
			(unlocked yes)
			(layer "B.Fab")
			(hide yes)
			(effects
				(font
					(size 1 1)
					(thickness 0.15)
				)
				(justify mirror)
			)
		)
		(sheetname "/Ethernet/")
		(sheetfile "ethernet.kicad_sch")
		(attr smd)
		(fp_line
			(start -1.415 -2.61)
			(end 1.415 -2.61)
			(stroke
				(width 0.15)
				(type solid)
			)
			(layer "B.SilkS")
		)
		(fp_line
			(start -1.415 2.61)
			(end 1.415 2.61)
			(stroke
				(width 0.15)
				(type solid)
			)
			(layer "B.SilkS")
		)
		(fp_rect
			(start -3.7 2.95)
			(end 3.7 -2.95)
			(stroke
				(width 0.05)
				(type solid)
			)
			(fill no)
			(layer "B.CrtYd")
		)
		(fp_rect
			(start -2.85 2.5)
			(end 2.85 -2.5)
			(stroke
				(width 0.15)
				(type solid)
			)
			(fill no)
			(layer "B.Fab")
		)
		(fp_text user "License: Apache-2.0"
			(at -3.7 -6.9 270)
			(layer "B.Fab")
			(effects
				(font
					(size 0.7 0.7)
					(thickness 0.15)
				)
				(justify left bottom mirror)
			)
		)
		(fp_text user "${REFERENCE}"
			(at -3.7 -5.9 270)
			(layer "B.Fab")
			(effects
				(font
					(size 0.7 0.7)
					(thickness 0.15)
				)
				(justify left bottom mirror)
			)
		)
		(fp_text user "Author: Antmicro"
			(at -3.7 -7.9 270)
			(layer "B.Fab")
			(effects
				(font
					(size 0.7 0.7)
					(thickness 0.15)
				)
				(justify left bottom mirror)
			)
		)
		(pad "1" smd roundrect
			(at -2.55 0 90)
			(size 1.8 5.4)
			(layers "B.Cu" "B.Mask" "B.Paste")
			(roundrect_rratio 0.138889)
			(net 1 "GNDD")
			(pintype "passive")
		)
		(pad "2" smd roundrect
			(at 2.55 0 90)
			(size 1.8 5.4)
			(layers "B.Cu" "B.Mask" "B.Paste")
			(roundrect_rratio 0.138889)
			(net 33 "/Ethernet/VDD")
			(pintype "passive")
		)
	)
	(footprint "antmicro-footprints:R_0402_1005Metric"
		(layer "B.Cu")
		(at 72.55 150.6365 -90)
		(descr "Resistor SMD 0402")
		(tags "resistor SMD 0402")
		(property "Reference" "R262"
			(at -3.8 -0.45 90)
			(layer "B.SilkS")
			(effects
				(font
					(size 0.7 0.7)
					(thickness 0.15)
				)
				(justify left bottom mirror)
			)
		)
		(property "Value" "R_100k_0402"
			(at -1.011843 -1.772047 90)
			(layer "B.Fab")
			(effects
				(font
					(size 0.7 0.7)
					(thickness 0.15)
				)
				(justify left bottom mirror)
			)
		)
		(property "Datasheet" "https://www.bourns.com/docs/product-datasheets/cr.pdf"
			(at 0 0 270)
			(layer "B.Fab")
			(hide yes)
			(effects
				(font
					(size 1.27 1.27)
					(thickness 0.15)
				)
			)
		)
		(property "Manufacturer" "Bourns"
			(at 0 0 270)
			(unlocked yes)
			(layer "B.Fab")
			(hide yes)
			(effects
				(font
					(size 1 1)
					(thickness 0.15)
				)
				(justify mirror)
			)
		)
		(property "MPN" "CR0402-FX-1003GLF"
			(at 0 0 270)
			(unlocked yes)
			(layer "B.Fab")
			(hide yes)
			(effects
				(font
					(size 1 1)
					(thickness 0.15)
				)
				(justify mirror)
			)
		)
		(property "Val" "100k"
			(at 0 0 270)
			(unlocked yes)
			(layer "B.Fab")
			(hide yes)
			(effects
				(font
					(size 1 1)
					(thickness 0.15)
				)
				(justify mirror)
			)
		)
		(property "License" "Apache-2.0"
			(at 0 0 270)
			(unlocked yes)
			(layer "B.Fab")
			(hide yes)
			(effects
				(font
					(size 1 1)
					(thickness 0.15)
				)
				(justify mirror)
			)
		)
		(property "Author" "Antmicro"
			(at 0 0 270)
			(unlocked yes)
			(layer "B.Fab")
			(hide yes)
			(effects
				(font
					(size 1 1)
					(thickness 0.15)
				)
				(justify mirror)
			)
		)
		(property "Tolerance" "1%"
			(at 0 0 270)
			(unlocked yes)
			(layer "B.Fab")
			(hide yes)
			(effects
				(font
					(size 1 1)
					(thickness 0.15)
				)
				(justify mirror)
			)
		)
		(sheetname "/Compute module/")
		(sheetfile "compute-module.kicad_sch")
		(attr smd)
		(fp_rect
			(start -0.925 0.47)
			(end 0.925 -0.47)
			(stroke
				(width 0.05)
				(type default)
			)
			(fill no)
			(layer "B.CrtYd")
		)
		(fp_rect
			(start -0.5 0.25)
			(end 0.5 -0.25)
			(stroke
				(width 0.15)
				(type solid)
			)
			(fill no)
			(layer "B.Fab")
		)
		(fp_text user "Author: Antmicro"
			(at -0.95 -4.169 90)
			(layer "B.Fab")
			(effects
				(font
					(size 0.7 0.7)
					(thickness 0.15)
				)
				(justify left bottom mirror)
			)
		)
		(fp_text user "License: Apache-2.0"
			(at -0.95 -5.169 90)
			(layer "B.Fab")
			(effects
				(font
					(size 0.7 0.7)
					(thickness 0.15)
				)
				(justify left bottom mirror)
			)
		)
		(fp_text user "${REFERENCE}"
			(at -0.95 -3.168 90)
			(layer "B.Fab")
			(effects
				(font
					(size 0.7 0.7)
					(thickness 0.15)
				)
				(justify left bottom mirror)
			)
		)
		(pad "1" smd roundrect
			(at -0.48 0 270)
			(size 0.59 0.64)
			(layers "B.Cu" "B.Mask" "B.Paste")
			(roundrect_rratio 0.25)
			(net 3 "GND")
			(pintype "passive")
		)
		(pad "2" smd roundrect
			(at 0.48 0 270)
			(size 0.59 0.64)
			(layers "B.Cu" "B.Mask" "B.Paste")
			(roundrect_rratio 0.25)
			(net 22 "+1V8")
			(pintype "passive")
		)
	)
	(footprint "antmicro-footprints:R_Array_4x0402_Panasonic_EXB28V"
		(layer "B.Cu")
		(at 110.087962 118.9265)
		(property "Reference" "R701"
			(at -4.26 0.42 0)
			(layer "B.SilkS")
			(effects
				(font
					(size 0.7 0.7)
					(thickness 0.15)
				)
				(justify right bottom mirror)
			)
		)
		(property "Value" "R_4x100R_0402_array"
			(at -1.5 -2 0)
			(layer "B.Fab")
			(effects
				(font
					(size 0.7 0.7)
					(thickness 0.15)
				)
				(justify right bottom mirror)
			)
		)
		(property "Datasheet" "http://industrial.panasonic.com/cdbs/www-data/pdf/AOC0000/AOC0000C14.pdf"
			(at 0 0 0)
			(layer "B.Fab")
			(hide yes)
			(effects
				(font
					(size 1.27 1.27)
					(thickness 0.15)
				)
			)
		)
		(property "MPN" "EXB-28V101JX"
			(at 0 0 0)
			(unlocked yes)
			(layer "B.Fab")
			(hide yes)
			(effects
				(font
					(size 1 1)
					(thickness 0.15)
				)
				(justify mirror)
			)
		)
		(property "Manufacturer" "Panasonic"
			(at 0 0 0)
			(unlocked yes)
			(layer "B.Fab")
			(hide yes)
			(effects
				(font
					(size 1 1)
					(thickness 0.15)
				)
				(justify mirror)
			)
		)
		(property "License" "Apache-2.0"
			(at 0 0 0)
			(unlocked yes)
			(layer "B.Fab")
			(hide yes)
			(effects
				(font
					(size 1 1)
					(thickness 0.15)
				)
				(justify mirror)
			)
		)
		(property "Author" "Antmicro"
			(at 0 0 0)
			(unlocked yes)
			(layer "B.Fab")
			(hide yes)
			(effects
				(font
					(size 1 1)
					(thickness 0.15)
				)
				(justify mirror)
			)
		)
		(property "Val" "R_4x100R_0402"
			(at 0 0 0)
			(unlocked yes)
			(layer "B.Fab")
			(hide yes)
			(effects
				(font
					(size 1 1)
					(thickness 0.15)
				)
				(justify mirror)
			)
		)
		(sheetname "/Display/")
		(sheetfile "display.kicad_sch")
		(attr smd)
		(fp_line
			(start -1.25 0.5)
			(end -1.25 -0.498)
			(stroke
				(width 0.15)
				(type solid)
			)
			(layer "B.SilkS")
		)
		(fp_line
			(start 1.25 -0.499)
			(end 1.25 0.499)
			(stroke
				(width 0.15)
				(type solid)
			)
			(layer "B.SilkS")
		)
		(fp_rect
			(start -1.25 0.8)
			(end 1.25 -0.8)
			(stroke
				(width 0.05)
				(type solid)
			)
			(fill no)
			(layer "B.CrtYd")
		)
		(fp_line
			(start -1 -0.498)
			(end -1 0.5)
			(stroke
				(width 0.15)
				(type solid)
			)
			(layer "B.Fab")
		)
		(fp_line
			(start -1 0.5)
			(end 0.998 0.5)
			(stroke
				(width 0.15)
				(type solid)
			)
			(layer "B.Fab")
		)
		(fp_line
			(start 0.998 -0.498)
			(end -1 -0.498)
			(stroke
				(width 0.15)
				(type solid)
			)
			(layer "B.Fab")
		)
		(fp_line
			(start 0.998 0.5)
			(end 0.998 -0.498)
			(stroke
				(width 0.15)
				(type solid)
			)
			(layer "B.Fab")
		)
		(fp_text user "License: Apache-2.0"
			(at -1.5 -5.75 180)
			(layer "B.Fab")
			(effects
				(font
					(size 0.7 0.7)
					(thickness 0.15)
				)
				(justify left bottom mirror)
			)
		)
		(fp_text user "${REFERENCE}"
			(at -1.5 -3.25 180)
			(layer "B.Fab")
			(effects
				(font
					(size 0.7 0.7)
					(thickness 0.15)
				)
				(justify left bottom mirror)
			)
		)
		(fp_text user "Author: Antmicro"
			(at -1.5 -4.5 180)
			(layer "B.Fab")
			(effects
				(font
					(size 0.7 0.7)
					(thickness 0.15)
				)
				(justify left bottom mirror)
			)
		)
		(pad "1" smd roundrect
			(at -0.8875 -0.45)
			(size 0.525 0.5)
			(layers "B.Cu" "B.Mask" "B.Paste")
			(roundrect_rratio 0.25)
			(net 266 "/Compute module/HDMI.SDA")
			(pinfunction "R1.1")
			(pintype "passive")
		)
		(pad "2" smd roundrect
			(at -0.25 -0.45)
			(size 0.25 0.5)
			(layers "B.Cu" "B.Mask" "B.Paste")
			(roundrect_rratio 0.25)
			(net 267 "/Compute module/HDMI.SCL")
			(pinfunction "R2.1")
			(pintype "passive")
		)
		(pad "3" smd roundrect
			(at 0.25 -0.45)
			(size 0.25 0.5)
			(layers "B.Cu" "B.Mask" "B.Paste")
			(roundrect_rratio 0.25)
			(net 261 "/Compute module/HDMI.CEC")
			(pinfunction "R3.1")
			(pintype "passive")
		)
		(pad "4" smd roundrect
			(at 0.8875 -0.45)
			(size 0.525 0.5)
			(layers "B.Cu" "B.Mask" "B.Paste")
			(roundrect_rratio 0.25)
			(net 262 "/Compute module/HDMI.HPD")
			(pinfunction "R4.1")
			(pintype "passive")
		)
		(pad "5" smd roundrect
			(at 0.8875 0.45)
			(size 0.525 0.5)
			(layers "B.Cu" "B.Mask" "B.Paste")
			(roundrect_rratio 0.25)
			(net 454 "/Display/HPD")
			(pinfunction "R4.2")
			(pintype "passive")
		)
		(pad "6" smd roundrect
			(at 0.25 0.45)
			(size 0.25 0.5)
			(layers "B.Cu" "B.Mask" "B.Paste")
			(roundrect_rratio 0.25)
			(net 451 "/Display/CEC")
			(pinfunction "R3.2")
			(pintype "passive")
		)
		(pad "7" smd roundrect
			(at -0.25 0.45)
			(size 0.25 0.5)
			(layers "B.Cu" "B.Mask" "B.Paste")
			(roundrect_rratio 0.25)
			(net 452 "/Display/SCL")
			(pinfunction "R2.2")
			(pintype "passive")
		)
		(pad "8" smd roundrect
			(at -0.8875 0.45)
			(size 0.525 0.5)
			(layers "B.Cu" "B.Mask" "B.Paste")
			(roundrect_rratio 0.25)
			(net 453 "/Display/SDA")
			(pinfunction "R1.2")
			(pintype "passive")
		)
	)
	(footprint "antmicro-footprints:SOD-523"
		(layer "B.Cu")
		(at 125.6 178.7 180)
		(property "Reference" "D811"
			(at -1.3 0.7 0)
			(layer "B.SilkS")
			(effects
				(font
					(size 0.7 0.7)
					(thickness 0.15)
				)
				(justify left bottom mirror)
			)
		)
		(property "Value" "RB521S30T1G"
			(at 0 -1.499 0)
			(layer "B.Fab")
			(effects
				(font
					(size 0.7 0.7)
					(thickness 0.15)
				)
				(justify left bottom mirror)
			)
		)
		(property "Datasheet" "https://www.onsemi.com/pdf/datasheet/rb521s30t1-d.pdf"
			(at 0 0 0)
			(layer "B.Fab")
			(hide yes)
			(effects
				(font
					(size 1.27 1.27)
					(thickness 0.15)
				)
				(justify mirror)
			)
		)
		(property "MPN" "RB521S30T1G"
			(at 0 0 180)
			(unlocked yes)
			(layer "B.Fab")
			(hide yes)
			(effects
				(font
					(size 1 1)
					(thickness 0.15)
				)
				(justify mirror)
			)
		)
		(property "Manufacturer" "ON Semiconductor"
			(at 0 0 180)
			(unlocked yes)
			(layer "B.Fab")
			(hide yes)
			(effects
				(font
					(size 1 1)
					(thickness 0.15)
				)
				(justify mirror)
			)
		)
		(property "Author" "Antmicro"
			(at 0 0 180)
			(unlocked yes)
			(layer "B.Fab")
			(hide yes)
			(effects
				(font
					(size 1 1)
					(thickness 0.15)
				)
				(justify mirror)
			)
		)
		(property "License" "Apache-2.0"
			(at 0 0 180)
			(unlocked yes)
			(layer "B.Fab")
			(hide yes)
			(effects
				(font
					(size 1 1)
					(thickness 0.15)
				)
				(justify mirror)
			)
		)
		(sheetname "/Peripherals/")
		(sheetfile "peripherals.kicad_sch")
		(attr smd)
		(fp_line
			(start -0.35 0.5)
			(end -0.35 -0.5)
			(stroke
				(width 0.15)
				(type solid)
			)
			(layer "B.SilkS")
		)
		(fp_rect
			(start -1 0.6)
			(end 1 -0.6)
			(stroke
				(width 0.05)
				(type solid)
			)
			(fill no)
			(layer "B.CrtYd")
		)
		(fp_line
			(start 0.65 0.425)
			(end 0.65 -0.423)
			(stroke
				(width 0.15)
				(type solid)
			)
			(layer "B.Fab")
		)
		(fp_line
			(start -0.35 0.4)
			(end -0.35 -0.4)
			(stroke
				(width 0.15)
				(type solid)
			)
			(layer "B.Fab")
		)
		(fp_line
			(start -0.652 0.425)
			(end 0.65 0.425)
			(stroke
				(width 0.15)
				(type solid)
			)
			(layer "B.Fab")
		)
		(fp_line
			(start -0.652 -0.423)
			(end 0.65 -0.423)
			(stroke
				(width 0.15)
				(type solid)
			)
			(layer "B.Fab")
		)
		(fp_line
			(start -0.652 -0.423)
			(end -0.652 0.425)
			(stroke
				(width 0.15)
				(type solid)
			)
			(layer "B.Fab")
		)
		(fp_text user "Author: Antmicro"
			(at -1.276 -4.7 0)
			(layer "B.Fab")
			(effects
				(font
					(size 0.7 0.7)
					(thickness 0.15)
				)
				(justify left bottom mirror)
			)
		)
		(fp_text user "${REFERENCE}"
			(at -1.276 -3.499 0)
			(layer "B.Fab")
			(effects
				(font
					(size 0.7 0.7)
					(thickness 0.15)
				)
				(justify left bottom mirror)
			)
		)
		(fp_text user "License: Apache-2.0"
			(at -1.276 -5.9 0)
			(layer "B.Fab")
			(effects
				(font
					(size 0.7 0.7)
					(thickness 0.15)
				)
				(justify left bottom mirror)
			)
		)
		(pad "1" smd roundrect
			(at -0.701 0 180)
			(size 0.5 0.6)
			(layers "B.Cu" "B.Mask" "B.Paste")
			(roundrect_rratio 0.25)
			(net 503 "Net-(D811-C)")
			(pinfunction "C")
			(pintype "passive")
		)
		(pad "2" smd roundrect
			(at 0.699 0 180)
			(size 0.5 0.6)
			(layers "B.Cu" "B.Mask" "B.Paste")
			(roundrect_rratio 0.25)
			(net 9 "+3V3")
			(pinfunction "A")
			(pintype "passive")
		)
	)
	(footprint "antmicro-footprints:TP_SMD_0.75mm"
		(layer "B.Cu")
		(at 82.617962 166.2165)
		(property "Reference" "TP202"
			(at -0.81 1.32 0)
			(layer "B.SilkS")
			(effects
				(font
					(size 0.7 0.7)
					(thickness 0.15)
				)
				(justify right bottom mirror)
			)
		)
		(property "Value" "TP_0.75mm_SMD"
			(at 0 -1.2 0)
			(layer "B.Fab")
			(effects
				(font
					(size 0.7 0.7)
					(thickness 0.15)
				)
				(justify right bottom mirror)
			)
		)
		(property "Author" "Antmicro"
			(at 0 0 0)
			(unlocked yes)
			(layer "B.Fab")
			(hide yes)
			(effects
				(font
					(size 1 1)
					(thickness 0.15)
				)
				(justify mirror)
			)
		)
		(property "License" "Apache-2.0"
			(at 0 0 0)
			(unlocked yes)
			(layer "B.Fab")
			(hide yes)
			(effects
				(font
					(size 1 1)
					(thickness 0.15)
				)
				(justify mirror)
			)
		)
		(property "MPN" ""
			(at 0 0 0)
			(unlocked yes)
			(layer "B.Fab")
			(hide yes)
			(effects
				(font
					(size 1 1)
					(thickness 0.15)
				)
				(justify mirror)
			)
		)
		(property "Manufacturer" ""
			(at 0 0 0)
			(unlocked yes)
			(layer "B.Fab")
			(hide yes)
			(effects
				(font
					(size 1 1)
					(thickness 0.15)
				)
				(justify mirror)
			)
		)
		(sheetname "/Compute module/")
		(sheetfile "compute-module.kicad_sch")
		(attr exclude_from_pos_files exclude_from_bom)
		(fp_circle
			(center 0 0)
			(end 0.475 0)
			(stroke
				(width 0.05)
				(type default)
			)
			(fill no)
			(layer "B.CrtYd")
		)
		(fp_text user "Author: Antmicro"
			(at -0.4 -3.901 180)
			(layer "B.Fab")
			(effects
				(font
					(size 0.7 0.7)
					(thickness 0.15)
				)
				(justify left bottom mirror)
			)
		)
		(fp_text user "${REFERENCE}"
			(at -0.4 -2.7 180)
			(layer "B.Fab")
			(effects
				(font
					(size 0.7 0.7)
					(thickness 0.15)
				)
				(justify left bottom mirror)
			)
		)
		(fp_text user "License: Apache-2.0"
			(at -0.4 -5.101 180)
			(layer "B.Fab")
			(effects
				(font
					(size 0.7 0.7)
					(thickness 0.15)
				)
				(justify left bottom mirror)
			)
		)
		(pad "1" smd circle
			(at 0 0)
			(size 0.75 0.75)
			(layers "B.Cu" "B.Mask")
			(net 128 "/Compute module/nEXTRST")
			(pinfunction "1")
			(pintype "passive")
		)
	)
	(footprint "antmicro-footprints:V-QFN2030-12"
		(layer "B.Cu")
		(at 54.167962 155.8165 -90)
		(property "Reference" "U303"
			(at -5.43 2.46 90)
			(layer "B.SilkS")
			(effects
				(font
					(size 0.7 0.7)
					(thickness 0.15)
				)
				(justify left bottom mirror)
			)
		)
		(property "Value" "AP62600SJ-7"
			(at -4 -2.2 90)
			(layer "B.Fab")
			(effects
				(font
					(size 0.7 0.7)
					(thickness 0.15)
				)
				(justify left bottom mirror)
			)
		)
		(property "Datasheet" "https://www.diodes.com/assets/Datasheets/AP62600.pdf"
			(at 0 0 90)
			(layer "B.Fab")
			(hide yes)
			(effects
				(font
					(size 1.27 1.27)
					(thickness 0.15)
				)
			)
		)
		(property "MPN" "AP62600SJ-7"
			(at 0 0 270)
			(unlocked yes)
			(layer "B.Fab")
			(hide yes)
			(effects
				(font
					(size 1 1)
					(thickness 0.15)
				)
				(justify mirror)
			)
		)
		(property "Manufacturer" "Diodes Incorporated"
			(at 0 0 270)
			(unlocked yes)
			(layer "B.Fab")
			(hide yes)
			(effects
				(font
					(size 1 1)
					(thickness 0.15)
				)
				(justify mirror)
			)
		)
		(property "Author" "Antmicro"
			(at 0 0 270)
			(unlocked yes)
			(layer "B.Fab")
			(hide yes)
			(effects
				(font
					(size 1 1)
					(thickness 0.15)
				)
				(justify mirror)
			)
		)
		(property "License" "Apache-2.0"
			(at 0 0 270)
			(unlocked yes)
			(layer "B.Fab")
			(hide yes)
			(effects
				(font
					(size 1 1)
					(thickness 0.15)
				)
				(justify mirror)
			)
		)
		(sheetname "/Supply/")
		(sheetfile "supply.kicad_sch")
		(attr smd)
		(fp_line
			(start 1.8 1.276)
			(end 1.8 1.025)
			(stroke
				(width 0.15)
				(type solid)
			)
			(layer "B.SilkS")
		)
		(fp_line
			(start -1.801 1.2)
			(end -0.802 1.2)
			(stroke
				(width 0.15)
				(type solid)
			)
			(layer "B.SilkS")
		)
		(fp_line
			(start -1.801 1)
			(end -1.801 1.2)
			(stroke
				(width 0.15)
				(type solid)
			)
			(layer "B.SilkS")
		)
		(fp_line
			(start 1.8 -0.998)
			(end 1.8 -1.199)
			(stroke
				(width 0.15)
				(type solid)
			)
			(layer "B.SilkS")
		)
		(fp_line
			(start -1.801 -1.199)
			(end -1.801 -0.998)
			(stroke
				(width 0.15)
				(type solid)
			)
			(layer "B.SilkS")
		)
		(fp_line
			(start -0.802 -1.199)
			(end -1.801 -1.199)
			(stroke
				(width 0.15)
				(type solid)
			)
			(layer "B.SilkS")
		)
		(fp_line
			(start 1.8 -1.199)
			(end 0.8 -1.199)
			(stroke
				(width 0.15)
				(type solid)
			)
			(layer "B.SilkS")
		)
		(fp_circle
			(center 0.497 1.7)
			(end 0.548 1.7)
			(stroke
				(width 0.15)
				(type solid)
			)
			(fill yes)
			(layer "B.SilkS")
		)
		(fp_rect
			(start -2.026 1.525)
			(end 2.023 -1.524)
			(stroke
				(width 0.05)
				(type solid)
			)
			(fill no)
			(layer "B.CrtYd")
		)
		(fp_line
			(start 1.3 1)
			(end 1.5 0.8)
			(stroke
				(width 0.15)
				(type solid)
			)
			(layer "B.Fab")
		)
		(fp_rect
			(start -1.526 1.025)
			(end 1.523 -1.024)
			(stroke
				(width 0.15)
				(type solid)
			)
			(fill no)
			(layer "B.Fab")
		)
		(fp_text user "${REFERENCE}"
			(at -4 -4.2 90)
			(layer "B.Fab")
			(effects
				(font
					(size 0.7 0.7)
					(thickness 0.15)
				)
				(justify left bottom mirror)
			)
		)
		(fp_text user "License: Apache-2.0"
			(at -4 -6.6 90)
			(layer "B.Fab")
			(effects
				(font
					(size 0.7 0.7)
					(thickness 0.15)
				)
				(justify left bottom mirror)
			)
		)
		(fp_text user "Author: Antmicro"
			(at -4 -5.4 90)
			(layer "B.Fab")
			(effects
				(font
					(size 0.7 0.7)
					(thickness 0.15)
				)
				(justify left bottom mirror)
			)
		)
		(pad "1" smd rect
			(at 0.498 0.552)
			(size 1.6 0.35)
			(layers "B.Cu" "B.Mask" "B.Paste")
			(net 3 "GND")
			(pinfunction "PGND")
			(pintype "passive")
		)
		(pad "2" smd rect
			(at -0.5 0.552)
			(size 1.6 0.35)
			(layers "B.Cu" "B.Mask" "B.Paste")
			(net 43 "VCC")
			(pinfunction "VIN")
			(pintype "power_in")
		)
		(pad "3" smd rect
			(at -1.45 0.75)
			(size 0.35 0.8)
			(layers "B.Cu" "B.Mask" "B.Paste")
			(net 351 "/Supply/EN_5V")
			(pinfunction "EN")
			(pintype "input")
		)
		(pad "4" smd rect
			(at -1.45 0.25)
			(size 0.35 0.8)
			(layers "B.Cu" "B.Mask" "B.Paste")
			(net 390 "unconnected-(U303-MODE-Pad4)")
			(pinfunction "MODE")
			(pintype "input+no_connect")
		)
		(pad "5" smd rect
			(at -1.45 -0.248)
			(size 0.35 0.8)
			(layers "B.Cu" "B.Mask" "B.Paste")
			(net 391 "unconnected-(U303-FSEL-Pad5)")
			(pinfunction "FSEL")
			(pintype "input+no_connect")
		)
		(pad "6" smd rect
			(at -1.45 -0.748)
			(size 0.35 0.8)
			(layers "B.Cu" "B.Mask" "B.Paste")
			(net 352 "Net-(U303-PG)")
			(pinfunction "PG")
			(pintype "open_collector")
		)
		(pad "7" smd rect
			(at -0.5 -0.949 270)
			(size 0.35 0.8)
			(layers "B.Cu" "B.Mask" "B.Paste")
			(net 60 "Net-(U303-BST)")
			(pinfunction "BST")
			(pintype "input")
		)
		(pad "8" smd rect
			(at 0 -0.55)
			(size 1.6 0.35)
			(layers "B.Cu" "B.Mask" "B.Paste")
			(net 59 "/Supply/SW_5V")
			(pinfunction "SW")
			(pintype "output")
		)
		(pad "9" smd rect
			(at 1.449 -0.748 180)
			(size 0.35 0.8)
			(layers "B.Cu" "B.Mask" "B.Paste")
			(net 66 "/Supply/VCC_5V")
			(pinfunction "VCC")
			(pintype "input")
		)
		(pad "10" smd rect
			(at 1.449 -0.248 180)
			(size 0.35 0.8)
			(layers "B.Cu" "B.Mask" "B.Paste")
			(net 392 "unconnected-(U303-SS{slash}TR-Pad10)")
			(pinfunction "SS/TR")
			(pintype "input+no_connect")
		)
		(pad "11" smd rect
			(at 1.449 0.25 180)
			(size 0.35 0.8)
			(layers "B.Cu" "B.Mask" "B.Paste")
			(net 3 "GND")
			(pinfunction "GND")
			(pintype "passive")
		)
		(pad "12" smd rect
			(at 1.449 0.75 180)
			(size 0.35 0.8)
			(layers "B.Cu" "B.Mask" "B.Paste")
			(net 353 "/Supply/FB_5V")
			(pinfunction "FB")
			(pintype "input")
		)
	)
	(footprint "antmicro-footprints:SOT-523"
		(layer "B.Cu")
		(at 74.8 152.9 -90)
		(property "Reference" "Q214"
			(at 2 -1.05 180)
			(layer "B.SilkS")
			(effects
				(font
					(size 0.7 0.7)
					(thickness 0.15)
				)
				(justify left bottom mirror)
			)
		)
		(property "Value" "PJE138K"
			(at 0.1 -1.824 90)
			(layer "B.Fab")
			(effects
				(font
					(size 0.7 0.7)
					(thickness 0.15)
				)
				(justify left bottom mirror)
			)
		)
		(property "Datasheet" "https://www.mouser.com/datasheet/2/1057/PJE138K-1876698.pdf"
			(at 0 0 270)
			(layer "B.Fab")
			(hide yes)
			(effects
				(font
					(size 1.27 1.27)
					(thickness 0.15)
				)
			)
		)
		(property "MPN" "PJE138K_R1_00001"
			(at 0 0 270)
			(unlocked yes)
			(layer "B.Fab")
			(hide yes)
			(effects
				(font
					(size 1 1)
					(thickness 0.15)
				)
				(justify mirror)
			)
		)
		(property "Manufacturer" "PANJIT"
			(at 0 0 270)
			(unlocked yes)
			(layer "B.Fab")
			(hide yes)
			(effects
				(font
					(size 1 1)
					(thickness 0.15)
				)
				(justify mirror)
			)
		)
		(property "Author" "Antmicro"
			(at 0 0 270)
			(unlocked yes)
			(layer "B.Fab")
			(hide yes)
			(effects
				(font
					(size 1 1)
					(thickness 0.15)
				)
				(justify mirror)
			)
		)
		(property "License" "Apache-2.0"
			(at 0 0 270)
			(unlocked yes)
			(layer "B.Fab")
			(hide yes)
			(effects
				(font
					(size 1 1)
					(thickness 0.15)
				)
				(justify mirror)
			)
		)
		(sheetname "/Compute module/")
		(sheetfile "compute-module.kicad_sch")
		(attr smd)
		(fp_line
			(start -0.725 0.551)
			(end -0.277 0.551)
			(stroke
				(width 0.15)
				(type solid)
			)
			(layer "B.SilkS")
		)
		(fp_line
			(start -0.277 0.551)
			(end -0.277 0.75)
			(stroke
				(width 0.15)
				(type solid)
			)
			(layer "B.SilkS")
		)
		(fp_line
			(start -0.927 0.351)
			(end -0.725 0.551)
			(stroke
				(width 0.15)
				(type solid)
			)
			(layer "B.SilkS")
		)
		(fp_line
			(start -0.927 0.051)
			(end -0.927 0.351)
			(stroke
				(width 0.15)
				(type solid)
			)
			(layer "B.SilkS")
		)
		(fp_circle
			(center -0.9652 -0.9652)
			(end -0.9152 -0.9652)
			(stroke
				(width 0.15)
				(type solid)
			)
			(fill yes)
			(layer "B.SilkS")
		)
		(fp_line
			(start -1.12 1.16)
			(end 1.1 1.16)
			(stroke
				(width 0.05)
				(type solid)
			)
			(layer "B.CrtYd")
		)
		(fp_line
			(start -1.12 1.16)
			(end -1.12 -1.15)
			(stroke
				(width 0.05)
				(type solid)
			)
			(layer "B.CrtYd")
		)
		(fp_line
			(start 1.1 1.16)
			(end 1.1 -1.15)
			(stroke
				(width 0.05)
				(type solid)
			)
			(layer "B.CrtYd")
		)
		(fp_line
			(start -1.12 -1.15)
			(end 1.1 -1.15)
			(stroke
				(width 0.05)
				(type solid)
			)
			(layer "B.CrtYd")
		)
		(fp_line
			(start -0.652 0.425)
			(end -0.802 0.276)
			(stroke
				(width 0.15)
				(type solid)
			)
			(layer "B.Fab")
		)
		(fp_line
			(start 0.8 0.425)
			(end -0.652 0.425)
			(stroke
				(width 0.15)
				(type solid)
			)
			(layer "B.Fab")
		)
		(fp_line
			(start 0.8 0.425)
			(end 0.8 -0.424)
			(stroke
				(width 0.15)
				(type solid)
			)
			(layer "B.Fab")
		)
		(fp_line
			(start -0.802 0.276)
			(end -0.802 -0.424)
			(stroke
				(width 0.15)
				(type solid)
			)
			(layer "B.Fab")
		)
		(fp_line
			(start 0.8 -0.424)
			(end -0.802 -0.424)
			(stroke
				(width 0.15)
				(type solid)
			)
			(layer "B.Fab")
		)
		(fp_circle
			(center -0.9652 -0.9652)
			(end -0.9144 -0.9652)
			(stroke
				(width 0.15)
				(type solid)
			)
			(fill no)
			(layer "B.Fab")
		)
		(fp_text user "Author: Antmicro"
			(at -1.12 -6.224 90)
			(layer "B.Fab")
			(effects
				(font
					(size 0.7 0.7)
					(thickness 0.15)
				)
				(justify left bottom mirror)
			)
		)
		(fp_text user "${REFERENCE}"
			(at -1.12 -3.824 90)
			(layer "B.Fab")
			(effects
				(font
					(size 0.7 0.7)
					(thickness 0.15)
				)
				(justify left bottom mirror)
			)
		)
		(fp_text user "License: Apache-2.0"
			(at -1.12 -5.024 90)
			(layer "B.Fab")
			(effects
				(font
					(size 0.7 0.7)
					(thickness 0.15)
				)
				(justify left bottom mirror)
			)
		)
		(pad "1" smd rect
			(at -0.5 -0.65 270)
			(size 0.4 0.51)
			(layers "B.Cu" "B.Mask" "B.Paste")
			(net 18 "V_{IO}")
			(pinfunction "G")
			(pintype "input")
		)
		(pad "2" smd rect
			(at 0.498 -0.65 270)
			(size 0.4 0.51)
			(layers "B.Cu" "B.Mask" "B.Paste")
			(net 3 "GND")
			(pinfunction "S")
			(pintype "passive")
		)
		(pad "3" smd rect
			(at 0 0.652 270)
			(size 0.4 0.51)
			(layers "B.Cu" "B.Mask" "B.Paste")
			(net 500 "Net-(Q214-D)")
			(pinfunction "D")
			(pintype "passive")
		)
	)
	(footprint "antmicro-footprints:L_Coilcraft-XAL6030"
		(layer "B.Cu")
		(at 61.242962 157.1915 -90)
		(property "Reference" "L303"
			(at -3.745 -4.465 90)
			(unlocked yes)
			(layer "B.SilkS")
			(effects
				(font
					(size 0.7 0.7)
					(thickness 0.15)
				)
				(justify left bottom mirror)
			)
		)
		(property "Value" "L_1u8_14A_Coilcraft-XAL6030"
			(at 0 -4.7 90)
			(unlocked yes)
			(layer "B.Fab")
			(effects
				(font
					(size 0.7 0.7)
					(thickness 0.15)
				)
				(justify left bottom mirror)
			)
		)
		(property "Datasheet" "https://www.mouser.com/datasheet/2/597/xal60xx-270658.pdf"
			(at 0 0 270)
			(layer "B.Fab")
			(hide yes)
			(effects
				(font
					(size 1.27 1.27)
					(thickness 0.15)
				)
			)
		)
		(property "Manufacturer" "Coilcraft"
			(at 0 0 270)
			(unlocked yes)
			(layer "B.Fab")
			(hide yes)
			(effects
				(font
					(size 1 1)
					(thickness 0.15)
				)
				(justify mirror)
			)
		)
		(property "MPN" "XAL6030-182MEC"
			(at 0 0 270)
			(unlocked yes)
			(layer "B.Fab")
			(hide yes)
			(effects
				(font
					(size 1 1)
					(thickness 0.15)
				)
				(justify mirror)
			)
		)
		(property "Size" "6.36x6.56"
			(at 0 0 270)
			(unlocked yes)
			(layer "B.Fab")
			(hide yes)
			(effects
				(font
					(size 1 1)
					(thickness 0.15)
				)
				(justify mirror)
			)
		)
		(property "Val" "1.8u/14A"
			(at 0 0 270)
			(unlocked yes)
			(layer "B.Fab")
			(hide yes)
			(effects
				(font
					(size 1 1)
					(thickness 0.15)
				)
				(justify mirror)
			)
		)
		(property "Author" "Antmicro"
			(at 0 0 270)
			(unlocked yes)
			(layer "B.Fab")
			(hide yes)
			(effects
				(font
					(size 1 1)
					(thickness 0.15)
				)
				(justify mirror)
			)
		)
		(property "License" "Apache-2.0"
			(at 0 0 270)
			(unlocked yes)
			(layer "B.Fab")
			(hide yes)
			(effects
				(font
					(size 1 1)
					(thickness 0.15)
				)
				(justify mirror)
			)
		)
		(property "ISat" "18.2 A"
			(at 0 0 270)
			(unlocked yes)
			(layer "B.Fab")
			(hide yes)
			(effects
				(font
					(size 1 1)
					(thickness 0.15)
				)
				(justify mirror)
			)
		)
		(property "IMax" "14 A"
			(at 0 0 270)
			(unlocked yes)
			(layer "B.Fab")
			(hide yes)
			(effects
				(font
					(size 1 1)
					(thickness 0.15)
				)
				(justify mirror)
			)
		)
		(sheetname "/Supply/")
		(sheetfile "supply.kicad_sch")
		(attr smd)
		(fp_rect
			(start -3.299 3.4)
			(end 3.299 -3.4)
			(stroke
				(width 0.15)
				(type solid)
			)
			(fill no)
			(layer "B.SilkS")
		)
		(fp_rect
			(start -3.52 3.63)
			(end 3.52 -3.63)
			(stroke
				(width 0.05)
				(type solid)
			)
			(fill no)
			(layer "B.CrtYd")
		)
		(fp_rect
			(start -3.279 3.38)
			(end 3.279 -3.38)
			(stroke
				(width 0.15)
				(type solid)
			)
			(fill no)
			(layer "B.Fab")
		)
		(fp_text user "Author: Antmicro"
			(at -3.52 -6.7 90)
			(layer "B.Fab")
			(effects
				(font
					(size 0.7 0.7)
					(thickness 0.15)
				)
				(justify left bottom mirror)
			)
		)
		(fp_text user "${REFERENCE}"
			(at -3.52 -7.9 90)
			(unlocked yes)
			(layer "B.Fab")
			(effects
				(font
					(size 0.7 0.7)
					(thickness 0.15)
				)
				(justify left bottom mirror)
			)
		)
		(fp_text user "License: Apache-2.0"
			(at -3.52 -9.1 90)
			(layer "B.Fab")
			(effects
				(font
					(size 0.7 0.7)
					(thickness 0.15)
				)
				(justify left bottom mirror)
			)
		)
		(pad "1" smd roundrect
			(at -2.02 0 270)
			(size 1.43 5.5)
			(layers "B.Cu" "B.Mask" "B.Paste")
			(roundrect_rratio 0.1)
			(net 59 "/Supply/SW_5V")
			(pintype "passive")
		)
		(pad "2" smd roundrect
			(at 2.019 0 270)
			(size 1.43 5.5)
			(layers "B.Cu" "B.Mask" "B.Paste")
			(roundrect_rratio 0.1)
			(net 77 "/Supply/OUT_5V")
			(pintype "passive")
		)
	)
	(footprint "antmicro-footprints:R_0402_1005Metric"
		(layer "B.Cu")
		(at 108.077962 133.0415 -90)
		(descr "Resistor SMD 0402")
		(tags "resistor SMD 0402")
		(property "Reference" "R318"
			(at -3.675 -0.4 90)
			(layer "B.SilkS")
			(effects
				(font
					(size 0.7 0.7)
					(thickness 0.15)
				)
				(justify left bottom mirror)
			)
		)
		(property "Value" "R_6k8_0402"
			(at -1.011843 -1.772047 90)
			(layer "B.Fab")
			(effects
				(font
					(size 0.7 0.7)
					(thickness 0.15)
				)
				(justify left bottom mirror)
			)
		)
		(property "Datasheet" "https://www.bourns.com/docs/product-datasheets/cr.pdf"
			(at 0 0 270)
			(layer "B.Fab")
			(hide yes)
			(effects
				(font
					(size 1.27 1.27)
					(thickness 0.15)
				)
			)
		)
		(property "MPN" "CR0402-FX-6801GLF"
			(at 0 0 270)
			(unlocked yes)
			(layer "B.Fab")
			(hide yes)
			(effects
				(font
					(size 1 1)
					(thickness 0.15)
				)
				(justify mirror)
			)
		)
		(property "Manufacturer" "Bourns"
			(at 0 0 270)
			(unlocked yes)
			(layer "B.Fab")
			(hide yes)
			(effects
				(font
					(size 1 1)
					(thickness 0.15)
				)
				(justify mirror)
			)
		)
		(property "License" "Apache-2.0"
			(at 0 0 270)
			(unlocked yes)
			(layer "B.Fab")
			(hide yes)
			(effects
				(font
					(size 1 1)
					(thickness 0.15)
				)
				(justify mirror)
			)
		)
		(property "Author" "Antmicro"
			(at 0 0 270)
			(unlocked yes)
			(layer "B.Fab")
			(hide yes)
			(effects
				(font
					(size 1 1)
					(thickness 0.15)
				)
				(justify mirror)
			)
		)
		(property "Val" "6k8"
			(at 0 0 270)
			(unlocked yes)
			(layer "B.Fab")
			(hide yes)
			(effects
				(font
					(size 1 1)
					(thickness 0.15)
				)
				(justify mirror)
			)
		)
		(property "Tolerance" "1%"
			(at 0 0 270)
			(unlocked yes)
			(layer "B.Fab")
			(hide yes)
			(effects
				(font
					(size 1 1)
					(thickness 0.15)
				)
				(justify mirror)
			)
		)
		(sheetname "/Supply/")
		(sheetfile "supply.kicad_sch")
		(attr smd)
		(fp_rect
			(start -0.925 0.47)
			(end 0.925 -0.47)
			(stroke
				(width 0.05)
				(type default)
			)
			(fill no)
			(layer "B.CrtYd")
		)
		(fp_rect
			(start -0.5 0.25)
			(end 0.5 -0.25)
			(stroke
				(width 0.15)
				(type solid)
			)
			(fill no)
			(layer "B.Fab")
		)
		(fp_text user "Author: Antmicro"
			(at -0.95 -4.169 90)
			(layer "B.Fab")
			(effects
				(font
					(size 0.7 0.7)
					(thickness 0.15)
				)
				(justify left bottom mirror)
			)
		)
		(fp_text user "License: Apache-2.0"
			(at -0.95 -5.169 90)
			(layer "B.Fab")
			(effects
				(font
					(size 0.7 0.7)
					(thickness 0.15)
				)
				(justify left bottom mirror)
			)
		)
		(fp_text user "${REFERENCE}"
			(at -0.95 -3.168 90)
			(layer "B.Fab")
			(effects
				(font
					(size 0.7 0.7)
					(thickness 0.15)
				)
				(justify left bottom mirror)
			)
		)
		(pad "1" smd roundrect
			(at -0.48 0 270)
			(size 0.59 0.64)
			(layers "B.Cu" "B.Mask" "B.Paste")
			(roundrect_rratio 0.25)
			(net 354 "/Supply/FB_M2")
			(pintype "passive")
		)
		(pad "2" smd roundrect
			(at 0.48 0 270)
			(size 0.59 0.64)
			(layers "B.Cu" "B.Mask" "B.Paste")
			(roundrect_rratio 0.25)
			(net 78 "/Supply/OUT_M2")
			(pintype "passive")
		)
	)
	(footprint "antmicro-footprints:Vishay_PowerPAK_1212-8_Single"
		(layer "B.Cu")
		(at 49.766962 163.3075 -90)
		(descr "PowerPAK 1212-8 Single")
		(tags "Vishay PowerPAK 1212-8 Single")
		(property "Reference" "Q306"
			(at -2.041 1.399 0)
			(layer "B.SilkS")
			(effects
				(font
					(size 0.7 0.7)
					(thickness 0.15)
				)
				(justify right bottom mirror)
			)
		)
		(property "Value" "SQS401EN-T1_BE3"
			(at 0 -2.7 90)
			(layer "B.Fab")
			(effects
				(font
					(size 0.7 0.7)
					(thickness 0.15)
				)
				(justify left bottom mirror)
			)
		)
		(property "Datasheet" "https://www.vishay.com/docs/65529/sqs401en.pdf"
			(at 0 0 270)
			(layer "B.Fab")
			(hide yes)
			(effects
				(font
					(size 1.27 1.27)
					(thickness 0.15)
				)
			)
		)
		(property "MPN" "SQS401EN-T1_BE3"
			(at 0 0 270)
			(unlocked yes)
			(layer "B.Fab")
			(hide yes)
			(effects
				(font
					(size 1 1)
					(thickness 0.15)
				)
				(justify mirror)
			)
		)
		(property "Manufacturer" "Vishay"
			(at 0 0 270)
			(unlocked yes)
			(layer "B.Fab")
			(hide yes)
			(effects
				(font
					(size 1 1)
					(thickness 0.15)
				)
				(justify mirror)
			)
		)
		(property "Author" "Antmicro"
			(at 0 0 270)
			(unlocked yes)
			(layer "B.Fab")
			(hide yes)
			(effects
				(font
					(size 1 1)
					(thickness 0.15)
				)
				(justify mirror)
			)
		)
		(property "License" "Apache-2.0"
			(at 0 0 270)
			(unlocked yes)
			(layer "B.Fab")
			(hide yes)
			(effects
				(font
					(size 1 1)
					(thickness 0.15)
				)
				(justify mirror)
			)
		)
		(sheetname "/Supply/")
		(sheetfile "supply.kicad_sch")
		(attr smd)
		(fp_line
			(start -1.651 1.651)
			(end 1.648 1.651)
			(stroke
				(width 0.15)
				(type solid)
			)
			(layer "B.SilkS")
		)
		(fp_line
			(start -1.651 1.651)
			(end -1.651 1.317)
			(stroke
				(width 0.15)
				(type solid)
			)
			(layer "B.SilkS")
		)
		(fp_line
			(start 1.648 1.651)
			(end 1.648 1.317)
			(stroke
				(width 0.15)
				(type solid)
			)
			(layer "B.SilkS")
		)
		(fp_line
			(start -1.635 -1.3)
			(end -1.635 -1.634)
			(stroke
				(width 0.15)
				(type solid)
			)
			(layer "B.SilkS")
		)
		(fp_line
			(start 1.634 -1.3)
			(end 1.634 -1.634)
			(stroke
				(width 0.15)
				(type solid)
			)
			(layer "B.SilkS")
		)
		(fp_line
			(start -1.635 -1.634)
			(end 1.634 -1.634)
			(stroke
				(width 0.15)
				(type solid)
			)
			(layer "B.SilkS")
		)
		(fp_circle
			(center -1.9 1.4)
			(end -1.85 1.4)
			(stroke
				(width 0.15)
				(type solid)
			)
			(fill yes)
			(layer "B.SilkS")
		)
		(fp_rect
			(start -2 1.8)
			(end 2 -1.798)
			(stroke
				(width 0.05)
				(type solid)
			)
			(fill no)
			(layer "B.CrtYd")
		)
		(fp_line
			(start -1.6425 1.4175)
			(end -1.4175 1.6425)
			(stroke
				(width 0.15)
				(type solid)
			)
			(layer "B.Fab")
		)
		(fp_rect
			(start -1.651 1.651)
			(end 1.648 -1.648)
			(stroke
				(width 0.15)
				(type solid)
			)
			(fill no)
			(layer "B.Fab")
		)
		(fp_text user "Author: Antmicro"
			(at -8 -5.9 90)
			(layer "B.Fab")
			(effects
				(font
					(size 0.7 0.7)
					(thickness 0.15)
				)
				(justify left bottom mirror)
			)
		)
		(fp_text user "${REFERENCE}"
			(at -8 -4.7 90)
			(layer "B.Fab")
			(effects
				(font
					(size 0.7 0.7)
					(thickness 0.15)
				)
				(justify left bottom mirror)
			)
		)
		(fp_text user "License: Apache-2.0"
			(at -8 -7.1 90)
			(layer "B.Fab")
			(effects
				(font
					(size 0.7 0.7)
					(thickness 0.15)
				)
				(justify left bottom mirror)
			)
		)
		(pad "1" smd rect
			(at -1.436 0.99 270)
			(size 0.99 0.405)
			(layers "B.Cu" "B.Mask" "B.Paste")
			(net 21 "/Supply/VCC_IN")
			(pinfunction "S")
			(pintype "passive")
		)
		(pad "2" smd rect
			(at -1.436 0.332 270)
			(size 0.99 0.405)
			(layers "B.Cu" "B.Mask" "B.Paste")
			(net 21 "/Supply/VCC_IN")
			(pinfunction "S")
			(pintype "passive")
		)
		(pad "3" smd rect
			(at -1.436 -0.33 270)
			(size 0.99 0.405)
			(layers "B.Cu" "B.Mask" "B.Paste")
			(net 21 "/Supply/VCC_IN")
			(pinfunction "S")
			(pintype "passive")
		)
		(pad "4" smd rect
			(at -1.436 -0.988 270)
			(size 0.99 0.405)
			(layers "B.Cu" "B.Mask" "B.Paste")
			(net 337 "Net-(Q303-BIAS)")
			(pinfunction "G")
			(pintype "input")
		)
		(pad "5" smd custom
			(at 0.557 0 270)
			(size 1.725 2.235)
			(layers "B.Cu" "B.Mask" "B.Paste")
			(net 443 "/Supply/V_{BUS}")
			(pinfunction "D")
			(pintype "passive")
			(zone_connect 2)
			(options
				(clearance outline)
				(anchor rect)
			)
			(primitives
				(gr_poly
					(pts
						(xy 0.8625 -0.1275) (xy 0.8625 0.1275) (xy 1.3725 0.1275) (xy 1.3725 0.5325) (xy 0.8625 0.5325)
						(xy 0.8625 0.7875) (xy 1.3725 0.7875) (xy 1.3725 1.195) (xy 0.6125 1.195) (xy 0.6125 -1.195) (xy 1.3725 -1.195)
						(xy 1.3725 -0.7875) (xy 0.8625 -0.7875) (xy 0.8625 -0.5325) (xy 1.3725 -0.5325) (xy 1.3725 -0.1275)
					)
					(width 0)
					(fill yes)
				)
			)
		)
	)
	(footprint "antmicro-footprints:R_0402_1005Metric"
		(layer "B.Cu")
		(at 76.442962 150.6165)
		(descr "Resistor SMD 0402")
		(tags "resistor SMD 0402")
		(property "Reference" "R224"
			(at -0.892962 -0.5165 0)
			(layer "B.SilkS")
			(effects
				(font
					(size 0.7 0.7)
					(thickness 0.15)
				)
				(justify right bottom mirror)
			)
		)
		(property "Value" "R_1k_0402"
			(at -1.011843 -1.772047 0)
			(layer "B.Fab")
			(effects
				(font
					(size 0.7 0.7)
					(thickness 0.15)
				)
				(justify right bottom mirror)
			)
		)
		(property "Datasheet" "https://www.bourns.com/docs/product-datasheets/cr.pdf"
			(at 0 0 0)
			(layer "B.Fab")
			(hide yes)
			(effects
				(font
					(size 1.27 1.27)
					(thickness 0.15)
				)
			)
		)
		(property "MPN" "CR0402-FX-1001GLF"
			(at 0 0 0)
			(unlocked yes)
			(layer "B.Fab")
			(hide yes)
			(effects
				(font
					(size 1 1)
					(thickness 0.15)
				)
				(justify mirror)
			)
		)
		(property "Manufacturer" "Bourns"
			(at 0 0 0)
			(unlocked yes)
			(layer "B.Fab")
			(hide yes)
			(effects
				(font
					(size 1 1)
					(thickness 0.15)
				)
				(justify mirror)
			)
		)
		(property "License" "Apache-2.0"
			(at 0 0 0)
			(unlocked yes)
			(layer "B.Fab")
			(hide yes)
			(effects
				(font
					(size 1 1)
					(thickness 0.15)
				)
				(justify mirror)
			)
		)
		(property "Author" "Antmicro"
			(at 0 0 0)
			(unlocked yes)
			(layer "B.Fab")
			(hide yes)
			(effects
				(font
					(size 1 1)
					(thickness 0.15)
				)
				(justify mirror)
			)
		)
		(property "Val" "1k"
			(at 0 0 0)
			(unlocked yes)
			(layer "B.Fab")
			(hide yes)
			(effects
				(font
					(size 1 1)
					(thickness 0.15)
				)
				(justify mirror)
			)
		)
		(property "Tolerance" "1%"
			(at 0 0 0)
			(unlocked yes)
			(layer "B.Fab")
			(hide yes)
			(effects
				(font
					(size 1 1)
					(thickness 0.15)
				)
				(justify mirror)
			)
		)
		(sheetname "/Compute module/")
		(sheetfile "compute-module.kicad_sch")
		(attr smd)
		(fp_rect
			(start -0.925 0.47)
			(end 0.925 -0.47)
			(stroke
				(width 0.05)
				(type default)
			)
			(fill no)
			(layer "B.CrtYd")
		)
		(fp_rect
			(start -0.5 0.25)
			(end 0.5 -0.25)
			(stroke
				(width 0.15)
				(type solid)
			)
			(fill no)
			(layer "B.Fab")
		)
		(fp_text user "${REFERENCE}"
			(at -0.95 -3.168 180)
			(layer "B.Fab")
			(effects
				(font
					(size 0.7 0.7)
					(thickness 0.15)
				)
				(justify left bottom mirror)
			)
		)
		(fp_text user "Author: Antmicro"
			(at -0.95 -4.169 180)
			(layer "B.Fab")
			(effects
				(font
					(size 0.7 0.7)
					(thickness 0.15)
				)
				(justify left bottom mirror)
			)
		)
		(fp_text user "License: Apache-2.0"
			(at -0.95 -5.169 180)
			(layer "B.Fab")
			(effects
				(font
					(size 0.7 0.7)
					(thickness 0.15)
				)
				(justify left bottom mirror)
			)
		)
		(pad "1" smd roundrect
			(at -0.48 0)
			(size 0.59 0.64)
			(layers "B.Cu" "B.Mask" "B.Paste")
			(roundrect_rratio 0.25)
			(net 331 "Net-(Q210-D)")
			(pintype "passive")
		)
		(pad "2" smd roundrect
			(at 0.48 0)
			(size 0.59 0.64)
			(layers "B.Cu" "B.Mask" "B.Paste")
			(roundrect_rratio 0.25)
			(net 465 "Net-(D205-C)")
			(pintype "passive")
		)
	)
	(footprint "antmicro-footprints:C_0402_1005Metric"
		(layer "B.Cu")
		(at 75.342962 136.9915 180)
		(descr "Capacitor SMD 0402")
		(tags "capacitor SMD 0402")
		(property "Reference" "C909"
			(at 0.945 -0.375 0)
			(layer "B.SilkS")
			(effects
				(font
					(size 0.7 0.7)
					(thickness 0.15)
				)
				(justify left bottom mirror)
			)
		)
		(property "Value" "C_100n_0402"
			(at -1.022927 -2.155213 0)
			(layer "B.Fab")
			(effects
				(font
					(size 0.7 0.7)
					(thickness 0.15)
				)
				(justify left bottom mirror)
			)
		)
		(property "Datasheet" "https://www.murata.com/products/productdetail?partno=GRM155R61H104KE14%23"
			(at 0 0 180)
			(layer "B.Fab")
			(hide yes)
			(effects
				(font
					(size 1.27 1.27)
					(thickness 0.15)
				)
			)
		)
		(property "Manufacturer" "Murata"
			(at 0 0 180)
			(unlocked yes)
			(layer "B.Fab")
			(hide yes)
			(effects
				(font
					(size 1 1)
					(thickness 0.15)
				)
				(justify mirror)
			)
		)
		(property "MPN" "GRM155R61H104KE14D"
			(at 0 0 180)
			(unlocked yes)
			(layer "B.Fab")
			(hide yes)
			(effects
				(font
					(size 1 1)
					(thickness 0.15)
				)
				(justify mirror)
			)
		)
		(property "Val" "100n"
			(at 0 0 180)
			(unlocked yes)
			(layer "B.Fab")
			(hide yes)
			(effects
				(font
					(size 1 1)
					(thickness 0.15)
				)
				(justify mirror)
			)
		)
		(property "License" "Apache-2.0"
			(at 0 0 180)
			(unlocked yes)
			(layer "B.Fab")
			(hide yes)
			(effects
				(font
					(size 1 1)
					(thickness 0.15)
				)
				(justify mirror)
			)
		)
		(property "Author" "Antmicro"
			(at 0 0 180)
			(unlocked yes)
			(layer "B.Fab")
			(hide yes)
			(effects
				(font
					(size 1 1)
					(thickness 0.15)
				)
				(justify mirror)
			)
		)
		(property "Voltage" "50V"
			(at 0 0 180)
			(unlocked yes)
			(layer "B.Fab")
			(hide yes)
			(effects
				(font
					(size 1 1)
					(thickness 0.15)
				)
				(justify mirror)
			)
		)
		(property "Dielectric" "X5R"
			(at 0 0 180)
			(unlocked yes)
			(layer "B.Fab")
			(hide yes)
			(effects
				(font
					(size 1 1)
					(thickness 0.15)
				)
				(justify mirror)
			)
		)
		(sheetname "/USB/")
		(sheetfile "usb.kicad_sch")
		(attr smd)
		(fp_rect
			(start -0.925 0.47)
			(end 0.925 -0.47)
			(stroke
				(width 0.05)
				(type default)
			)
			(fill no)
			(layer "B.CrtYd")
		)
		(fp_line
			(start 0.504 0.25)
			(end 0.504 -0.248)
			(stroke
				(width 0.15)
				(type solid)
			)
			(layer "B.Fab")
		)
		(fp_line
			(start 0.504 -0.248)
			(end -0.494 -0.248)
			(stroke
				(width 0.15)
				(type solid)
			)
			(layer "B.Fab")
		)
		(fp_line
			(start -0.494 0.25)
			(end 0.504 0.25)
			(stroke
				(width 0.15)
				(type solid)
			)
			(layer "B.Fab")
		)
		(fp_line
			(start -0.494 -0.248)
			(end -0.494 0.25)
			(stroke
				(width 0.15)
				(type solid)
			)
			(layer "B.Fab")
		)
		(fp_text user "License: Apache-2.0"
			(at -0.939 -5.799 0)
			(layer "B.Fab")
			(effects
				(font
					(size 0.7 0.7)
					(thickness 0.15)
				)
				(justify left bottom mirror)
			)
		)
		(fp_text user "${REFERENCE}"
			(at -0.939 -4.599 0)
			(layer "B.Fab")
			(effects
				(font
					(size 0.7 0.7)
					(thickness 0.15)
				)
				(justify left bottom mirror)
			)
		)
		(fp_text user "Author: Antmicro"
			(at -0.939 -3.399 0)
			(layer "B.Fab")
			(effects
				(font
					(size 0.7 0.7)
					(thickness 0.15)
				)
				(justify left bottom mirror)
			)
		)
		(pad "1" smd roundrect
			(at -0.48 0 180)
			(size 0.59 0.64)
			(layers "B.Cu" "B.Mask" "B.Paste")
			(roundrect_rratio 0.25)
			(net 29 "/USB/USBD_SVBUS")
			(pintype "passive")
		)
		(pad "2" smd roundrect
			(at 0.48 0 180)
			(size 0.59 0.64)
			(layers "B.Cu" "B.Mask" "B.Paste")
			(roundrect_rratio 0.25)
			(net 3 "GND")
			(pintype "passive")
		)
	)
	(footprint "antmicro-footprints:R_0402_1005Metric"
		(layer "B.Cu")
		(at 90.387962 154.3665)
		(descr "Resistor SMD 0402")
		(tags "resistor SMD 0402")
		(property "Reference" "R231"
			(at -1.71 3.94 0)
			(layer "B.SilkS")
			(effects
				(font
					(size 0.7 0.7)
					(thickness 0.15)
				)
				(justify right bottom mirror)
			)
		)
		(property "Value" "R_10k_0402"
			(at -1.011843 -1.772047 0)
			(layer "B.Fab")
			(effects
				(font
					(size 0.7 0.7)
					(thickness 0.15)
				)
				(justify right bottom mirror)
			)
		)
		(property "Datasheet" "https://www.bourns.com/docs/product-datasheets/cr.pdf"
			(at 0 0 0)
			(layer "B.Fab")
			(hide yes)
			(effects
				(font
					(size 1.27 1.27)
					(thickness 0.15)
				)
			)
		)
		(property "MPN" "CR0402-FX-1002GLF"
			(at 0 0 0)
			(unlocked yes)
			(layer "B.Fab")
			(hide yes)
			(effects
				(font
					(size 1 1)
					(thickness 0.15)
				)
				(justify mirror)
			)
		)
		(property "Manufacturer" "Bourns"
			(at 0 0 0)
			(unlocked yes)
			(layer "B.Fab")
			(hide yes)
			(effects
				(font
					(size 1 1)
					(thickness 0.15)
				)
				(justify mirror)
			)
		)
		(property "License" "Apache-2.0"
			(at 0 0 0)
			(unlocked yes)
			(layer "B.Fab")
			(hide yes)
			(effects
				(font
					(size 1 1)
					(thickness 0.15)
				)
				(justify mirror)
			)
		)
		(property "Author" "Antmicro"
			(at 0 0 0)
			(unlocked yes)
			(layer "B.Fab")
			(hide yes)
			(effects
				(font
					(size 1 1)
					(thickness 0.15)
				)
				(justify mirror)
			)
		)
		(property "Val" "10k"
			(at 0 0 0)
			(unlocked yes)
			(layer "B.Fab")
			(hide yes)
			(effects
				(font
					(size 1 1)
					(thickness 0.15)
				)
				(justify mirror)
			)
		)
		(property "Tolerance" "1%"
			(at 0 0 0)
			(unlocked yes)
			(layer "B.Fab")
			(hide yes)
			(effects
				(font
					(size 1 1)
					(thickness 0.15)
				)
				(justify mirror)
			)
		)
		(sheetname "/Compute module/")
		(sheetfile "compute-module.kicad_sch")
		(attr smd)
		(fp_rect
			(start -0.925 0.47)
			(end 0.925 -0.47)
			(stroke
				(width 0.05)
				(type default)
			)
			(fill no)
			(layer "B.CrtYd")
		)
		(fp_rect
			(start -0.5 0.25)
			(end 0.5 -0.25)
			(stroke
				(width 0.15)
				(type solid)
			)
			(fill no)
			(layer "B.Fab")
		)
		(fp_text user "License: Apache-2.0"
			(at -0.95 -5.169 180)
			(layer "B.Fab")
			(effects
				(font
					(size 0.7 0.7)
					(thickness 0.15)
				)
				(justify left bottom mirror)
			)
		)
		(fp_text user "${REFERENCE}"
			(at -0.95 -3.168 180)
			(layer "B.Fab")
			(effects
				(font
					(size 0.7 0.7)
					(thickness 0.15)
				)
				(justify left bottom mirror)
			)
		)
		(fp_text user "Author: Antmicro"
			(at -0.95 -4.169 180)
			(layer "B.Fab")
			(effects
				(font
					(size 0.7 0.7)
					(thickness 0.15)
				)
				(justify left bottom mirror)
			)
		)
		(pad "1" smd roundrect
			(at -0.48 0)
			(size 0.59 0.64)
			(layers "B.Cu" "B.Mask" "B.Paste")
			(roundrect_rratio 0.25)
			(net 3 "GND")
			(pintype "passive")
		)
		(pad "2" smd roundrect
			(at 0.48 0)
			(size 0.59 0.64)
			(layers "B.Cu" "B.Mask" "B.Paste")
			(roundrect_rratio 0.25)
			(net 345 "Net-(U204-A2)")
			(pintype "passive")
		)
	)
	(footprint "antmicro-footprints:C_0402_1005Metric"
		(layer "B.Cu")
		(at 119.142962 132.3165 -90)
		(descr "Capacitor SMD 0402")
		(tags "capacitor SMD 0402")
		(property "Reference" "C501"
			(at -1.31 0.575 90)
			(layer "B.SilkS")
			(effects
				(font
					(size 0.7 0.7)
					(thickness 0.15)
				)
				(justify left bottom mirror)
			)
		)
		(property "Value" "C_10u_0402"
			(at -1.022927 -2.155213 90)
			(layer "B.Fab")
			(effects
				(font
					(size 0.7 0.7)
					(thickness 0.15)
				)
				(justify left bottom mirror)
			)
		)
		(property "Datasheet" "https://www.yageo.com/en/Chart/Download/pdf/CC0402MRX5R5BB106"
			(at 0 0 270)
			(layer "B.Fab")
			(hide yes)
			(effects
				(font
					(size 1.27 1.27)
					(thickness 0.15)
				)
			)
		)
		(property "MPN" "CC0402MRX5R5BB106"
			(at 0 0 270)
			(unlocked yes)
			(layer "B.Fab")
			(hide yes)
			(effects
				(font
					(size 1 1)
					(thickness 0.15)
				)
				(justify mirror)
			)
		)
		(property "Manufacturer" "YAGEO"
			(at 0 0 270)
			(unlocked yes)
			(layer "B.Fab")
			(hide yes)
			(effects
				(font
					(size 1 1)
					(thickness 0.15)
				)
				(justify mirror)
			)
		)
		(property "License" "Apache-2.0"
			(at 0 0 270)
			(unlocked yes)
			(layer "B.Fab")
			(hide yes)
			(effects
				(font
					(size 1 1)
					(thickness 0.15)
				)
				(justify mirror)
			)
		)
		(property "Author" "Antmicro"
			(at 0 0 270)
			(unlocked yes)
			(layer "B.Fab")
			(hide yes)
			(effects
				(font
					(size 1 1)
					(thickness 0.15)
				)
				(justify mirror)
			)
		)
		(property "Val" "10u"
			(at 0 0 270)
			(unlocked yes)
			(layer "B.Fab")
			(hide yes)
			(effects
				(font
					(size 1 1)
					(thickness 0.15)
				)
				(justify mirror)
			)
		)
		(property "Voltage" ""
			(at 0 0 270)
			(unlocked yes)
			(layer "B.Fab")
			(hide yes)
			(effects
				(font
					(size 1 1)
					(thickness 0.15)
				)
				(justify mirror)
			)
		)
		(property "Dielectric" ""
			(at 0 0 270)
			(unlocked yes)
			(layer "B.Fab")
			(hide yes)
			(effects
				(font
					(size 1 1)
					(thickness 0.15)
				)
				(justify mirror)
			)
		)
		(sheetname "/NVMe & microSD/")
		(sheetfile "nvme-micro-sd.kicad_sch")
		(attr smd)
		(fp_rect
			(start -0.925 0.47)
			(end 0.925 -0.47)
			(stroke
				(width 0.05)
				(type default)
			)
			(fill no)
			(layer "B.CrtYd")
		)
		(fp_line
			(start -0.494 0.25)
			(end 0.504 0.25)
			(stroke
				(width 0.15)
				(type solid)
			)
			(layer "B.Fab")
		)
		(fp_line
			(start 0.504 0.25)
			(end 0.504 -0.248)
			(stroke
				(width 0.15)
				(type solid)
			)
			(layer "B.Fab")
		)
		(fp_line
			(start -0.494 -0.248)
			(end -0.494 0.25)
			(stroke
				(width 0.15)
				(type solid)
			)
			(layer "B.Fab")
		)
		(fp_line
			(start 0.504 -0.248)
			(end -0.494 -0.248)
			(stroke
				(width 0.15)
				(type solid)
			)
			(layer "B.Fab")
		)
		(fp_text user "${REFERENCE}"
			(at -0.939 -4.599 90)
			(layer "B.Fab")
			(effects
				(font
					(size 0.7 0.7)
					(thickness 0.15)
				)
				(justify left bottom mirror)
			)
		)
		(fp_text user "Author: Antmicro"
			(at -0.939 -3.399 90)
			(layer "B.Fab")
			(effects
				(font
					(size 0.7 0.7)
					(thickness 0.15)
				)
				(justify left bottom mirror)
			)
		)
		(fp_text user "License: Apache-2.0"
			(at -0.939 -5.799 90)
			(layer "B.Fab")
			(effects
				(font
					(size 0.7 0.7)
					(thickness 0.15)
				)
				(justify left bottom mirror)
			)
		)
		(pad "1" smd roundrect
			(at -0.48 0 270)
			(size 0.59 0.64)
			(layers "B.Cu" "B.Mask" "B.Paste")
			(roundrect_rratio 0.25)
			(net 3 "GND")
			(pintype "passive")
		)
		(pad "2" smd roundrect
			(at 0.48 0 270)
			(size 0.59 0.64)
			(layers "B.Cu" "B.Mask" "B.Paste")
			(roundrect_rratio 0.25)
			(net 65 "3V3_SSD")
			(pintype "passive")
		)
	)
	(footprint "antmicro-footprints:TSOT23-6"
		(layer "B.Cu")
		(at 66.162962 163.7465 90)
		(property "Reference" "U302"
			(at -4.71 0.065 90)
			(layer "B.SilkS")
			(effects
				(font
					(size 0.7 0.7)
					(thickness 0.15)
				)
				(justify right bottom mirror)
			)
		)
		(property "Value" "AP62301_TSOT"
			(at 0 -2.6 90)
			(layer "B.Fab")
			(effects
				(font
					(size 0.7 0.7)
					(thickness 0.15)
				)
				(justify right bottom mirror)
			)
		)
		(property "Datasheet" "https://www.diodes.com/assets/Datasheets/AP62300_AP62301_AP62300T.pdf"
			(at 0 0 90)
			(layer "B.Fab")
			(hide yes)
			(effects
				(font
					(size 1.27 1.27)
					(thickness 0.15)
				)
			)
		)
		(property "MPN" "AP62301WU-7"
			(at 0 0 90)
			(unlocked yes)
			(layer "B.Fab")
			(hide yes)
			(effects
				(font
					(size 1 1)
					(thickness 0.15)
				)
				(justify mirror)
			)
		)
		(property "Manufacturer" "Diodes Incorporated"
			(at 0 0 90)
			(unlocked yes)
			(layer "B.Fab")
			(hide yes)
			(effects
				(font
					(size 1 1)
					(thickness 0.15)
				)
				(justify mirror)
			)
		)
		(property "Author" "Antmicro"
			(at 0 0 90)
			(unlocked yes)
			(layer "B.Fab")
			(hide yes)
			(effects
				(font
					(size 1 1)
					(thickness 0.15)
				)
				(justify mirror)
			)
		)
		(property "License" "Apache-2.0"
			(at 0 0 90)
			(unlocked yes)
			(layer "B.Fab")
			(hide yes)
			(effects
				(font
					(size 1 1)
					(thickness 0.15)
				)
				(justify mirror)
			)
		)
		(sheetname "/Supply/")
		(sheetfile "supply.kicad_sch")
		(attr smd)
		(fp_line
			(start 1 -1.55)
			(end -1 -1.55)
			(stroke
				(width 0.15)
				(type solid)
			)
			(layer "B.SilkS")
		)
		(fp_line
			(start 1 -1.55)
			(end 1 -1.4)
			(stroke
				(width 0.15)
				(type solid)
			)
			(layer "B.SilkS")
		)
		(fp_line
			(start -1 -1.55)
			(end -1 -1.4)
			(stroke
				(width 0.15)
				(type solid)
			)
			(layer "B.SilkS")
		)
		(fp_line
			(start 1 1.497)
			(end 1 1.375)
			(stroke
				(width 0.15)
				(type solid)
			)
			(layer "B.SilkS")
		)
		(fp_line
			(start 1 1.497)
			(end -1 1.5)
			(stroke
				(width 0.15)
				(type solid)
			)
			(layer "B.SilkS")
		)
		(fp_line
			(start -1 1.5)
			(end -1 1.375)
			(stroke
				(width 0.15)
				(type solid)
			)
			(layer "B.SilkS")
		)
		(fp_circle
			(center -1.44 1.5)
			(end -1.39 1.5)
			(stroke
				(width 0.15)
				(type solid)
			)
			(fill yes)
			(layer "B.SilkS")
		)
		(fp_rect
			(start 1.93 1.7)
			(end -1.93 -1.7)
			(stroke
				(width 0.05)
				(type solid)
			)
			(fill no)
			(layer "B.CrtYd")
		)
		(fp_line
			(start -0.45 1.521)
			(end -0.876 1.096)
			(stroke
				(width 0.15)
				(type solid)
			)
			(layer "B.Fab")
		)
		(fp_rect
			(start 0.875 -1.528)
			(end -0.875 1.525)
			(stroke
				(width 0.15)
				(type solid)
			)
			(fill no)
			(layer "B.Fab")
		)
		(fp_text user "License: Apache-2.0"
			(at -1.93 -6.199 270)
			(layer "B.Fab")
			(effects
				(font
					(size 0.7 0.7)
					(thickness 0.15)
				)
				(justify left bottom mirror)
			)
		)
		(fp_text user "Author: Antmicro"
			(at -1.93 -5 270)
			(layer "B.Fab")
			(effects
				(font
					(size 0.7 0.7)
					(thickness 0.15)
				)
				(justify left bottom mirror)
			)
		)
		(fp_text user "${REFERENCE}"
			(at -1.93 -3.8 270)
			(layer "B.Fab")
			(effects
				(font
					(size 0.7 0.7)
					(thickness 0.15)
				)
				(justify left bottom mirror)
			)
		)
		(pad "1" smd rect
			(at -1.301 0.947 180)
			(size 0.7 1.2)
			(layers "B.Cu" "B.Mask" "B.Paste")
			(net 3 "GND")
			(pinfunction "GND")
			(pintype "power_in")
		)
		(pad "2" smd rect
			(at -1.301 -0.004 180)
			(size 0.7 1.2)
			(layers "B.Cu" "B.Mask" "B.Paste")
			(net 49 "/Supply/SW_3V3")
			(pinfunction "SW")
			(pintype "power_out")
		)
		(pad "3" smd rect
			(at -1.301 -0.954 180)
			(size 0.7 1.2)
			(layers "B.Cu" "B.Mask" "B.Paste")
			(net 43 "VCC")
			(pinfunction "VIN")
			(pintype "power_in")
		)
		(pad "4" smd rect
			(at 1.299 -0.954 180)
			(size 0.7 1.2)
			(layers "B.Cu" "B.Mask" "B.Paste")
			(net 355 "/Supply/FB_3V3")
			(pinfunction "FB")
			(pintype "input")
		)
		(pad "5" smd rect
			(at 1.299 -0.004 180)
			(size 0.7 1.2)
			(layers "B.Cu" "B.Mask" "B.Paste")
			(net 350 "/Supply/EN_3V3")
			(pinfunction "EN")
			(pintype "input")
		)
		(pad "6" smd rect
			(at 1.299 0.947 180)
			(size 0.7 1.2)
			(layers "B.Cu" "B.Mask" "B.Paste")
			(net 51 "Net-(U302-BST)")
			(pinfunction "BST")
			(pintype "output")
		)
	)
	(footprint "antmicro-footprints:Vishay_PowerPAK_1212-8_Single"
		(layer "B.Cu")
		(at 44.617962 156.1665 90)
		(descr "PowerPAK 1212-8 Single")
		(tags "Vishay PowerPAK 1212-8 Single")
		(property "Reference" "Q307"
			(at -2.91 0.02 180)
			(layer "B.SilkS")
			(effects
				(font
					(size 0.7 0.7)
					(thickness 0.15)
				)
				(justify right bottom mirror)
			)
		)
		(property "Value" "SQS401EN-T1_BE3"
			(at 0 -2.7 90)
			(layer "B.Fab")
			(effects
				(font
					(size 0.7 0.7)
					(thickness 0.15)
				)
				(justify right bottom mirror)
			)
		)
		(property "Datasheet" "https://www.vishay.com/docs/65529/sqs401en.pdf"
			(at 0 0 90)
			(layer "B.Fab")
			(hide yes)
			(effects
				(font
					(size 1.27 1.27)
					(thickness 0.15)
				)
			)
		)
		(property "MPN" "SQS401EN-T1_BE3"
			(at 0 0 90)
			(unlocked yes)
			(layer "B.Fab")
			(hide yes)
			(effects
				(font
					(size 1 1)
					(thickness 0.15)
				)
				(justify mirror)
			)
		)
		(property "Manufacturer" "Vishay"
			(at 0 0 90)
			(unlocked yes)
			(layer "B.Fab")
			(hide yes)
			(effects
				(font
					(size 1 1)
					(thickness 0.15)
				)
				(justify mirror)
			)
		)
		(property "Author" "Antmicro"
			(at 0 0 90)
			(unlocked yes)
			(layer "B.Fab")
			(hide yes)
			(effects
				(font
					(size 1 1)
					(thickness 0.15)
				)
				(justify mirror)
			)
		)
		(property "License" "Apache-2.0"
			(at 0 0 90)
			(unlocked yes)
			(layer "B.Fab")
			(hide yes)
			(effects
				(font
					(size 1 1)
					(thickness 0.15)
				)
				(justify mirror)
			)
		)
		(sheetname "/Supply/")
		(sheetfile "supply.kicad_sch")
		(attr smd)
		(fp_line
			(start -1.635 -1.634)
			(end 1.634 -1.634)
			(stroke
				(width 0.15)
				(type solid)
			)
			(layer "B.SilkS")
		)
		(fp_line
			(start 1.634 -1.3)
			(end 1.634 -1.634)
			(stroke
				(width 0.15)
				(type solid)
			)
			(layer "B.SilkS")
		)
		(fp_line
			(start -1.635 -1.3)
			(end -1.635 -1.634)
			(stroke
				(width 0.15)
				(type solid)
			)
			(layer "B.SilkS")
		)
		(fp_line
			(start 1.648 1.651)
			(end 1.648 1.317)
			(stroke
				(width 0.15)
				(type solid)
			)
			(layer "B.SilkS")
		)
		(fp_line
			(start -1.651 1.651)
			(end -1.651 1.317)
			(stroke
				(width 0.15)
				(type solid)
			)
			(layer "B.SilkS")
		)
		(fp_line
			(start -1.651 1.651)
			(end 1.648 1.651)
			(stroke
				(width 0.15)
				(type solid)
			)
			(layer "B.SilkS")
		)
		(fp_circle
			(center -1.9 1.4)
			(end -1.85 1.4)
			(stroke
				(width 0.15)
				(type solid)
			)
			(fill yes)
			(layer "B.SilkS")
		)
		(fp_rect
			(start -2 1.8)
			(end 2 -1.798)
			(stroke
				(width 0.05)
				(type solid)
			)
			(fill no)
			(layer "B.CrtYd")
		)
		(fp_line
			(start -1.6425 1.4175)
			(end -1.4175 1.6425)
			(stroke
				(width 0.15)
				(type solid)
			)
			(layer "B.Fab")
		)
		(fp_rect
			(start -1.651 1.651)
			(end 1.648 -1.648)
			(stroke
				(width 0.15)
				(type solid)
			)
			(fill no)
			(layer "B.Fab")
		)
		(fp_text user "${REFERENCE}"
			(at -8 -4.7 270)
			(layer "B.Fab")
			(effects
				(font
					(size 0.7 0.7)
					(thickness 0.15)
				)
				(justify left bottom mirror)
			)
		)
		(fp_text user "License: Apache-2.0"
			(at -8 -7.1 270)
			(layer "B.Fab")
			(effects
				(font
					(size 0.7 0.7)
					(thickness 0.15)
				)
				(justify left bottom mirror)
			)
		)
		(fp_text user "Author: Antmicro"
			(at -8 -5.9 270)
			(layer "B.Fab")
			(effects
				(font
					(size 0.7 0.7)
					(thickness 0.15)
				)
				(justify left bottom mirror)
			)
		)
		(pad "1" smd rect
			(at -1.436 0.99 90)
			(size 0.99 0.405)
			(layers "B.Cu" "B.Mask" "B.Paste")
			(net 21 "/Supply/VCC_IN")
			(pinfunction "S")
			(pintype "passive")
		)
		(pad "2" smd rect
			(at -1.436 0.332 90)
			(size 0.99 0.405)
			(layers "B.Cu" "B.Mask" "B.Paste")
			(net 21 "/Supply/VCC_IN")
			(pinfunction "S")
			(pintype "passive")
		)
		(pad "3" smd rect
			(at -1.436 -0.33 90)
			(size 0.99 0.405)
			(layers "B.Cu" "B.Mask" "B.Paste")
			(net 21 "/Supply/VCC_IN")
			(pinfunction "S")
			(pintype "passive")
		)
		(pad "4" smd rect
			(at -1.436 -0.988 90)
			(size 0.99 0.405)
			(layers "B.Cu" "B.Mask" "B.Paste")
			(net 17 "Net-(Q307-G)")
			(pinfunction "G")
			(pintype "input")
		)
		(pad "5" smd custom
			(at 0.557 0 90)
			(size 1.725 2.235)
			(layers "B.Cu" "B.Mask" "B.Paste")
			(net 43 "VCC")
			(pinfunction "D")
			(pintype "passive")
			(zone_connect 2)
			(options
				(clearance outline)
				(anchor rect)
			)
			(primitives
				(gr_poly
					(pts
						(xy 0.8625 -0.1275) (xy 0.8625 0.1275) (xy 1.3725 0.1275) (xy 1.3725 0.5325) (xy 0.8625 0.5325)
						(xy 0.8625 0.7875) (xy 1.3725 0.7875) (xy 1.3725 1.195) (xy 0.6125 1.195) (xy 0.6125 -1.195) (xy 1.3725 -1.195)
						(xy 1.3725 -0.7875) (xy 0.8625 -0.7875) (xy 0.8625 -0.5325) (xy 1.3725 -0.5325) (xy 1.3725 -0.1275)
					)
					(width 0)
					(fill yes)
				)
			)
		)
	)
	(footprint "antmicro-footprints:R_0402_1005Metric"
		(layer "B.Cu")
		(at 63.492962 162.2365)
		(descr "Resistor SMD 0402")
		(tags "resistor SMD 0402")
		(property "Reference" "R312"
			(at 12.495 1.7 0)
			(layer "B.SilkS")
			(effects
				(font
					(size 0.7 0.7)
					(thickness 0.15)
				)
				(justify right bottom mirror)
			)
		)
		(property "Value" "R_10k_0402"
			(at -1.011843 -1.772047 0)
			(layer "B.Fab")
			(effects
				(font
					(size 0.7 0.7)
					(thickness 0.15)
				)
				(justify right bottom mirror)
			)
		)
		(property "Datasheet" "https://www.bourns.com/docs/product-datasheets/cr.pdf"
			(at 0 0 0)
			(layer "B.Fab")
			(hide yes)
			(effects
				(font
					(size 1.27 1.27)
					(thickness 0.15)
				)
			)
		)
		(property "Manufacturer" "Bourns"
			(at 0 0 0)
			(unlocked yes)
			(layer "B.Fab")
			(hide yes)
			(effects
				(font
					(size 1 1)
					(thickness 0.15)
				)
				(justify mirror)
			)
		)
		(property "MPN" "CR0402-FX-1002GLF"
			(at 0 0 0)
			(unlocked yes)
			(layer "B.Fab")
			(hide yes)
			(effects
				(font
					(size 1 1)
					(thickness 0.15)
				)
				(justify mirror)
			)
		)
		(property "Val" "10k"
			(at 0 0 0)
			(unlocked yes)
			(layer "B.Fab")
			(hide yes)
			(effects
				(font
					(size 1 1)
					(thickness 0.15)
				)
				(justify mirror)
			)
		)
		(property "License" "Apache-2.0"
			(at 0 0 0)
			(unlocked yes)
			(layer "B.Fab")
			(hide yes)
			(effects
				(font
					(size 1 1)
					(thickness 0.15)
				)
				(justify mirror)
			)
		)
		(property "Author" "Antmicro"
			(at 0 0 0)
			(unlocked yes)
			(layer "B.Fab")
			(hide yes)
			(effects
				(font
					(size 1 1)
					(thickness 0.15)
				)
				(justify mirror)
			)
		)
		(property "Tolerance" "1%"
			(at 0 0 0)
			(unlocked yes)
			(layer "B.Fab")
			(hide yes)
			(effects
				(font
					(size 1 1)
					(thickness 0.15)
				)
				(justify mirror)
			)
		)
		(sheetname "/Supply/")
		(sheetfile "supply.kicad_sch")
		(attr smd)
		(fp_rect
			(start -0.925 0.47)
			(end 0.925 -0.47)
			(stroke
				(width 0.05)
				(type default)
			)
			(fill no)
			(layer "B.CrtYd")
		)
		(fp_rect
			(start -0.5 0.25)
			(end 0.5 -0.25)
			(stroke
				(width 0.15)
				(type solid)
			)
			(fill no)
			(layer "B.Fab")
		)
		(fp_text user "License: Apache-2.0"
			(at -0.95 -5.169 180)
			(layer "B.Fab")
			(effects
				(font
					(size 0.7 0.7)
					(thickness 0.15)
				)
				(justify left bottom mirror)
			)
		)
		(fp_text user "Author: Antmicro"
			(at -0.95 -4.169 180)
			(layer "B.Fab")
			(effects
				(font
					(size 0.7 0.7)
					(thickness 0.15)
				)
				(justify left bottom mirror)
			)
		)
		(fp_text user "${REFERENCE}"
			(at -0.95 -3.168 180)
			(layer "B.Fab")
			(effects
				(font
					(size 0.7 0.7)
					(thickness 0.15)
				)
				(justify left bottom mirror)
			)
		)
		(pad "1" smd roundrect
			(at -0.48 0)
			(size 0.59 0.64)
			(layers "B.Cu" "B.Mask" "B.Paste")
			(roundrect_rratio 0.25)
			(net 3 "GND")
			(pintype "passive")
		)
		(pad "2" smd roundrect
			(at 0.48 0)
			(size 0.59 0.64)
			(layers "B.Cu" "B.Mask" "B.Paste")
			(roundrect_rratio 0.25)
			(net 350 "/Supply/EN_3V3")
			(pintype "passive")
		)
	)
	(footprint "antmicro-footprints:R_0402_1005Metric"
		(layer "B.Cu")
		(at 78.492962 153.6415 90)
		(descr "Resistor SMD 0402")
		(tags "resistor SMD 0402")
		(property "Reference" "R260"
			(at -3.725 0.425 90)
			(layer "B.SilkS")
			(effects
				(font
					(size 0.7 0.7)
					(thickness 0.15)
				)
				(justify right bottom mirror)
			)
		)
		(property "Value" "R_100k_0402"
			(at -1.011843 -1.772047 90)
			(layer "B.Fab")
			(effects
				(font
					(size 0.7 0.7)
					(thickness 0.15)
				)
				(justify right bottom mirror)
			)
		)
		(property "Datasheet" "https://www.bourns.com/docs/product-datasheets/cr.pdf"
			(at 0 0 90)
			(layer "B.Fab")
			(hide yes)
			(effects
				(font
					(size 1.27 1.27)
					(thickness 0.15)
				)
			)
		)
		(property "MPN" "CR0402-FX-1003GLF"
			(at 0 0 90)
			(unlocked yes)
			(layer "B.Fab")
			(hide yes)
			(effects
				(font
					(size 1 1)
					(thickness 0.15)
				)
				(justify mirror)
			)
		)
		(property "Manufacturer" "Bourns"
			(at 0 0 90)
			(unlocked yes)
			(layer "B.Fab")
			(hide yes)
			(effects
				(font
					(size 1 1)
					(thickness 0.15)
				)
				(justify mirror)
			)
		)
		(property "License" "Apache-2.0"
			(at 0 0 90)
			(unlocked yes)
			(layer "B.Fab")
			(hide yes)
			(effects
				(font
					(size 1 1)
					(thickness 0.15)
				)
				(justify mirror)
			)
		)
		(property "Author" "Antmicro"
			(at 0 0 90)
			(unlocked yes)
			(layer "B.Fab")
			(hide yes)
			(effects
				(font
					(size 1 1)
					(thickness 0.15)
				)
				(justify mirror)
			)
		)
		(property "Val" "100k"
			(at 0 0 90)
			(unlocked yes)
			(layer "B.Fab")
			(hide yes)
			(effects
				(font
					(size 1 1)
					(thickness 0.15)
				)
				(justify mirror)
			)
		)
		(property "Tolerance" "1%"
			(at 0 0 90)
			(unlocked yes)
			(layer "B.Fab")
			(hide yes)
			(effects
				(font
					(size 1 1)
					(thickness 0.15)
				)
				(justify mirror)
			)
		)
		(sheetname "/Compute module/")
		(sheetfile "compute-module.kicad_sch")
		(attr smd)
		(fp_rect
			(start -0.925 0.47)
			(end 0.925 -0.47)
			(stroke
				(width 0.05)
				(type default)
			)
			(fill no)
			(layer "B.CrtYd")
		)
		(fp_rect
			(start -0.5 0.25)
			(end 0.5 -0.25)
			(stroke
				(width 0.15)
				(type solid)
			)
			(fill no)
			(layer "B.Fab")
		)
		(fp_text user "Author: Antmicro"
			(at -0.95 -4.169 270)
			(layer "B.Fab")
			(effects
				(font
					(size 0.7 0.7)
					(thickness 0.15)
				)
				(justify left bottom mirror)
			)
		)
		(fp_text user "${REFERENCE}"
			(at -0.95 -3.168 270)
			(layer "B.Fab")
			(effects
				(font
					(size 0.7 0.7)
					(thickness 0.15)
				)
				(justify left bottom mirror)
			)
		)
		(fp_text user "License: Apache-2.0"
			(at -0.95 -5.169 270)
			(layer "B.Fab")
			(effects
				(font
					(size 0.7 0.7)
					(thickness 0.15)
				)
				(justify left bottom mirror)
			)
		)
		(pad "1" smd roundrect
			(at -0.48 0 90)
			(size 0.59 0.64)
			(layers "B.Cu" "B.Mask" "B.Paste")
			(roundrect_rratio 0.25)
			(net 3 "GND")
			(pintype "passive")
		)
		(pad "2" smd roundrect
			(at 0.48 0 90)
			(size 0.59 0.64)
			(layers "B.Cu" "B.Mask" "B.Paste")
			(roundrect_rratio 0.25)
			(net 231 "/Compute module/PolarfireID")
			(pintype "passive")
		)
	)
	(footprint "antmicro-footprints:SOT-523"
		(layer "B.Cu")
		(at 75.642962 128.2665 180)
		(property "Reference" "Q904"
			(at 1.155 -0.22 0)
			(layer "B.SilkS")
			(effects
				(font
					(size 0.7 0.7)
					(thickness 0.15)
				)
				(justify left bottom mirror)
			)
		)
		(property "Value" "PJE138K"
			(at 0.1 -1.824 0)
			(layer "B.Fab")
			(effects
				(font
					(size 0.7 0.7)
					(thickness 0.15)
				)
				(justify left bottom mirror)
			)
		)
		(property "Datasheet" "https://www.mouser.com/datasheet/2/1057/PJE138K-1876698.pdf"
			(at 0 0 180)
			(layer "B.Fab")
			(hide yes)
			(effects
				(font
					(size 1.27 1.27)
					(thickness 0.15)
				)
			)
		)
		(property "MPN" "PJE138K_R1_00001"
			(at 0 0 180)
			(unlocked yes)
			(layer "B.Fab")
			(hide yes)
			(effects
				(font
					(size 1 1)
					(thickness 0.15)
				)
				(justify mirror)
			)
		)
		(property "Manufacturer" "PANJIT"
			(at 0 0 180)
			(unlocked yes)
			(layer "B.Fab")
			(hide yes)
			(effects
				(font
					(size 1 1)
					(thickness 0.15)
				)
				(justify mirror)
			)
		)
		(property "Author" "Antmicro"
			(at 0 0 180)
			(unlocked yes)
			(layer "B.Fab")
			(hide yes)
			(effects
				(font
					(size 1 1)
					(thickness 0.15)
				)
				(justify mirror)
			)
		)
		(property "License" "Apache-2.0"
			(at 0 0 180)
			(unlocked yes)
			(layer "B.Fab")
			(hide yes)
			(effects
				(font
					(size 1 1)
					(thickness 0.15)
				)
				(justify mirror)
			)
		)
		(sheetname "/USB/")
		(sheetfile "usb.kicad_sch")
		(attr smd)
		(fp_line
			(start -0.277 0.551)
			(end -0.277 0.75)
			(stroke
				(width 0.15)
				(type solid)
			)
			(layer "B.SilkS")
		)
		(fp_line
			(start -0.725 0.551)
			(end -0.277 0.551)
			(stroke
				(width 0.15)
				(type solid)
			)
			(layer "B.SilkS")
		)
		(fp_line
			(start -0.927 0.351)
			(end -0.725 0.551)
			(stroke
				(width 0.15)
				(type solid)
			)
			(layer "B.SilkS")
		)
		(fp_line
			(start -0.927 0.051)
			(end -0.927 0.351)
			(stroke
				(width 0.15)
				(type solid)
			)
			(layer "B.SilkS")
		)
		(fp_circle
			(center -0.9652 -0.9652)
			(end -0.9152 -0.9652)
			(stroke
				(width 0.15)
				(type solid)
			)
			(fill yes)
			(layer "B.SilkS")
		)
		(fp_line
			(start 1.1 1.16)
			(end 1.1 -1.15)
			(stroke
				(width 0.05)
				(type solid)
			)
			(layer "B.CrtYd")
		)
		(fp_line
			(start -1.12 1.16)
			(end 1.1 1.16)
			(stroke
				(width 0.05)
				(type solid)
			)
			(layer "B.CrtYd")
		)
		(fp_line
			(start -1.12 1.16)
			(end -1.12 -1.15)
			(stroke
				(width 0.05)
				(type solid)
			)
			(layer "B.CrtYd")
		)
		(fp_line
			(start -1.12 -1.15)
			(end 1.1 -1.15)
			(stroke
				(width 0.05)
				(type solid)
			)
			(layer "B.CrtYd")
		)
		(fp_line
			(start 0.8 0.425)
			(end 0.8 -0.424)
			(stroke
				(width 0.15)
				(type solid)
			)
			(layer "B.Fab")
		)
		(fp_line
			(start 0.8 0.425)
			(end -0.652 0.425)
			(stroke
				(width 0.15)
				(type solid)
			)
			(layer "B.Fab")
		)
		(fp_line
			(start 0.8 -0.424)
			(end -0.802 -0.424)
			(stroke
				(width 0.15)
				(type solid)
			)
			(layer "B.Fab")
		)
		(fp_line
			(start -0.652 0.425)
			(end -0.802 0.276)
			(stroke
				(width 0.15)
				(type solid)
			)
			(layer "B.Fab")
		)
		(fp_line
			(start -0.802 0.276)
			(end -0.802 -0.424)
			(stroke
				(width 0.15)
				(type solid)
			)
			(layer "B.Fab")
		)
		(fp_circle
			(center -0.9652 -0.9652)
			(end -0.9144 -0.9652)
			(stroke
				(width 0.15)
				(type solid)
			)
			(fill no)
			(layer "B.Fab")
		)
		(fp_text user "Author: Antmicro"
			(at -1.12 -6.224 0)
			(layer "B.Fab")
			(effects
				(font
					(size 0.7 0.7)
					(thickness 0.15)
				)
				(justify left bottom mirror)
			)
		)
		(fp_text user "License: Apache-2.0"
			(at -1.12 -5.024 0)
			(layer "B.Fab")
			(effects
				(font
					(size 0.7 0.7)
					(thickness 0.15)
				)
				(justify left bottom mirror)
			)
		)
		(fp_text user "${REFERENCE}"
			(at -1.12 -3.824 0)
			(layer "B.Fab")
			(effects
				(font
					(size 0.7 0.7)
					(thickness 0.15)
				)
				(justify left bottom mirror)
			)
		)
		(pad "1" smd rect
			(at -0.5 -0.65 180)
			(size 0.4 0.51)
			(layers "B.Cu" "B.Mask" "B.Paste")
			(net 338 "/USB/USBD_IN_EN")
			(pinfunction "G")
			(pintype "input")
		)
		(pad "2" smd rect
			(at 0.498 -0.65 180)
			(size 0.4 0.51)
			(layers "B.Cu" "B.Mask" "B.Paste")
			(net 3 "GND")
			(pinfunction "S")
			(pintype "passive")
		)
		(pad "3" smd rect
			(at 0 0.652 180)
			(size 0.4 0.51)
			(layers "B.Cu" "B.Mask" "B.Paste")
			(net 341 "Net-(Q902-G)")
			(pinfunction "D")
			(pintype "passive")
		)
	)
	(footprint "antmicro-footprints:C_0402_1005Metric"
		(layer "B.Cu")
		(at 134.617962 148.4415 90)
		(descr "Capacitor SMD 0402")
		(tags "capacitor SMD 0402")
		(property "Reference" "C604"
			(at -3.745 0.18 90)
			(layer "B.SilkS")
			(effects
				(font
					(size 0.7 0.7)
					(thickness 0.15)
				)
				(justify right bottom mirror)
			)
		)
		(property "Value" "C_1u_0402"
			(at -1.022927 -2.155213 90)
			(layer "B.Fab")
			(effects
				(font
					(size 0.7 0.7)
					(thickness 0.15)
				)
				(justify right bottom mirror)
			)
		)
		(property "Datasheet" "https://product.tdk.com/en/search/capacitor/ceramic/mlcc/info?part_no=C1005X6S1A105K050BC"
			(at 0 0 90)
			(layer "B.Fab")
			(hide yes)
			(effects
				(font
					(size 1.27 1.27)
					(thickness 0.15)
				)
			)
		)
		(property "Manufacturer" "TDK"
			(at 0 0 90)
			(unlocked yes)
			(layer "B.Fab")
			(hide yes)
			(effects
				(font
					(size 1 1)
					(thickness 0.15)
				)
				(justify mirror)
			)
		)
		(property "MPN" "C1005X6S1A105K050BC"
			(at 0 0 90)
			(unlocked yes)
			(layer "B.Fab")
			(hide yes)
			(effects
				(font
					(size 1 1)
					(thickness 0.15)
				)
				(justify mirror)
			)
		)
		(property "Val" "1u"
			(at 0 0 90)
			(unlocked yes)
			(layer "B.Fab")
			(hide yes)
			(effects
				(font
					(size 1 1)
					(thickness 0.15)
				)
				(justify mirror)
			)
		)
		(property "License" "Apache-2.0"
			(at 0 0 90)
			(unlocked yes)
			(layer "B.Fab")
			(hide yes)
			(effects
				(font
					(size 1 1)
					(thickness 0.15)
				)
				(justify mirror)
			)
		)
		(property "Author" "Antmicro"
			(at 0 0 90)
			(unlocked yes)
			(layer "B.Fab")
			(hide yes)
			(effects
				(font
					(size 1 1)
					(thickness 0.15)
				)
				(justify mirror)
			)
		)
		(property "Voltage" ""
			(at 0 0 90)
			(unlocked yes)
			(layer "B.Fab")
			(hide yes)
			(effects
				(font
					(size 1 1)
					(thickness 0.15)
				)
				(justify mirror)
			)
		)
		(property "Dielectric" ""
			(at 0 0 90)
			(unlocked yes)
			(layer "B.Fab")
			(hide yes)
			(effects
				(font
					(size 1 1)
					(thickness 0.15)
				)
				(justify mirror)
			)
		)
		(sheetname "/CSI/")
		(sheetfile "csi.kicad_sch")
		(attr smd)
		(fp_rect
			(start -0.925 0.47)
			(end 0.925 -0.47)
			(stroke
				(width 0.05)
				(type default)
			)
			(fill no)
			(layer "B.CrtYd")
		)
		(fp_line
			(start 0.504 -0.248)
			(end -0.494 -0.248)
			(stroke
				(width 0.15)
				(type solid)
			)
			(layer "B.Fab")
		)
		(fp_line
			(start -0.494 -0.248)
			(end -0.494 0.25)
			(stroke
				(width 0.15)
				(type solid)
			)
			(layer "B.Fab")
		)
		(fp_line
			(start 0.504 0.25)
			(end 0.504 -0.248)
			(stroke
				(width 0.15)
				(type solid)
			)
			(layer "B.Fab")
		)
		(fp_line
			(start -0.494 0.25)
			(end 0.504 0.25)
			(stroke
				(width 0.15)
				(type solid)
			)
			(layer "B.Fab")
		)
		(fp_text user "License: Apache-2.0"
			(at -0.939 -5.799 270)
			(layer "B.Fab")
			(effects
				(font
					(size 0.7 0.7)
					(thickness 0.15)
				)
				(justify left bottom mirror)
			)
		)
		(fp_text user "Author: Antmicro"
			(at -0.939 -3.399 270)
			(layer "B.Fab")
			(effects
				(font
					(size 0.7 0.7)
					(thickness 0.15)
				)
				(justify left bottom mirror)
			)
		)
		(fp_text user "${REFERENCE}"
			(at -0.939 -4.599 270)
			(layer "B.Fab")
			(effects
				(font
					(size 0.7 0.7)
					(thickness 0.15)
				)
				(justify left bottom mirror)
			)
		)
		(pad "1" smd roundrect
			(at -0.48 0 90)
			(size 0.59 0.64)
			(layers "B.Cu" "B.Mask" "B.Paste")
			(roundrect_rratio 0.25)
			(net 3 "GND")
			(pintype "passive")
		)
		(pad "2" smd roundrect
			(at 0.48 0 90)
			(size 0.59 0.64)
			(layers "B.Cu" "B.Mask" "B.Paste")
			(roundrect_rratio 0.25)
			(net 20 "/CSI/CSI_5V")
			(pintype "passive")
		)
	)
	(footprint "antmicro-footprints:L_Bourns-SRP3212A"
		(layer "B.Cu")
		(at 90.667962 125.8165 -90)
		(property "Reference" "L901"
			(at -0.9 -2.46 90)
			(layer "B.SilkS")
			(effects
				(font
					(size 0.7 0.7)
					(thickness 0.15)
				)
				(justify left bottom mirror)
			)
		)
		(property "Value" "L_1u_5.5A_Bourns-SRP3212A"
			(at 0.05 -2.8 90)
			(layer "B.Fab")
			(effects
				(font
					(size 0.7 0.7)
					(thickness 0.15)
				)
				(justify left bottom mirror)
			)
		)
		(property "Datasheet" "https://www.mouser.com/datasheet/2/54/SRP3212A-3011944.pdf"
			(at 0 0 270)
			(layer "B.Fab")
			(hide yes)
			(effects
				(font
					(size 1.27 1.27)
					(thickness 0.15)
				)
			)
		)
		(property "Manufacturer" "Bourns"
			(at 0 0 270)
			(unlocked yes)
			(layer "B.Fab")
			(hide yes)
			(effects
				(font
					(size 1 1)
					(thickness 0.15)
				)
				(justify mirror)
			)
		)
		(property "MPN" "SRP3212A-1R0M"
			(at 0 0 270)
			(unlocked yes)
			(layer "B.Fab")
			(hide yes)
			(effects
				(font
					(size 1 1)
					(thickness 0.15)
				)
				(justify mirror)
			)
		)
		(property "Size" "3.2x2.5"
			(at 0 0 270)
			(unlocked yes)
			(layer "B.Fab")
			(hide yes)
			(effects
				(font
					(size 1 1)
					(thickness 0.15)
				)
				(justify mirror)
			)
		)
		(property "Val" "1u/5.5A"
			(at 0 0 270)
			(unlocked yes)
			(layer "B.Fab")
			(hide yes)
			(effects
				(font
					(size 1 1)
					(thickness 0.15)
				)
				(justify mirror)
			)
		)
		(property "Author" "Antmicro"
			(at 0 0 270)
			(unlocked yes)
			(layer "B.Fab")
			(hide yes)
			(effects
				(font
					(size 1 1)
					(thickness 0.15)
				)
				(justify mirror)
			)
		)
		(property "License" "Apache-2.0"
			(at 0 0 270)
			(unlocked yes)
			(layer "B.Fab")
			(hide yes)
			(effects
				(font
					(size 1 1)
					(thickness 0.15)
				)
				(justify mirror)
			)
		)
		(property "ISat" "6.5 A"
			(at 0 0 270)
			(unlocked yes)
			(layer "B.Fab")
			(hide yes)
			(effects
				(font
					(size 1 1)
					(thickness 0.15)
				)
				(justify mirror)
			)
		)
		(property "IMax" "5.5 A"
			(at 0 0 270)
			(unlocked yes)
			(layer "B.Fab")
			(hide yes)
			(effects
				(font
					(size 1 1)
					(thickness 0.15)
				)
				(justify mirror)
			)
		)
		(sheetname "/USB/")
		(sheetfile "usb.kicad_sch")
		(attr smd)
		(fp_line
			(start -0.4 1.25)
			(end 0.399 1.25)
			(stroke
				(width 0.15)
				(type solid)
			)
			(layer "B.SilkS")
		)
		(fp_line
			(start -0.4 -1.249)
			(end 0.399 -1.249)
			(stroke
				(width 0.15)
				(type solid)
			)
			(layer "B.SilkS")
		)
		(fp_rect
			(start -2.1 1.65)
			(end 2.1 -1.65)
			(stroke
				(width 0.05)
				(type solid)
			)
			(fill no)
			(layer "B.CrtYd")
		)
		(fp_rect
			(start -1.609 1.26)
			(end 1.609 -1.26)
			(stroke
				(width 0.15)
				(type solid)
			)
			(fill no)
			(layer "B.Fab")
		)
		(fp_text user "Author: Antmicro"
			(at -2.1 -6 90)
			(layer "B.Fab")
			(effects
				(font
					(size 0.7 0.7)
					(thickness 0.15)
				)
				(justify left bottom mirror)
			)
		)
		(fp_text user "License: Apache-2.0"
			(at -2.1 -7.2 90)
			(layer "B.Fab")
			(effects
				(font
					(size 0.7 0.7)
					(thickness 0.15)
				)
				(justify left bottom mirror)
			)
		)
		(fp_text user "${REFERENCE}"
			(at -2.1 -4.8 90)
			(layer "B.Fab")
			(effects
				(font
					(size 0.7 0.7)
					(thickness 0.15)
				)
				(justify left bottom mirror)
			)
		)
		(pad "1" smd roundrect
			(at -1.175 0 270)
			(size 1.35 2.8)
			(layers "B.Cu" "B.Mask" "B.Paste")
			(roundrect_rratio 0.1)
			(net 111 "/USB/SW_FTDI")
			(pintype "passive")
		)
		(pad "2" smd roundrect
			(at 1.175 0 270)
			(size 1.35 2.8)
			(layers "B.Cu" "B.Mask" "B.Paste")
			(roundrect_rratio 0.1)
			(net 113 "/USB/OUT_FTDI")
			(pintype "passive")
		)
	)
	(footprint "antmicro-footprints:XDFN-2_1x0.60mm"
		(layer "B.Cu")
		(at 98.492962 174.5415 90)
		(property "Reference" "D711"
			(at 1.595 6.465 90)
			(layer "B.SilkS")
			(effects
				(font
					(size 0.7 0.7)
					(thickness 0.15)
				)
				(justify left bottom mirror)
			)
		)
		(property "Value" "TPD1E0B04_XDFN-2"
			(at 0 -1.5 90)
			(layer "B.Fab")
			(effects
				(font
					(size 0.7 0.7)
					(thickness 0.15)
				)
				(justify right bottom mirror)
			)
		)
		(property "Datasheet" "https://www.ti.com/general/docs/suppproductinfo.tsp?distId=26&gotoUrl=https://www.ti.com/lit/gpn/tpd1e0b04"
			(at 0 0 90)
			(layer "B.Fab")
			(hide yes)
			(effects
				(font
					(size 1.27 1.27)
					(thickness 0.15)
				)
			)
		)
		(property "MPN" "TPD1E0B04DPYR"
			(at 273.034462 76.048538 0)
			(layer "B.Fab")
			(hide yes)
			(effects
				(font
					(size 1 1)
					(thickness 0.15)
				)
				(justify mirror)
			)
		)
		(property "Manufacturer" "Texas Instruments"
			(at 273.034462 76.048538 0)
			(layer "B.Fab")
			(hide yes)
			(effects
				(font
					(size 1 1)
					(thickness 0.15)
				)
				(justify mirror)
			)
		)
		(property "Author" "Antmicro"
			(at 0 0 90)
			(unlocked yes)
			(layer "B.Fab")
			(hide yes)
			(effects
				(font
					(size 1 1)
					(thickness 0.15)
				)
				(justify mirror)
			)
		)
		(property "License" "Apache-2.0"
			(at 0 0 90)
			(unlocked yes)
			(layer "B.Fab")
			(hide yes)
			(effects
				(font
					(size 1 1)
					(thickness 0.15)
				)
				(justify mirror)
			)
		)
		(sheetname "/Display/")
		(sheetfile "display.kicad_sch")
		(attr smd)
		(fp_rect
			(start -0.725 0.475)
			(end 0.725 -0.475)
			(stroke
				(width 0.05)
				(type solid)
			)
			(fill no)
			(layer "B.CrtYd")
		)
		(fp_rect
			(start -0.55 0.35)
			(end 0.55 -0.35)
			(stroke
				(width 0.15)
				(type solid)
			)
			(fill no)
			(layer "B.Fab")
		)
		(fp_text user "${REFERENCE}"
			(at -0.8 -3.2 270)
			(layer "B.Fab")
			(effects
				(font
					(size 0.7 0.7)
					(thickness 0.15)
				)
				(justify left bottom mirror)
			)
		)
		(fp_text user "License: Apache-2.0"
			(at -0.8 -5.6 270)
			(layer "B.Fab")
			(effects
				(font
					(size 0.7 0.7)
					(thickness 0.15)
				)
				(justify left bottom mirror)
			)
		)
		(fp_text user "Author: Antmicro"
			(at -0.8 -4.4 270)
			(layer "B.Fab")
			(effects
				(font
					(size 0.7 0.7)
					(thickness 0.15)
				)
				(justify left bottom mirror)
			)
		)
		(pad "1" smd roundrect
			(at -0.351 0 90)
			(size 0.3 0.5)
			(layers "B.Cu" "B.Mask" "B.Paste")
			(roundrect_rratio 0.25)
			(net 3 "GND")
			(pinfunction "C")
			(pintype "passive")
		)
		(pad "2" smd roundrect
			(at 0.349 0 90)
			(size 0.3 0.5)
			(layers "B.Cu" "B.Mask" "B.Paste")
			(roundrect_rratio 0.25)
			(net 9 "+3V3")
			(pinfunction "A")
			(pintype "passive")
		)
	)
	(footprint "antmicro-footprints:Mech_M2_2280_H2.5mm"
		(locked yes)
		(layer "B.Cu")
		(at 44.992962 124.767 -90)
		(property "Reference" "M501"
			(at 0.7495 -4.585 90)
			(layer "B.SilkS")
			(effects
				(font
					(size 0.7 0.7)
					(thickness 0.15)
				)
				(justify right bottom mirror)
			)
		)
		(property "Value" "Mech_M2_2280_H2.5mm"
			(at 0 -6.857 90)
			(layer "B.Fab")
			(effects
				(font
					(size 0.7 0.7)
					(thickness 0.15)
				)
				(justify right bottom mirror)
			)
		)
		(property "Description" "Mechanical model for M2 2280 2.5mm module"
			(at 0 0 90)
			(layer "B.Fab")
			(hide yes)
			(effects
				(font
					(size 1.27 1.27)
					(thickness 0.15)
				)
			)
		)
		(property "Manufacturer" ""
			(at 0 0 270)
			(unlocked yes)
			(layer "B.Fab")
			(hide yes)
			(effects
				(font
					(size 1 1)
					(thickness 0.15)
				)
				(justify mirror)
			)
		)
		(property "MPN" ""
			(at 0 0 270)
			(unlocked yes)
			(layer "B.Fab")
			(hide yes)
			(effects
				(font
					(size 1 1)
					(thickness 0.15)
				)
				(justify mirror)
			)
		)
		(property "Author" "Antmicro"
			(at 0 0 270)
			(unlocked yes)
			(layer "B.Fab")
			(hide yes)
			(effects
				(font
					(size 1 1)
					(thickness 0.15)
				)
				(justify mirror)
			)
		)
		(property "License" "Apache-2.0"
			(at 0 0 270)
			(unlocked yes)
			(layer "B.Fab")
			(hide yes)
			(effects
				(font
					(size 1 1)
					(thickness 0.15)
				)
				(justify mirror)
			)
		)
		(sheetname "/NVMe & microSD/")
		(sheetfile "nvme-micro-sd.kicad_sch")
		(attr exclude_from_pos_files exclude_from_bom allow_missing_courtyard dnp)
		(fp_rect
			(start -10.922 -0.0508)
			(end 11.0236 -80.0608)
			(stroke
				(width 0.15)
				(type solid)
			)
			(fill no)
			(layer "B.Fab")
		)
		(fp_text user "${REFERENCE}"
			(at -12.2428 -81.9912 90)
			(layer "B.Fab")
			(effects
				(font
					(size 0.7 0.7)
					(thickness 0.15)
				)
				(justify left bottom mirror)
			)
		)
		(fp_text user "Author: Antmicro"
			(at -12.2428 -83.1912 90)
			(layer "B.Fab")
			(effects
				(font
					(size 0.7 0.7)
					(thickness 0.15)
				)
				(justify left bottom mirror)
			)
		)
		(fp_text user "License: Apache-2.0"
			(at -12.2428 -84.3922 90)
			(layer "B.Fab")
			(effects
				(font
					(size 0.7 0.7)
					(thickness 0.15)
				)
				(justify left bottom mirror)
			)
		)
	)
	(footprint "antmicro-footprints:Conn_Socket_Molex_SlimStack_2x20_543630489"
		(layer "B.Cu")
		(at 94.067962 171.9395 90)
		(property "Reference" "J701"
			(at 6.923 4.37 270)
			(layer "B.SilkS")
			(effects
				(font
					(size 0.7 0.7)
					(thickness 0.15)
				)
				(justify left bottom mirror)
			)
		)
		(property "Value" "Socket_Molex_SlimStack_2x20_543630489"
			(at 0 -4.65 270)
			(layer "B.Fab")
			(effects
				(font
					(size 0.7 0.7)
					(thickness 0.15)
				)
				(justify left bottom mirror)
			)
		)
		(property "Datasheet" "https://www.molex.com/pdm_docs/sd/543630489_sd.pdf"
			(at 0 0 90)
			(layer "B.Fab")
			(hide yes)
			(effects
				(font
					(size 1.27 1.27)
					(thickness 0.15)
				)
			)
		)
		(property "MPN" "543630489"
			(at 0 0 90)
			(unlocked yes)
			(layer "B.Fab")
			(hide yes)
			(effects
				(font
					(size 1 1)
					(thickness 0.15)
				)
				(justify mirror)
			)
		)
		(property "Manufacturer" "Molex"
			(at 0 0 90)
			(unlocked yes)
			(layer "B.Fab")
			(hide yes)
			(effects
				(font
					(size 1 1)
					(thickness 0.15)
				)
				(justify mirror)
			)
		)
		(property "Pitch" "0.5 mm"
			(at 0 0 90)
			(unlocked yes)
			(layer "B.Fab")
			(hide yes)
			(effects
				(font
					(size 1 1)
					(thickness 0.15)
				)
				(justify mirror)
			)
		)
		(property "Author" "Antmicro"
			(at 0 0 90)
			(unlocked yes)
			(layer "B.Fab")
			(hide yes)
			(effects
				(font
					(size 1 1)
					(thickness 0.15)
				)
				(justify mirror)
			)
		)
		(property "License" "Apache-2.0"
			(at 0 0 90)
			(unlocked yes)
			(layer "B.Fab")
			(hide yes)
			(effects
				(font
					(size 1 1)
					(thickness 0.15)
				)
				(justify mirror)
			)
		)
		(sheetname "/Display/")
		(sheetfile "display.kicad_sch")
		(attr smd)
		(fp_line
			(start 7 2.5)
			(end 7 -2.5)
			(stroke
				(width 0.15)
				(type solid)
			)
			(layer "B.SilkS")
		)
		(fp_line
			(start -7 2.5)
			(end -7 -2.5)
			(stroke
				(width 0.15)
				(type solid)
			)
			(layer "B.SilkS")
		)
		(fp_circle
			(center -5.1 -3.1)
			(end -5.05 -3.1)
			(stroke
				(width 0.15)
				(type solid)
			)
			(fill yes)
			(layer "B.SilkS")
		)
		(fp_rect
			(start -7.3 3.6)
			(end 7.3 -3.6)
			(stroke
				(width 0.05)
				(type solid)
			)
			(fill no)
			(layer "B.CrtYd")
		)
		(fp_text user "License: Apache-2.0"
			(at -7.7 -6.3 270)
			(layer "B.Fab")
			(effects
				(font
					(size 0.7 0.7)
					(thickness 0.15)
				)
				(justify left bottom mirror)
			)
		)
		(fp_text user "Author: Antmicro"
			(at -7.7 -8.7 270)
			(layer "B.Fab")
			(effects
				(font
					(size 0.7 0.7)
					(thickness 0.15)
				)
				(justify left bottom mirror)
			)
		)
		(fp_text user "${REFERENCE}"
			(at -7.7 -7.5 270)
			(layer "B.Fab")
			(effects
				(font
					(size 0.7 0.7)
					(thickness 0.15)
				)
				(justify left bottom mirror)
			)
		)
		(pad "1" smd rect
			(at -4.748 -2.755 270)
			(size 0.3 1.1)
			(layers "B.Cu" "B.Mask" "B.Paste")
			(net 3 "GND")
			(pintype "passive")
		)
		(pad "2" smd rect
			(at -4.748 2.742 270)
			(size 0.3 1.1)
			(layers "B.Cu" "B.Mask" "B.Paste")
			(net 3 "GND")
			(pintype "passive")
		)
		(pad "3" smd rect
			(at -4.248 -2.755 270)
			(size 0.3 1.1)
			(layers "B.Cu" "B.Mask" "B.Paste")
			(net 96 "/Compute module/DSI.D3_N")
			(pintype "passive")
		)
		(pad "4" smd rect
			(at -4.248 2.742 270)
			(size 0.3 1.1)
			(layers "B.Cu" "B.Mask" "B.Paste")
			(net 464 "Net-(D709-C)")
			(pintype "passive")
		)
		(pad "5" smd rect
			(at -3.748 -2.755 270)
			(size 0.3 1.1)
			(layers "B.Cu" "B.Mask" "B.Paste")
			(net 98 "/Compute module/DSI.D3_P")
			(pintype "passive")
		)
		(pad "6" smd rect
			(at -3.748 2.742 270)
			(size 0.3 1.1)
			(layers "B.Cu" "B.Mask" "B.Paste")
			(net 464 "Net-(D709-C)")
			(pintype "passive")
		)
		(pad "7" smd rect
			(at -3.248 -2.755 270)
			(size 0.3 1.1)
			(layers "B.Cu" "B.Mask" "B.Paste")
			(net 3 "GND")
			(pintype "passive")
		)
		(pad "8" smd rect
			(at -3.248 2.742 270)
			(size 0.3 1.1)
			(layers "B.Cu" "B.Mask" "B.Paste")
			(net 464 "Net-(D709-C)")
			(pintype "passive")
		)
		(pad "9" smd rect
			(at -2.748 -2.755 270)
			(size 0.3 1.1)
			(layers "B.Cu" "B.Mask" "B.Paste")
			(net 87 "/Compute module/DSI.D2_N")
			(pintype "passive")
		)
		(pad "10" smd rect
			(at -2.748 2.742 270)
			(size 0.3 1.1)
			(layers "B.Cu" "B.Mask" "B.Paste")
			(net 464 "Net-(D709-C)")
			(pintype "passive")
		)
		(pad "11" smd rect
			(at -2.248 -2.755 270)
			(size 0.3 1.1)
			(layers "B.Cu" "B.Mask" "B.Paste")
			(net 97 "/Compute module/DSI.D2_P")
			(pintype "passive")
		)
		(pad "12" smd rect
			(at -2.248 2.742 270)
			(size 0.3 1.1)
			(layers "B.Cu" "B.Mask" "B.Paste")
			(net 9 "+3V3")
			(pintype "passive")
		)
		(pad "13" smd rect
			(at -1.748 -2.755 270)
			(size 0.3 1.1)
			(layers "B.Cu" "B.Mask" "B.Paste")
			(net 3 "GND")
			(pintype "passive")
		)
		(pad "14" smd rect
			(at -1.748 2.742 270)
			(size 0.3 1.1)
			(layers "B.Cu" "B.Mask" "B.Paste")
			(net 3 "GND")
			(pintype "passive")
		)
		(pad "15" smd rect
			(at -1.248 -2.755 270)
			(size 0.3 1.1)
			(layers "B.Cu" "B.Mask" "B.Paste")
			(net 74 "/Compute module/DSI.D1_N")
			(pintype "passive")
		)
		(pad "16" smd rect
			(at -1.248 2.742 270)
			(size 0.3 1.1)
			(layers "B.Cu" "B.Mask" "B.Paste")
			(net 301 "Net-(R705-R1.1)")
			(pintype "passive")
		)
		(pad "17" smd rect
			(at -0.748 -2.755 270)
			(size 0.3 1.1)
			(layers "B.Cu" "B.Mask" "B.Paste")
			(net 75 "/Compute module/DSI.D1_P")
			(pintype "passive")
		)
		(pad "18" smd rect
			(at -0.748 2.742 270)
			(size 0.3 1.1)
			(layers "B.Cu" "B.Mask" "B.Paste")
			(net 302 "Net-(R705-R2.1)")
			(pintype "passive")
		)
		(pad "19" smd rect
			(at -0.248 -2.755 270)
			(size 0.3 1.1)
			(layers "B.Cu" "B.Mask" "B.Paste")
			(net 3 "GND")
			(pintype "passive")
		)
		(pad "20" smd rect
			(at -0.248 2.742 270)
			(size 0.3 1.1)
			(layers "B.Cu" "B.Mask" "B.Paste")
			(net 303 "Net-(R705-R3.1)")
			(pintype "passive")
		)
		(pad "21" smd rect
			(at 0.252 -2.755 270)
			(size 0.3 1.1)
			(layers "B.Cu" "B.Mask" "B.Paste")
			(net 72 "/Compute module/DSI.D0_N")
			(pintype "passive")
		)
		(pad "22" smd rect
			(at 0.252 2.742 270)
			(size 0.3 1.1)
			(layers "B.Cu" "B.Mask" "B.Paste")
			(net 304 "Net-(R705-R4.1)")
			(pintype "passive")
		)
		(pad "23" smd rect
			(at 0.752 -2.755 270)
			(size 0.3 1.1)
			(layers "B.Cu" "B.Mask" "B.Paste")
			(net 73 "/Compute module/DSI.D0_P")
			(pintype "passive")
		)
		(pad "24" smd rect
			(at 0.752 2.742 270)
			(size 0.3 1.1)
			(layers "B.Cu" "B.Mask" "B.Paste")
			(net 305 "Net-(R706-R1.1)")
			(pintype "passive")
		)
		(pad "25" smd rect
			(at 1.252 -2.755 270)
			(size 0.3 1.1)
			(layers "B.Cu" "B.Mask" "B.Paste")
			(net 3 "GND")
			(pintype "passive")
		)
		(pad "26" smd rect
			(at 1.252 2.742 270)
			(size 0.3 1.1)
			(layers "B.Cu" "B.Mask" "B.Paste")
			(net 306 "Net-(R706-R2.1)")
			(pintype "passive")
		)
		(pad "27" smd rect
			(at 1.752 -2.755 270)
			(size 0.3 1.1)
			(layers "B.Cu" "B.Mask" "B.Paste")
			(net 76 "/Compute module/DSI.CLK_N")
			(pintype "passive")
		)
		(pad "28" smd rect
			(at 1.752 2.742 270)
			(size 0.3 1.1)
			(layers "B.Cu" "B.Mask" "B.Paste")
			(net 307 "Net-(R706-R3.1)")
			(pintype "passive")
		)
		(pad "29" smd rect
			(at 2.251 -2.755 270)
			(size 0.3 1.1)
			(layers "B.Cu" "B.Mask" "B.Paste")
			(net 86 "/Compute module/DSI.CLK_P")
			(pintype "passive")
		)
		(pad "30" smd rect
			(at 2.251 2.742 270)
			(size 0.3 1.1)
			(layers "B.Cu" "B.Mask" "B.Paste")
			(net 308 "Net-(R706-R4.1)")
			(pintype "passive")
		)
		(pad "31" smd rect
			(at 2.751 -2.755 270)
			(size 0.3 1.1)
			(layers "B.Cu" "B.Mask" "B.Paste")
			(net 3 "GND")
			(pintype "passive")
		)
		(pad "32" smd rect
			(at 2.751 2.742 270)
			(size 0.3 1.1)
			(layers "B.Cu" "B.Mask" "B.Paste")
			(net 3 "GND")
			(pintype "passive")
		)
		(pad "33" smd rect
			(at 3.251 -2.755 270)
			(size 0.3 1.1)
			(layers "B.Cu" "B.Mask" "B.Paste")
			(net 309 "unconnected-(J701-Pad33)")
			(pintype "passive+no_connect")
		)
		(pad "34" smd rect
			(at 3.251 2.742 270)
			(size 0.3 1.1)
			(layers "B.Cu" "B.Mask" "B.Paste")
			(net 310 "unconnected-(J701-Pad34)")
			(pintype "passive+no_connect")
		)
		(pad "35" smd rect
			(at 3.751 -2.755 270)
			(size 0.3 1.1)
			(layers "B.Cu" "B.Mask" "B.Paste")
			(net 311 "unconnected-(J701-Pad35)")
			(pintype "passive+no_connect")
		)
		(pad "36" smd rect
			(at 3.751 2.742 270)
			(size 0.3 1.1)
			(layers "B.Cu" "B.Mask" "B.Paste")
			(net 312 "unconnected-(J701-Pad36)")
			(pintype "passive+no_connect")
		)
		(pad "37" smd rect
			(at 4.252 -2.755 270)
			(size 0.3 1.1)
			(layers "B.Cu" "B.Mask" "B.Paste")
			(net 313 "unconnected-(J701-Pad37)")
			(pintype "passive+no_connect")
		)
		(pad "38" smd rect
			(at 4.252 2.742 270)
			(size 0.3 1.1)
			(layers "B.Cu" "B.Mask" "B.Paste")
			(net 314 "unconnected-(J701-Pad38)")
			(pintype "passive+no_connect")
		)
		(pad "39" smd rect
			(at 4.752 -2.755 270)
			(size 0.3 1.1)
			(layers "B.Cu" "B.Mask" "B.Paste")
			(net 315 "unconnected-(J701-Pad39)")
			(pintype "passive+no_connect")
		)
		(pad "40" smd rect
			(at 4.752 2.742 270)
			(size 0.3 1.1)
			(layers "B.Cu" "B.Mask" "B.Paste")
			(net 316 "unconnected-(J701-Pad40)")
			(pintype "passive+no_connect")
		)
		(pad "MP" smd rect
			(at -5.949 -2.568 270)
			(size 1.3 1.32)
			(layers "B.Cu" "B.Mask" "B.Paste")
			(net 3 "GND")
			(pintype "passive")
		)
		(pad "MP" smd rect
			(at -5.949 2.552 270)
			(size 1.3 1.32)
			(layers "B.Cu" "B.Mask" "B.Paste")
			(net 3 "GND")
			(pintype "passive")
		)
		(pad "MP" smd rect
			(at 5.953 2.552 270)
			(size 1.3 1.32)
			(layers "B.Cu" "B.Mask" "B.Paste")
			(net 3 "GND")
			(pintype "passive")
		)
		(pad "MP" smd rect
			(at 5.958 -2.568 270)
			(size 1.3 1.32)
			(layers "B.Cu" "B.Mask" "B.Paste")
			(net 3 "GND")
			(pintype "passive")
		)
	)
	(footprint "antmicro-footprints:Nexperia_DFN-10_2.5x1mm_P0.5mm"
		(layer "B.Cu")
		(at 89.505962 172.1785 90)
		(property "Reference" "D702"
			(at -1.198 -1.908 90)
			(layer "B.SilkS")
			(effects
				(font
					(size 0.7 0.7)
					(thickness 0.15)
				)
				(justify right bottom mirror)
			)
		)
		(property "Value" "PUSB3F96X_PASS"
			(at -0.016 -1.705 90)
			(layer "B.Fab")
			(effects
				(font
					(size 0.7 0.7)
					(thickness 0.15)
				)
				(justify right bottom mirror)
			)
		)
		(property "Datasheet" "https://mouser.com/datasheet/2/916/PUSB3F96-1600324.pdf"
			(at 0 0 90)
			(layer "B.Fab")
			(hide yes)
			(effects
				(font
					(size 1.27 1.27)
					(thickness 0.15)
				)
			)
		)
		(property "Manufacturer" "Nexperia"
			(at 0 0 90)
			(unlocked yes)
			(layer "B.Fab")
			(hide yes)
			(effects
				(font
					(size 1 1)
					(thickness 0.15)
				)
				(justify mirror)
			)
		)
		(property "MPN" "PUSB3F96X"
			(at 0 0 90)
			(unlocked yes)
			(layer "B.Fab")
			(hide yes)
			(effects
				(font
					(size 1 1)
					(thickness 0.15)
				)
				(justify mirror)
			)
		)
		(property "Author" "Antmicro"
			(at 0 0 90)
			(unlocked yes)
			(layer "B.Fab")
			(hide yes)
			(effects
				(font
					(size 1 1)
					(thickness 0.15)
				)
				(justify mirror)
			)
		)
		(property "License" "Apache-2.0"
			(at 0 0 90)
			(unlocked yes)
			(layer "B.Fab")
			(hide yes)
			(effects
				(font
					(size 1 1)
					(thickness 0.15)
				)
				(justify mirror)
			)
		)
		(sheetname "/Display/")
		(sheetfile "display.kicad_sch")
		(attr smd)
		(fp_line
			(start 1.375 -0.4)
			(end 1.375 0.4)
			(stroke
				(width 0.15)
				(type solid)
			)
			(layer "B.SilkS")
		)
		(fp_line
			(start -1.375 0.4)
			(end -1.375 -0.4)
			(stroke
				(width 0.15)
				(type solid)
			)
			(layer "B.SilkS")
		)
		(fp_circle
			(center -1.4 -0.7)
			(end -1.349 -0.7)
			(stroke
				(width 0.15)
				(type solid)
			)
			(fill yes)
			(layer "B.SilkS")
		)
		(fp_rect
			(start -1.4 0.725)
			(end 1.4 -0.725)
			(stroke
				(width 0.05)
				(type solid)
			)
			(fill no)
			(layer "B.CrtYd")
		)
		(fp_line
			(start 1.25 -0.5)
			(end 1.25 0.5)
			(stroke
				(width 0.15)
				(type solid)
			)
			(layer "B.Fab")
		)
		(fp_line
			(start -0.9 -0.5)
			(end 1.25 -0.5)
			(stroke
				(width 0.15)
				(type solid)
			)
			(layer "B.Fab")
		)
		(fp_line
			(start -1.25 -0.15)
			(end -0.9 -0.5)
			(stroke
				(width 0.15)
				(type solid)
			)
			(layer "B.Fab")
		)
		(fp_line
			(start 1.25 0.5)
			(end -1.25 0.5)
			(stroke
				(width 0.15)
				(type solid)
			)
			(layer "B.Fab")
		)
		(fp_line
			(start -1.25 0.5)
			(end -1.25 -0.15)
			(stroke
				(width 0.15)
				(type solid)
			)
			(layer "B.Fab")
		)
		(fp_text user "Author: Antmicro"
			(at -1.367 -4.905 270)
			(layer "B.Fab")
			(effects
				(font
					(size 0.7 0.7)
					(thickness 0.15)
				)
				(justify left bottom mirror)
			)
		)
		(fp_text user "${REFERENCE}"
			(at -1.367 -3.704 270)
			(layer "B.Fab")
			(effects
				(font
					(size 0.7 0.7)
					(thickness 0.15)
				)
				(justify left bottom mirror)
			)
		)
		(fp_text user "License: Apache-2.0"
			(at -1.367 -6.105 270)
			(layer "B.Fab")
			(effects
				(font
					(size 0.7 0.7)
					(thickness 0.15)
				)
				(justify left bottom mirror)
			)
		)
		(pad "1" smd rect
			(at -1 -0.3875 90)
			(size 0.2 0.475)
			(layers "B.Cu" "B.Mask" "B.Paste")
			(net 74 "/Compute module/DSI.D1_N")
			(pinfunction "CH1")
			(pintype "passive")
			(solder_mask_margin 0.05)
		)
		(pad "2" smd rect
			(at -0.5 -0.3875 90)
			(size 0.2 0.475)
			(layers "B.Cu" "B.Mask" "B.Paste")
			(net 75 "/Compute module/DSI.D1_P")
			(pinfunction "CH2")
			(pintype "passive")
			(solder_mask_margin 0.05)
		)
		(pad "3" smd rect
			(at 0 -0.3875 90)
			(size 0.2 0.475)
			(layers "B.Cu" "B.Mask" "B.Paste")
			(net 3 "GND")
			(pinfunction "GND")
			(pintype "passive")
			(solder_mask_margin 0.05)
		)
		(pad "4" smd rect
			(at 0.5 -0.3875 90)
			(size 0.2 0.475)
			(layers "B.Cu" "B.Mask" "B.Paste")
			(net 72 "/Compute module/DSI.D0_N")
			(pinfunction "CH3")
			(pintype "passive")
			(solder_mask_margin 0.05)
		)
		(pad "5" smd rect
			(at 1 -0.3875 90)
			(size 0.2 0.475)
			(layers "B.Cu" "B.Mask" "B.Paste")
			(net 73 "/Compute module/DSI.D0_P")
			(pinfunction "CH4")
			(pintype "passive")
			(solder_mask_margin 0.05)
		)
		(pad "6" smd rect
			(at 1 0.3875 90)
			(size 0.2 0.475)
			(layers "B.Cu" "B.Mask" "B.Paste")
			(net 73 "/Compute module/DSI.D0_P")
			(pinfunction "CH4")
			(pintype "passive")
			(solder_mask_margin 0.05)
		)
		(pad "7" smd rect
			(at 0.5 0.3875 90)
			(size 0.2 0.475)
			(layers "B.Cu" "B.Mask" "B.Paste")
			(net 72 "/Compute module/DSI.D0_N")
			(pinfunction "CH3")
			(pintype "passive")
			(solder_mask_margin 0.05)
		)
		(pad "8" smd rect
			(at 0 0.3875 90)
			(size 0.2 0.475)
			(layers "B.Cu" "B.Mask" "B.Paste")
			(net 3 "GND")
			(pinfunction "GND")
			(pintype "passive")
			(solder_mask_margin 0.05)
		)
		(pad "9" smd rect
			(at -0.501 0.3875 90)
			(size 0.2 0.475)
			(layers "B.Cu" "B.Mask" "B.Paste")
			(net 75 "/Compute module/DSI.D1_P")
			(pinfunction "CH2")
			(pintype "passive")
			(solder_mask_margin 0.05)
		)
		(pad "10" smd rect
			(at -1 0.3875 90)
			(size 0.2 0.475)
			(layers "B.Cu" "B.Mask" "B.Paste")
			(net 74 "/Compute module/DSI.D1_N")
			(pinfunction "CH1")
			(pintype "passive")
			(solder_mask_margin 0.05)
		)
	)
	(footprint "antmicro-footprints:R_0402_1005Metric"
		(layer "B.Cu")
		(at 78.767962 151.2415 180)
		(descr "Resistor SMD 0402")
		(tags "resistor SMD 0402")
		(property "Reference" "R241"
			(at -4.88 0.245 0)
			(layer "B.SilkS")
			(effects
				(font
					(size 0.7 0.7)
					(thickness 0.15)
				)
				(justify left bottom mirror)
			)
		)
		(property "Value" "R_2k2_0402"
			(at -1.011843 -1.772047 0)
			(layer "B.Fab")
			(effects
				(font
					(size 0.7 0.7)
					(thickness 0.15)
				)
				(justify left bottom mirror)
			)
		)
		(property "Datasheet" "https://www.bourns.com/docs/product-datasheets/cr.pdf"
			(at 0 0 180)
			(layer "B.Fab")
			(hide yes)
			(effects
				(font
					(size 1.27 1.27)
					(thickness 0.15)
				)
			)
		)
		(property "MPN" "CR0402-FX-2201GLF"
			(at 0 0 180)
			(unlocked yes)
			(layer "B.Fab")
			(hide yes)
			(effects
				(font
					(size 1 1)
					(thickness 0.15)
				)
				(justify mirror)
			)
		)
		(property "Manufacturer" "Bourns"
			(at 0 0 180)
			(unlocked yes)
			(layer "B.Fab")
			(hide yes)
			(effects
				(font
					(size 1 1)
					(thickness 0.15)
				)
				(justify mirror)
			)
		)
		(property "License" "Apache-2.0"
			(at 0 0 180)
			(unlocked yes)
			(layer "B.Fab")
			(hide yes)
			(effects
				(font
					(size 1 1)
					(thickness 0.15)
				)
				(justify mirror)
			)
		)
		(property "Author" "Antmicro"
			(at 0 0 180)
			(unlocked yes)
			(layer "B.Fab")
			(hide yes)
			(effects
				(font
					(size 1 1)
					(thickness 0.15)
				)
				(justify mirror)
			)
		)
		(property "Val" "2k2"
			(at 0 0 180)
			(unlocked yes)
			(layer "B.Fab")
			(hide yes)
			(effects
				(font
					(size 1 1)
					(thickness 0.15)
				)
				(justify mirror)
			)
		)
		(property "Tolerance" "1%"
			(at 0 0 180)
			(unlocked yes)
			(layer "B.Fab")
			(hide yes)
			(effects
				(font
					(size 1 1)
					(thickness 0.15)
				)
				(justify mirror)
			)
		)
		(sheetname "/Compute module/")
		(sheetfile "compute-module.kicad_sch")
		(attr smd)
		(fp_rect
			(start -0.925 0.47)
			(end 0.925 -0.47)
			(stroke
				(width 0.05)
				(type default)
			)
			(fill no)
			(layer "B.CrtYd")
		)
		(fp_rect
			(start -0.5 0.25)
			(end 0.5 -0.25)
			(stroke
				(width 0.15)
				(type solid)
			)
			(fill no)
			(layer "B.Fab")
		)
		(fp_text user "License: Apache-2.0"
			(at -0.95 -5.169 0)
			(layer "B.Fab")
			(effects
				(font
					(size 0.7 0.7)
					(thickness 0.15)
				)
				(justify left bottom mirror)
			)
		)
		(fp_text user "${REFERENCE}"
			(at -0.95 -3.168 0)
			(layer "B.Fab")
			(effects
				(font
					(size 0.7 0.7)
					(thickness 0.15)
				)
				(justify left bottom mirror)
			)
		)
		(fp_text user "Author: Antmicro"
			(at -0.95 -4.169 0)
			(layer "B.Fab")
			(effects
				(font
					(size 0.7 0.7)
					(thickness 0.15)
				)
				(justify left bottom mirror)
			)
		)
		(pad "1" smd roundrect
			(at -0.48 0 180)
			(size 0.59 0.64)
			(layers "B.Cu" "B.Mask" "B.Paste")
			(roundrect_rratio 0.25)
			(net 446 "/Compute module/GPIO.1{slash}SCL0")
			(pintype "passive")
		)
		(pad "2" smd roundrect
			(at 0.48 0 180)
			(size 0.59 0.64)
			(layers "B.Cu" "B.Mask" "B.Paste")
			(roundrect_rratio 0.25)
			(net 18 "V_{IO}")
			(pintype "passive")
		)
	)
	(footprint "antmicro-footprints:R_0402_1005Metric"
		(layer "B.Cu")
		(at 82.542962 135.5415 90)
		(descr "Resistor SMD 0402")
		(tags "resistor SMD 0402")
		(property "Reference" "R923"
			(at -3.485 0.445 90)
			(layer "B.SilkS")
			(effects
				(font
					(size 0.7 0.7)
					(thickness 0.15)
				)
				(justify right bottom mirror)
			)
		)
		(property "Value" "R_2k2_0402"
			(at -1.011843 -1.772047 90)
			(layer "B.Fab")
			(effects
				(font
					(size 0.7 0.7)
					(thickness 0.15)
				)
				(justify right bottom mirror)
			)
		)
		(property "Datasheet" "https://www.bourns.com/docs/product-datasheets/cr.pdf"
			(at 0 0 90)
			(layer "B.Fab")
			(hide yes)
			(effects
				(font
					(size 1.27 1.27)
					(thickness 0.15)
				)
			)
		)
		(property "MPN" "CR0402-FX-2201GLF"
			(at 0 0 90)
			(unlocked yes)
			(layer "B.Fab")
			(hide yes)
			(effects
				(font
					(size 1 1)
					(thickness 0.15)
				)
				(justify mirror)
			)
		)
		(property "Manufacturer" "Bourns"
			(at 0 0 90)
			(unlocked yes)
			(layer "B.Fab")
			(hide yes)
			(effects
				(font
					(size 1 1)
					(thickness 0.15)
				)
				(justify mirror)
			)
		)
		(property "License" "Apache-2.0"
			(at 0 0 90)
			(unlocked yes)
			(layer "B.Fab")
			(hide yes)
			(effects
				(font
					(size 1 1)
					(thickness 0.15)
				)
				(justify mirror)
			)
		)
		(property "Author" "Antmicro"
			(at 0 0 90)
			(unlocked yes)
			(layer "B.Fab")
			(hide yes)
			(effects
				(font
					(size 1 1)
					(thickness 0.15)
				)
				(justify mirror)
			)
		)
		(property "Val" "2k2"
			(at 0 0 90)
			(unlocked yes)
			(layer "B.Fab")
			(hide yes)
			(effects
				(font
					(size 1 1)
					(thickness 0.15)
				)
				(justify mirror)
			)
		)
		(property "Tolerance" "1%"
			(at 0 0 90)
			(unlocked yes)
			(layer "B.Fab")
			(hide yes)
			(effects
				(font
					(size 1 1)
					(thickness 0.15)
				)
				(justify mirror)
			)
		)
		(sheetname "/USB/")
		(sheetfile "usb.kicad_sch")
		(attr smd)
		(fp_rect
			(start -0.925 0.47)
			(end 0.925 -0.47)
			(stroke
				(width 0.05)
				(type default)
			)
			(fill no)
			(layer "B.CrtYd")
		)
		(fp_rect
			(start -0.5 0.25)
			(end 0.5 -0.25)
			(stroke
				(width 0.15)
				(type solid)
			)
			(fill no)
			(layer "B.Fab")
		)
		(fp_text user "${REFERENCE}"
			(at -0.95 -3.168 270)
			(layer "B.Fab")
			(effects
				(font
					(size 0.7 0.7)
					(thickness 0.15)
				)
				(justify left bottom mirror)
			)
		)
		(fp_text user "License: Apache-2.0"
			(at -0.95 -5.169 270)
			(layer "B.Fab")
			(effects
				(font
					(size 0.7 0.7)
					(thickness 0.15)
				)
				(justify left bottom mirror)
			)
		)
		(fp_text user "Author: Antmicro"
			(at -0.95 -4.169 270)
			(layer "B.Fab")
			(effects
				(font
					(size 0.7 0.7)
					(thickness 0.15)
				)
				(justify left bottom mirror)
			)
		)
		(pad "1" smd roundrect
			(at -0.48 0 90)
			(size 0.59 0.64)
			(layers "B.Cu" "B.Mask" "B.Paste")
			(roundrect_rratio 0.25)
			(net 379 "Net-(U905-~{RESET})")
			(pintype "passive")
		)
		(pad "2" smd roundrect
			(at 0.48 0 90)
			(size 0.59 0.64)
			(layers "B.Cu" "B.Mask" "B.Paste")
			(roundrect_rratio 0.25)
			(net 27 "/USB/USB_3V3")
			(pintype "passive")
		)
	)
	(footprint "antmicro-footprints:R_0402_1005Metric"
		(layer "B.Cu")
		(at 86.48 118.4)
		(descr "Resistor SMD 0402")
		(tags "resistor SMD 0402")
		(property "Reference" "R934"
			(at 0 -1.1 0)
			(layer "B.SilkS")
			(effects
				(font
					(size 0.7 0.7)
					(thickness 0.15)
				)
				(justify right bottom mirror)
			)
		)
		(property "Value" "R_10k_0402"
			(at -1.011843 -1.772047 0)
			(layer "B.Fab")
			(effects
				(font
					(size 0.7 0.7)
					(thickness 0.15)
				)
				(justify right bottom mirror)
			)
		)
		(property "Datasheet" "https://www.bourns.com/docs/product-datasheets/cr.pdf"
			(at 0 0 0)
			(layer "B.Fab")
			(hide yes)
			(effects
				(font
					(size 1.27 1.27)
					(thickness 0.15)
				)
			)
		)
		(property "Manufacturer" "Bourns"
			(at 0 0 0)
			(unlocked yes)
			(layer "B.Fab")
			(hide yes)
			(effects
				(font
					(size 1 1)
					(thickness 0.15)
				)
				(justify mirror)
			)
		)
		(property "MPN" "CR0402-FX-1002GLF"
			(at 0 0 0)
			(unlocked yes)
			(layer "B.Fab")
			(hide yes)
			(effects
				(font
					(size 1 1)
					(thickness 0.15)
				)
				(justify mirror)
			)
		)
		(property "Val" "10k"
			(at 0 0 0)
			(unlocked yes)
			(layer "B.Fab")
			(hide yes)
			(effects
				(font
					(size 1 1)
					(thickness 0.15)
				)
				(justify mirror)
			)
		)
		(property "License" "Apache-2.0"
			(at 0 0 0)
			(unlocked yes)
			(layer "B.Fab")
			(hide yes)
			(effects
				(font
					(size 1 1)
					(thickness 0.15)
				)
				(justify mirror)
			)
		)
		(property "Author" "Antmicro"
			(at 0 0 0)
			(unlocked yes)
			(layer "B.Fab")
			(hide yes)
			(effects
				(font
					(size 1 1)
					(thickness 0.15)
				)
				(justify mirror)
			)
		)
		(property "Tolerance" "1%"
			(at 0 0 0)
			(unlocked yes)
			(layer "B.Fab")
			(hide yes)
			(effects
				(font
					(size 1 1)
					(thickness 0.15)
				)
				(justify mirror)
			)
		)
		(sheetname "/USB/")
		(sheetfile "usb.kicad_sch")
		(attr smd)
		(fp_rect
			(start -0.925 0.47)
			(end 0.925 -0.47)
			(stroke
				(width 0.05)
				(type default)
			)
			(fill no)
			(layer "B.CrtYd")
		)
		(fp_rect
			(start -0.5 0.25)
			(end 0.5 -0.25)
			(stroke
				(width 0.15)
				(type solid)
			)
			(fill no)
			(layer "B.Fab")
		)
		(fp_text user "License: Apache-2.0"
			(at -0.95 -5.169 180)
			(layer "B.Fab")
			(effects
				(font
					(size 0.7 0.7)
					(thickness 0.15)
				)
				(justify left bottom mirror)
			)
		)
		(fp_text user "${REFERENCE}"
			(at -0.95 -3.168 180)
			(layer "B.Fab")
			(effects
				(font
					(size 0.7 0.7)
					(thickness 0.15)
				)
				(justify left bottom mirror)
			)
		)
		(fp_text user "Author: Antmicro"
			(at -0.95 -4.169 180)
			(layer "B.Fab")
			(effects
				(font
					(size 0.7 0.7)
					(thickness 0.15)
				)
				(justify left bottom mirror)
			)
		)
		(pad "1" smd roundrect
			(at -0.48 0)
			(size 0.59 0.64)
			(layers "B.Cu" "B.Mask" "B.Paste")
			(roundrect_rratio 0.25)
			(net 499 "Net-(Q906-G)")
			(pintype "passive")
		)
		(pad "2" smd roundrect
			(at 0.48 0)
			(size 0.59 0.64)
			(layers "B.Cu" "B.Mask" "B.Paste")
			(roundrect_rratio 0.25)
			(net 3 "GND")
			(pintype "passive")
		)
	)
	(footprint "antmicro-footprints:TSOT23-6"
		(layer "B.Cu")
		(at 87.317962 125.6165 90)
		(property "Reference" "U903"
			(at -4.74 -0.85 90)
			(layer "B.SilkS")
			(effects
				(font
					(size 0.7 0.7)
					(thickness 0.15)
				)
				(justify right bottom mirror)
			)
		)
		(property "Value" "AP62301_TSOT"
			(at 0 -2.6 90)
			(layer "B.Fab")
			(effects
				(font
					(size 0.7 0.7)
					(thickness 0.15)
				)
				(justify right bottom mirror)
			)
		)
		(property "Datasheet" "https://www.diodes.com/assets/Datasheets/AP62300_AP62301_AP62300T.pdf"
			(at 0 0 90)
			(layer "B.Fab")
			(hide yes)
			(effects
				(font
					(size 1.27 1.27)
					(thickness 0.15)
				)
			)
		)
		(property "MPN" "AP62301WU-7"
			(at 0 0 90)
			(unlocked yes)
			(layer "B.Fab")
			(hide yes)
			(effects
				(font
					(size 1 1)
					(thickness 0.15)
				)
				(justify mirror)
			)
		)
		(property "Manufacturer" "Diodes Incorporated"
			(at 0 0 90)
			(unlocked yes)
			(layer "B.Fab")
			(hide yes)
			(effects
				(font
					(size 1 1)
					(thickness 0.15)
				)
				(justify mirror)
			)
		)
		(property "Author" "Antmicro"
			(at 0 0 90)
			(unlocked yes)
			(layer "B.Fab")
			(hide yes)
			(effects
				(font
					(size 1 1)
					(thickness 0.15)
				)
				(justify mirror)
			)
		)
		(property "License" "Apache-2.0"
			(at 0 0 90)
			(unlocked yes)
			(layer "B.Fab")
			(hide yes)
			(effects
				(font
					(size 1 1)
					(thickness 0.15)
				)
				(justify mirror)
			)
		)
		(sheetname "/USB/")
		(sheetfile "usb.kicad_sch")
		(attr smd)
		(fp_line
			(start 1 -1.55)
			(end -1 -1.55)
			(stroke
				(width 0.15)
				(type solid)
			)
			(layer "B.SilkS")
		)
		(fp_line
			(start 1 -1.55)
			(end 1 -1.4)
			(stroke
				(width 0.15)
				(type solid)
			)
			(layer "B.SilkS")
		)
		(fp_line
			(start -1 -1.55)
			(end -1 -1.4)
			(stroke
				(width 0.15)
				(type solid)
			)
			(layer "B.SilkS")
		)
		(fp_line
			(start 1 1.497)
			(end 1 1.375)
			(stroke
				(width 0.15)
				(type solid)
			)
			(layer "B.SilkS")
		)
		(fp_line
			(start 1 1.497)
			(end -1 1.5)
			(stroke
				(width 0.15)
				(type solid)
			)
			(layer "B.SilkS")
		)
		(fp_line
			(start -1 1.5)
			(end -1 1.375)
			(stroke
				(width 0.15)
				(type solid)
			)
			(layer "B.SilkS")
		)
		(fp_circle
			(center -1.44 1.5)
			(end -1.39 1.5)
			(stroke
				(width 0.15)
				(type solid)
			)
			(fill yes)
			(layer "B.SilkS")
		)
		(fp_rect
			(start 1.93 1.7)
			(end -1.93 -1.7)
			(stroke
				(width 0.05)
				(type solid)
			)
			(fill no)
			(layer "B.CrtYd")
		)
		(fp_line
			(start -0.45 1.521)
			(end -0.876 1.096)
			(stroke
				(width 0.15)
				(type solid)
			)
			(layer "B.Fab")
		)
		(fp_rect
			(start 0.875 -1.528)
			(end -0.875 1.525)
			(stroke
				(width 0.15)
				(type solid)
			)
			(fill no)
			(layer "B.Fab")
		)
		(fp_text user "License: Apache-2.0"
			(at -1.93 -6.199 270)
			(layer "B.Fab")
			(effects
				(font
					(size 0.7 0.7)
					(thickness 0.15)
				)
				(justify left bottom mirror)
			)
		)
		(fp_text user "${REFERENCE}"
			(at -1.93 -3.8 270)
			(layer "B.Fab")
			(effects
				(font
					(size 0.7 0.7)
					(thickness 0.15)
				)
				(justify left bottom mirror)
			)
		)
		(fp_text user "Author: Antmicro"
			(at -1.93 -5 270)
			(layer "B.Fab")
			(effects
				(font
					(size 0.7 0.7)
					(thickness 0.15)
				)
				(justify left bottom mirror)
			)
		)
		(pad "1" smd rect
			(at -1.301 0.947 180)
			(size 0.7 1.2)
			(layers "B.Cu" "B.Mask" "B.Paste")
			(net 3 "GND")
			(pinfunction "GND")
			(pintype "power_in")
		)
		(pad "2" smd rect
			(at -1.301 -0.004 180)
			(size 0.7 1.2)
			(layers "B.Cu" "B.Mask" "B.Paste")
			(net 111 "/USB/SW_FTDI")
			(pinfunction "SW")
			(pintype "power_out")
		)
		(pad "3" smd rect
			(at -1.301 -0.954 180)
			(size 0.7 1.2)
			(layers "B.Cu" "B.Mask" "B.Paste")
			(net 26 "/USB/USBD_VBUS")
			(pinfunction "VIN")
			(pintype "power_in")
		)
		(pad "4" smd rect
			(at 1.299 -0.954 180)
			(size 0.7 1.2)
			(layers "B.Cu" "B.Mask" "B.Paste")
			(net 344 "/USB/FB_FTDI")
			(pinfunction "FB")
			(pintype "input")
		)
		(pad "5" smd rect
			(at 1.299 -0.004 180)
			(size 0.7 1.2)
			(layers "B.Cu" "B.Mask" "B.Paste")
			(net 343 "/USB/EN_FTDI")
			(pinfunction "EN")
			(pintype "input")
		)
		(pad "6" smd rect
			(at 1.299 0.947 180)
			(size 0.7 1.2)
			(layers "B.Cu" "B.Mask" "B.Paste")
			(net 112 "Net-(U903-BST)")
			(pinfunction "BST")
			(pintype "output")
		)
	)
	(footprint "antmicro-footprints:C_0805_2012Metric"
		(layer "B.Cu")
		(at 89.617962 128.8665 180)
		(descr "Capacitor SMD 0805")
		(tags "capacitor SMD 0805")
		(property "Reference" "C907"
			(at -1.87 -3.67 0)
			(layer "B.SilkS")
			(effects
				(font
					(size 0.7 0.7)
					(thickness 0.15)
				)
				(justify left bottom mirror)
			)
		)
		(property "Value" "C_22u_25V_0805"
			(at -2.055717 -1.963152 0)
			(layer "B.Fab")
			(effects
				(font
					(size 0.7 0.7)
					(thickness 0.15)
				)
				(justify left bottom mirror)
			)
		)
		(property "Datasheet" "https://product.samsungsem.com/mlcc/CL21A226MAYNNN.do"
			(at 0 0 180)
			(layer "B.Fab")
			(hide yes)
			(effects
				(font
					(size 1.27 1.27)
					(thickness 0.15)
				)
			)
		)
		(property "Manufacturer" "Samsung Electro-Mechanics"
			(at 0 0 180)
			(unlocked yes)
			(layer "B.Fab")
			(hide yes)
			(effects
				(font
					(size 1 1)
					(thickness 0.15)
				)
				(justify mirror)
			)
		)
		(property "MPN" "CL21A226MAYNNNE"
			(at 0 0 180)
			(unlocked yes)
			(layer "B.Fab")
			(hide yes)
			(effects
				(font
					(size 1 1)
					(thickness 0.15)
				)
				(justify mirror)
			)
		)
		(property "Val" "22u"
			(at 0 0 180)
			(unlocked yes)
			(layer "B.Fab")
			(hide yes)
			(effects
				(font
					(size 1 1)
					(thickness 0.15)
				)
				(justify mirror)
			)
		)
		(property "License" "Apache-2.0"
			(at 0 0 180)
			(unlocked yes)
			(layer "B.Fab")
			(hide yes)
			(effects
				(font
					(size 1 1)
					(thickness 0.15)
				)
				(justify mirror)
			)
		)
		(property "Author" "Antmicro"
			(at 0 0 180)
			(unlocked yes)
			(layer "B.Fab")
			(hide yes)
			(effects
				(font
					(size 1 1)
					(thickness 0.15)
				)
				(justify mirror)
			)
		)
		(property "Voltage" "25V"
			(at 0 0 180)
			(unlocked yes)
			(layer "B.Fab")
			(hide yes)
			(effects
				(font
					(size 1 1)
					(thickness 0.15)
				)
				(justify mirror)
			)
		)
		(property "Dielectric" "X5R"
			(at 0 0 180)
			(unlocked yes)
			(layer "B.Fab")
			(hide yes)
			(effects
				(font
					(size 1 1)
					(thickness 0.15)
				)
				(justify mirror)
			)
		)
		(property "Public" "False"
			(at 0 0 180)
			(unlocked yes)
			(layer "B.Fab")
			(hide yes)
			(effects
				(font
					(size 1 1)
					(thickness 0.15)
				)
				(justify mirror)
			)
		)
		(sheetname "/USB/")
		(sheetfile "usb.kicad_sch")
		(attr smd)
		(fp_line
			(start -0.3 0.7)
			(end 0.3 0.7)
			(stroke
				(width 0.15)
				(type solid)
			)
			(layer "B.SilkS")
		)
		(fp_line
			(start -0.3 -0.7)
			(end 0.3 -0.7)
			(stroke
				(width 0.15)
				(type solid)
			)
			(layer "B.SilkS")
		)
		(fp_rect
			(start 1.95 0.9)
			(end -1.95 -0.9)
			(stroke
				(width 0.05)
				(type default)
			)
			(fill no)
			(layer "B.CrtYd")
		)
		(fp_rect
			(start -0.95 0.675)
			(end 0.95 -0.675)
			(stroke
				(width 0.15)
				(type solid)
			)
			(fill no)
			(layer "B.Fab")
		)
		(fp_text user "${REFERENCE}"
			(at -1.9 -3.947 0)
			(layer "B.Fab")
			(effects
				(font
					(size 0.7 0.7)
					(thickness 0.15)
				)
				(justify left bottom mirror)
			)
		)
		(fp_text user "Author: Antmicro"
			(at -1.9 -5.947 0)
			(layer "B.Fab")
			(effects
				(font
					(size 0.7 0.7)
					(thickness 0.15)
				)
				(justify left bottom mirror)
			)
		)
		(fp_text user "License: Apache-2.0"
			(at -1.9 -4.947 0)
			(layer "B.Fab")
			(effects
				(font
					(size 0.7 0.7)
					(thickness 0.15)
				)
				(justify left bottom mirror)
			)
		)
		(pad "1" smd roundrect
			(at -1.1 0 180)
			(size 1.2 1.3)
			(layers "B.Cu" "B.Mask" "B.Paste")
			(roundrect_rratio 0.25)
			(net 113 "/USB/OUT_FTDI")
			(pintype "passive")
		)
		(pad "2" smd roundrect
			(at 1.1 0 180)
			(size 1.2 1.3)
			(layers "B.Cu" "B.Mask" "B.Paste")
			(roundrect_rratio 0.25)
			(net 3 "GND")
			(pintype "passive")
		)
	)
	(footprint "antmicro-footprints:FB_0603_1608Metric"
		(layer "B.Cu")
		(at 59.242962 113.8915 180)
		(property "Reference" "FB402"
			(at -1.725 0.715 0)
			(layer "B.SilkS")
			(effects
				(font
					(size 0.7 0.7)
					(thickness 0.15)
				)
				(justify left bottom mirror)
			)
		)
		(property "Value" "FB_220Z_2.2A_TDK-MPZ_0603"
			(at 0 -1.5 0)
			(layer "B.Fab")
			(effects
				(font
					(size 0.7 0.7)
					(thickness 0.15)
				)
				(justify left bottom mirror)
			)
		)
		(property "Datasheet" "https://product.tdk.com/info/en/catalog/datasheets/beads_commercial_power_mpz1608_en.pdf"
			(at 0 0 180)
			(layer "B.Fab")
			(hide yes)
			(effects
				(font
					(size 1.27 1.27)
					(thickness 0.15)
				)
			)
		)
		(property "MPN" "MPZ1608S221ATA00"
			(at 0 0 180)
			(unlocked yes)
			(layer "B.Fab")
			(hide yes)
			(effects
				(font
					(size 1 1)
					(thickness 0.15)
				)
				(justify mirror)
			)
		)
		(property "Manufacturer" "TDK"
			(at 0 0 180)
			(unlocked yes)
			(layer "B.Fab")
			(hide yes)
			(effects
				(font
					(size 1 1)
					(thickness 0.15)
				)
				(justify mirror)
			)
		)
		(property "Author" "Antmicro"
			(at 0 0 180)
			(unlocked yes)
			(layer "B.Fab")
			(hide yes)
			(effects
				(font
					(size 1 1)
					(thickness 0.15)
				)
				(justify mirror)
			)
		)
		(property "License" "Apache-2.0"
			(at 0 0 180)
			(unlocked yes)
			(layer "B.Fab")
			(hide yes)
			(effects
				(font
					(size 1 1)
					(thickness 0.15)
				)
				(justify mirror)
			)
		)
		(property "Val" "220Z/2.2A"
			(at 0 0 180)
			(unlocked yes)
			(layer "B.Fab")
			(hide yes)
			(effects
				(font
					(size 1 1)
					(thickness 0.15)
				)
				(justify mirror)
			)
		)
		(property "Current" ""
			(at 0 0 180)
			(unlocked yes)
			(layer "B.Fab")
			(hide yes)
			(effects
				(font
					(size 1 1)
					(thickness 0.15)
				)
				(justify mirror)
			)
		)
		(sheetname "/Ethernet/")
		(sheetfile "ethernet.kicad_sch")
		(attr smd)
		(fp_line
			(start -0.15 0.4)
			(end 0.15 0.4)
			(stroke
				(width 0.15)
				(type solid)
			)
			(layer "B.SilkS")
		)
		(fp_line
			(start -0.15 -0.4)
			(end 0.15 -0.4)
			(stroke
				(width 0.15)
				(type solid)
			)
			(layer "B.SilkS")
		)
		(fp_rect
			(start -1.25 0.65)
			(end 1.25 -0.65)
			(stroke
				(width 0.05)
				(type solid)
			)
			(fill no)
			(layer "B.CrtYd")
		)
		(fp_line
			(start 0.8 0.408)
			(end 0.8 -0.406)
			(stroke
				(width 0.15)
				(type solid)
			)
			(layer "B.Fab")
		)
		(fp_line
			(start 0.8 0.408)
			(end -0.803 0.408)
			(stroke
				(width 0.15)
				(type solid)
			)
			(layer "B.Fab")
		)
		(fp_line
			(start 0.8 -0.406)
			(end -0.803 -0.406)
			(stroke
				(width 0.15)
				(type solid)
			)
			(layer "B.Fab")
		)
		(fp_line
			(start -0.803 -0.406)
			(end -0.803 0.408)
			(stroke
				(width 0.15)
				(type solid)
			)
			(layer "B.Fab")
		)
		(fp_text user "License: Apache-2.0"
			(at -1.653 -5.9 0)
			(layer "B.Fab")
			(effects
				(font
					(size 0.7 0.7)
					(thickness 0.15)
				)
				(justify left bottom mirror)
			)
		)
		(fp_text user "Author: Antmicro"
			(at -1.653 -3.162 0)
			(layer "B.Fab")
			(effects
				(font
					(size 0.7 0.7)
					(thickness 0.15)
				)
				(justify left bottom mirror)
			)
		)
		(fp_text user "${REFERENCE}"
			(at -1.653 -4.6 0)
			(layer "B.Fab")
			(effects
				(font
					(size 0.7 0.7)
					(thickness 0.15)
				)
				(justify left bottom mirror)
			)
		)
		(pad "1" smd roundrect
			(at -0.7 0 180)
			(size 0.8 1)
			(layers "B.Cu" "B.Mask" "B.Paste")
			(roundrect_rratio 0.2)
			(net 116 "Net-(D401-Pad1)")
			(pintype "passive")
		)
		(pad "2" smd roundrect
			(at 0.7 0 180)
			(size 0.8 1)
			(layers "B.Cu" "B.Mask" "B.Paste")
			(roundrect_rratio 0.2)
			(net 90 "/Ethernet/VSS")
			(pintype "passive")
		)
	)
	(footprint "antmicro-footprints:R_0402_1005Metric"
		(layer "B.Cu")
		(at 127.3 178.2 -90)
		(descr "Resistor SMD 0402")
		(tags "resistor SMD 0402")
		(property "Reference" "R811"
			(at -3.7 -0.4 270)
			(layer "B.SilkS")
			(effects
				(font
					(size 0.7 0.7)
					(thickness 0.15)
				)
				(justify left bottom mirror)
			)
		)
		(property "Value" "R_2k2_0402"
			(at -1.011843 -1.772047 90)
			(layer "B.Fab")
			(effects
				(font
					(size 0.7 0.7)
					(thickness 0.15)
				)
				(justify left bottom mirror)
			)
		)
		(property "Datasheet" "https://www.bourns.com/docs/product-datasheets/cr.pdf"
			(at 0 0 90)
			(layer "B.Fab")
			(hide yes)
			(effects
				(font
					(size 1.27 1.27)
					(thickness 0.15)
				)
				(justify mirror)
			)
		)
		(property "Description" "SMD Chip Resistor, 2.2 kohm, ± 1%, 62.5 mW, 0402 [1005 Metric], Thick Film, General Purpose"
			(at 0 0 90)
			(layer "B.Fab")
			(hide yes)
			(effects
				(font
					(size 1.27 1.27)
					(thickness 0.15)
				)
				(justify mirror)
			)
		)
		(property "MPN" "CR0402-FX-2201GLF"
			(at 0 0 270)
			(unlocked yes)
			(layer "B.Fab")
			(hide yes)
			(effects
				(font
					(size 1 1)
					(thickness 0.15)
				)
				(justify mirror)
			)
		)
		(property "Manufacturer" "Bourns"
			(at 0 0 270)
			(unlocked yes)
			(layer "B.Fab")
			(hide yes)
			(effects
				(font
					(size 1 1)
					(thickness 0.15)
				)
				(justify mirror)
			)
		)
		(property "License" "Apache-2.0"
			(at 0 0 270)
			(unlocked yes)
			(layer "B.Fab")
			(hide yes)
			(effects
				(font
					(size 1 1)
					(thickness 0.15)
				)
				(justify mirror)
			)
		)
		(property "Author" "Antmicro"
			(at 0 0 270)
			(unlocked yes)
			(layer "B.Fab")
			(hide yes)
			(effects
				(font
					(size 1 1)
					(thickness 0.15)
				)
				(justify mirror)
			)
		)
		(property "Val" "2k2"
			(at 0 0 270)
			(unlocked yes)
			(layer "B.Fab")
			(hide yes)
			(effects
				(font
					(size 1 1)
					(thickness 0.15)
				)
				(justify mirror)
			)
		)
		(property "Tolerance" "1%"
			(at 0 0 270)
			(unlocked yes)
			(layer "B.Fab")
			(hide yes)
			(effects
				(font
					(size 1 1)
					(thickness 0.15)
				)
				(justify mirror)
			)
		)
		(sheetname "/Peripherals/")
		(sheetfile "peripherals.kicad_sch")
		(attr smd)
		(fp_rect
			(start -0.925 0.47)
			(end 0.925 -0.47)
			(stroke
				(width 0.05)
				(type default)
			)
			(fill no)
			(layer "B.CrtYd")
		)
		(fp_rect
			(start -0.5 0.25)
			(end 0.5 -0.25)
			(stroke
				(width 0.15)
				(type solid)
			)
			(fill no)
			(layer "B.Fab")
		)
		(fp_text user "${REFERENCE}"
			(at -0.95 -3.168 90)
			(layer "B.Fab")
			(effects
				(font
					(size 0.7 0.7)
					(thickness 0.15)
				)
				(justify left bottom mirror)
			)
		)
		(fp_text user "Author: Antmicro"
			(at -0.95 -4.169 90)
			(layer "B.Fab")
			(effects
				(font
					(size 0.7 0.7)
					(thickness 0.15)
				)
				(justify left bottom mirror)
			)
		)
		(fp_text user "License: Apache-2.0"
			(at -0.95 -5.169 90)
			(layer "B.Fab")
			(effects
				(font
					(size 0.7 0.7)
					(thickness 0.15)
				)
				(justify left bottom mirror)
			)
		)
		(pad "1" smd roundrect
			(at -0.48 0 270)
			(size 0.59 0.64)
			(layers "B.Cu" "B.Mask" "B.Paste")
			(roundrect_rratio 0.25)
			(net 502 "Net-(BT801-+)")
			(pintype "passive")
		)
		(pad "2" smd roundrect
			(at 0.48 0 270)
			(size 0.59 0.64)
			(layers "B.Cu" "B.Mask" "B.Paste")
			(roundrect_rratio 0.25)
			(net 503 "Net-(D811-C)")
			(pintype "passive")
		)
	)
	(footprint "antmicro-footprints:C_2220_5650Metric"
		(layer "B.Cu")
		(at 43.292962 145.6465 90)
		(descr "Capacitor SMD 2220")
		(tags "capacitor SMD 2220")
		(property "Reference" "C407"
			(at -4.63 -1.275 180)
			(layer "B.SilkS")
			(effects
				(font
					(size 0.7 0.7)
					(thickness 0.15)
				)
				(justify right bottom mirror)
			)
		)
		(property "Value" "C_22u_100V_2220"
			(at 0 -3.9 90)
			(layer "B.Fab")
			(effects
				(font
					(size 0.7 0.7)
					(thickness 0.15)
				)
				(justify right bottom mirror)
			)
		)
		(property "Datasheet" "https://product.tdk.com/en/search/capacitor/ceramic/mlcc/info?part_no=C5750X7S2A226M280KB"
			(at 0 0 90)
			(layer "B.Fab")
			(hide yes)
			(effects
				(font
					(size 1.27 1.27)
					(thickness 0.15)
				)
			)
		)
		(property "Manufacturer" "TDK"
			(at 0 0 90)
			(unlocked yes)
			(layer "B.Fab")
			(hide yes)
			(effects
				(font
					(size 1 1)
					(thickness 0.15)
				)
				(justify mirror)
			)
		)
		(property "MPN" "C5750X7S2A226M280KB"
			(at 0 0 90)
			(unlocked yes)
			(layer "B.Fab")
			(hide yes)
			(effects
				(font
					(size 1 1)
					(thickness 0.15)
				)
				(justify mirror)
			)
		)
		(property "Val" "22u"
			(at 0 0 90)
			(unlocked yes)
			(layer "B.Fab")
			(hide yes)
			(effects
				(font
					(size 1 1)
					(thickness 0.15)
				)
				(justify mirror)
			)
		)
		(property "License" "Apache-2.0"
			(at 0 0 90)
			(unlocked yes)
			(layer "B.Fab")
			(hide yes)
			(effects
				(font
					(size 1 1)
					(thickness 0.15)
				)
				(justify mirror)
			)
		)
		(property "Author" "Antmicro"
			(at 0 0 90)
			(unlocked yes)
			(layer "B.Fab")
			(hide yes)
			(effects
				(font
					(size 1 1)
					(thickness 0.15)
				)
				(justify mirror)
			)
		)
		(property "Voltage" "100V"
			(at 0 0 90)
			(unlocked yes)
			(layer "B.Fab")
			(hide yes)
			(effects
				(font
					(size 1 1)
					(thickness 0.15)
				)
				(justify mirror)
			)
		)
		(property "Dielectric" "X7S"
			(at 0 0 90)
			(unlocked yes)
			(layer "B.Fab")
			(hide yes)
			(effects
				(font
					(size 1 1)
					(thickness 0.15)
				)
				(justify mirror)
			)
		)
		(property "Public" "False"
			(at 0 0 90)
			(unlocked yes)
			(layer "B.Fab")
			(hide yes)
			(effects
				(font
					(size 1 1)
					(thickness 0.15)
				)
				(justify mirror)
			)
		)
		(sheetname "/Ethernet/")
		(sheetfile "ethernet.kicad_sch")
		(attr smd)
		(fp_line
			(start -1.415 -2.61)
			(end 1.415 -2.61)
			(stroke
				(width 0.15)
				(type solid)
			)
			(layer "B.SilkS")
		)
		(fp_line
			(start -1.415 2.61)
			(end 1.415 2.61)
			(stroke
				(width 0.15)
				(type solid)
			)
			(layer "B.SilkS")
		)
		(fp_rect
			(start -3.7 2.95)
			(end 3.7 -2.95)
			(stroke
				(width 0.05)
				(type solid)
			)
			(fill no)
			(layer "B.CrtYd")
		)
		(fp_rect
			(start -2.85 2.5)
			(end 2.85 -2.5)
			(stroke
				(width 0.15)
				(type solid)
			)
			(fill no)
			(layer "B.Fab")
		)
		(fp_text user "License: Apache-2.0"
			(at -3.7 -6.9 270)
			(layer "B.Fab")
			(effects
				(font
					(size 0.7 0.7)
					(thickness 0.15)
				)
				(justify left bottom mirror)
			)
		)
		(fp_text user "${REFERENCE}"
			(at -3.7 -5.9 270)
			(layer "B.Fab")
			(effects
				(font
					(size 0.7 0.7)
					(thickness 0.15)
				)
				(justify left bottom mirror)
			)
		)
		(fp_text user "Author: Antmicro"
			(at -3.7 -7.9 270)
			(layer "B.Fab")
			(effects
				(font
					(size 0.7 0.7)
					(thickness 0.15)
				)
				(justify left bottom mirror)
			)
		)
		(pad "1" smd roundrect
			(at -2.55 0 90)
			(size 1.8 5.4)
			(layers "B.Cu" "B.Mask" "B.Paste")
			(roundrect_rratio 0.138889)
			(net 1 "GNDD")
			(pintype "passive")
		)
		(pad "2" smd roundrect
			(at 2.55 0 90)
			(size 1.8 5.4)
			(layers "B.Cu" "B.Mask" "B.Paste")
			(roundrect_rratio 0.138889)
			(net 33 "/Ethernet/VDD")
			(pintype "passive")
		)
	)
	(footprint "antmicro-footprints:C_0805_2012Metric"
		(layer "B.Cu")
		(at 56.717962 171.3165 -90)
		(descr "Capacitor SMD 0805")
		(tags "capacitor SMD 0805")
		(property "Reference" "C410"
			(at 1.76 -0.4 90)
			(layer "B.SilkS")
			(effects
				(font
					(size 0.7 0.7)
					(thickness 0.15)
				)
				(justify left bottom mirror)
			)
		)
		(property "Value" "C_22u_25V_0805"
			(at -2.055717 -1.963152 90)
			(layer "B.Fab")
			(effects
				(font
					(size 0.7 0.7)
					(thickness 0.15)
				)
				(justify left bottom mirror)
			)
		)
		(property "Datasheet" "https://product.samsungsem.com/mlcc/CL21A226MAYNNN.do"
			(at 0 0 270)
			(layer "B.Fab")
			(hide yes)
			(effects
				(font
					(size 1.27 1.27)
					(thickness 0.15)
				)
			)
		)
		(property "Manufacturer" "Samsung Electro-Mechanics"
			(at 0 0 270)
			(unlocked yes)
			(layer "B.Fab")
			(hide yes)
			(effects
				(font
					(size 1 1)
					(thickness 0.15)
				)
				(justify mirror)
			)
		)
		(property "MPN" "CL21A226MAYNNNE"
			(at 0 0 270)
			(unlocked yes)
			(layer "B.Fab")
			(hide yes)
			(effects
				(font
					(size 1 1)
					(thickness 0.15)
				)
				(justify mirror)
			)
		)
		(property "Val" "22u"
			(at 0 0 270)
			(unlocked yes)
			(layer "B.Fab")
			(hide yes)
			(effects
				(font
					(size 1 1)
					(thickness 0.15)
				)
				(justify mirror)
			)
		)
		(property "License" "Apache-2.0"
			(at 0 0 270)
			(unlocked yes)
			(layer "B.Fab")
			(hide yes)
			(effects
				(font
					(size 1 1)
					(thickness 0.15)
				)
				(justify mirror)
			)
		)
		(property "Author" "Antmicro"
			(at 0 0 270)
			(unlocked yes)
			(layer "B.Fab")
			(hide yes)
			(effects
				(font
					(size 1 1)
					(thickness 0.15)
				)
				(justify mirror)
			)
		)
		(property "Voltage" "25V"
			(at 0 0 270)
			(unlocked yes)
			(layer "B.Fab")
			(hide yes)
			(effects
				(font
					(size 1 1)
					(thickness 0.15)
				)
				(justify mirror)
			)
		)
		(property "Dielectric" "X5R"
			(at 0 0 270)
			(unlocked yes)
			(layer "B.Fab")
			(hide yes)
			(effects
				(font
					(size 1 1)
					(thickness 0.15)
				)
				(justify mirror)
			)
		)
		(property "Public" "False"
			(at 0 0 270)
			(unlocked yes)
			(layer "B.Fab")
			(hide yes)
			(effects
				(font
					(size 1 1)
					(thickness 0.15)
				)
				(justify mirror)
			)
		)
		(sheetname "/Ethernet/")
		(sheetfile "ethernet.kicad_sch")
		(attr smd)
		(fp_line
			(start -0.3 0.7)
			(end 0.3 0.7)
			(stroke
				(width 0.15)
				(type solid)
			)
			(layer "B.SilkS")
		)
		(fp_line
			(start -0.3 -0.7)
			(end 0.3 -0.7)
			(stroke
				(width 0.15)
				(type solid)
			)
			(layer "B.SilkS")
		)
		(fp_rect
			(start 1.95 0.9)
			(end -1.95 -0.9)
			(stroke
				(width 0.05)
				(type default)
			)
			(fill no)
			(layer "B.CrtYd")
		)
		(fp_rect
			(start -0.95 0.675)
			(end 0.95 -0.675)
			(stroke
				(width 0.15)
				(type solid)
			)
			(fill no)
			(layer "B.Fab")
		)
		(fp_text user "License: Apache-2.0"
			(at -1.9 -4.947 90)
			(layer "B.Fab")
			(effects
				(font
					(size 0.7 0.7)
					(thickness 0.15)
				)
				(justify left bottom mirror)
			)
		)
		(fp_text user "${REFERENCE}"
			(at -1.9 -3.947 90)
			(layer "B.Fab")
			(effects
				(font
					(size 0.7 0.7)
					(thickness 0.15)
				)
				(justify left bottom mirror)
			)
		)
		(fp_text user "Author: Antmicro"
			(at -1.9 -5.947 90)
			(layer "B.Fab")
			(effects
				(font
					(size 0.7 0.7)
					(thickness 0.15)
				)
				(justify left bottom mirror)
			)
		)
		(pad "1" smd roundrect
			(at -1.1 0 270)
			(size 1.2 1.3)
			(layers "B.Cu" "B.Mask" "B.Paste")
			(roundrect_rratio 0.25)
			(net 47 "/Ethernet/POE_12V")
			(pintype "passive")
		)
		(pad "2" smd roundrect
			(at 1.1 0 270)
			(size 1.2 1.3)
			(layers "B.Cu" "B.Mask" "B.Paste")
			(roundrect_rratio 0.25)
			(net 3 "GND")
			(pintype "passive")
		)
	)
	(footprint "antmicro-footprints:R_0402_1005Metric"
		(layer "B.Cu")
		(at 119.092962 122.4665 -90)
		(descr "Resistor SMD 0402")
		(tags "resistor SMD 0402")
		(property "Reference" "R501"
			(at 0.72 -0.555 90)
			(layer "B.SilkS")
			(effects
				(font
					(size 0.7 0.7)
					(thickness 0.15)
				)
				(justify left bottom mirror)
			)
		)
		(property "Value" "R_10k_0402"
			(at -1.011843 -1.772047 90)
			(layer "B.Fab")
			(effects
				(font
					(size 0.7 0.7)
					(thickness 0.15)
				)
				(justify left bottom mirror)
			)
		)
		(property "Datasheet" "https://www.bourns.com/docs/product-datasheets/cr.pdf"
			(at 0 0 270)
			(layer "B.Fab")
			(hide yes)
			(effects
				(font
					(size 1.27 1.27)
					(thickness 0.15)
				)
			)
		)
		(property "Manufacturer" "Bourns"
			(at 0 0 270)
			(unlocked yes)
			(layer "B.Fab")
			(hide yes)
			(effects
				(font
					(size 1 1)
					(thickness 0.15)
				)
				(justify mirror)
			)
		)
		(property "MPN" "CR0402-FX-1002GLF"
			(at 0 0 270)
			(unlocked yes)
			(layer "B.Fab")
			(hide yes)
			(effects
				(font
					(size 1 1)
					(thickness 0.15)
				)
				(justify mirror)
			)
		)
		(property "Val" "10k"
			(at 0 0 270)
			(unlocked yes)
			(layer "B.Fab")
			(hide yes)
			(effects
				(font
					(size 1 1)
					(thickness 0.15)
				)
				(justify mirror)
			)
		)
		(property "License" "Apache-2.0"
			(at 0 0 270)
			(unlocked yes)
			(layer "B.Fab")
			(hide yes)
			(effects
				(font
					(size 1 1)
					(thickness 0.15)
				)
				(justify mirror)
			)
		)
		(property "Author" "Antmicro"
			(at 0 0 270)
			(unlocked yes)
			(layer "B.Fab")
			(hide yes)
			(effects
				(font
					(size 1 1)
					(thickness 0.15)
				)
				(justify mirror)
			)
		)
		(property "Tolerance" "1%"
			(at 0 0 270)
			(unlocked yes)
			(layer "B.Fab")
			(hide yes)
			(effects
				(font
					(size 1 1)
					(thickness 0.15)
				)
				(justify mirror)
			)
		)
		(sheetname "/NVMe & microSD/")
		(sheetfile "nvme-micro-sd.kicad_sch")
		(attr smd)
		(fp_rect
			(start -0.925 0.47)
			(end 0.925 -0.47)
			(stroke
				(width 0.05)
				(type default)
			)
			(fill no)
			(layer "B.CrtYd")
		)
		(fp_rect
			(start -0.5 0.25)
			(end 0.5 -0.25)
			(stroke
				(width 0.15)
				(type solid)
			)
			(fill no)
			(layer "B.Fab")
		)
		(fp_text user "Author: Antmicro"
			(at -0.95 -4.169 90)
			(layer "B.Fab")
			(effects
				(font
					(size 0.7 0.7)
					(thickness 0.15)
				)
				(justify left bottom mirror)
			)
		)
		(fp_text user "License: Apache-2.0"
			(at -0.95 -5.169 90)
			(layer "B.Fab")
			(effects
				(font
					(size 0.7 0.7)
					(thickness 0.15)
				)
				(justify left bottom mirror)
			)
		)
		(fp_text user "${REFERENCE}"
			(at -0.95 -3.168 90)
			(layer "B.Fab")
			(effects
				(font
					(size 0.7 0.7)
					(thickness 0.15)
				)
				(justify left bottom mirror)
			)
		)
		(pad "1" smd roundrect
			(at -0.48 0 270)
			(size 0.59 0.64)
			(layers "B.Cu" "B.Mask" "B.Paste")
			(roundrect_rratio 0.25)
			(net 145 "/Compute module/NVMe.~{RST}")
			(pintype "passive")
		)
		(pad "2" smd roundrect
			(at 0.48 0 270)
			(size 0.59 0.64)
			(layers "B.Cu" "B.Mask" "B.Paste")
			(roundrect_rratio 0.25)
			(net 65 "3V3_SSD")
			(pintype "passive")
		)
	)
	(footprint "antmicro-footprints:R_0402_1005Metric"
		(layer "B.Cu")
		(at 92.537962 153.3915)
		(descr "Resistor SMD 0402")
		(tags "resistor SMD 0402")
		(property "Reference" "R232"
			(at -0.99 3.96 0)
			(layer "B.SilkS")
			(effects
				(font
					(size 0.7 0.7)
					(thickness 0.15)
				)
				(justify right bottom mirror)
			)
		)
		(property "Value" "R_10k_0402"
			(at -1.011843 -1.772047 0)
			(layer "B.Fab")
			(effects
				(font
					(size 0.7 0.7)
					(thickness 0.15)
				)
				(justify right bottom mirror)
			)
		)
		(property "Datasheet" "https://www.bourns.com/docs/product-datasheets/cr.pdf"
			(at 0 0 0)
			(layer "B.Fab")
			(hide yes)
			(effects
				(font
					(size 1.27 1.27)
					(thickness 0.15)
				)
			)
		)
		(property "MPN" "CR0402-FX-1002GLF"
			(at 0 0 0)
			(unlocked yes)
			(layer "B.Fab")
			(hide yes)
			(effects
				(font
					(size 1 1)
					(thickness 0.15)
				)
				(justify mirror)
			)
		)
		(property "Manufacturer" "Bourns"
			(at 0 0 0)
			(unlocked yes)
			(layer "B.Fab")
			(hide yes)
			(effects
				(font
					(size 1 1)
					(thickness 0.15)
				)
				(justify mirror)
			)
		)
		(property "License" "Apache-2.0"
			(at 0 0 0)
			(unlocked yes)
			(layer "B.Fab")
			(hide yes)
			(effects
				(font
					(size 1 1)
					(thickness 0.15)
				)
				(justify mirror)
			)
		)
		(property "Author" "Antmicro"
			(at 0 0 0)
			(unlocked yes)
			(layer "B.Fab")
			(hide yes)
			(effects
				(font
					(size 1 1)
					(thickness 0.15)
				)
				(justify mirror)
			)
		)
		(property "Val" "10k"
			(at 0 0 0)
			(unlocked yes)
			(layer "B.Fab")
			(hide yes)
			(effects
				(font
					(size 1 1)
					(thickness 0.15)
				)
				(justify mirror)
			)
		)
		(property "Tolerance" "1%"
			(at 0 0 0)
			(unlocked yes)
			(layer "B.Fab")
			(hide yes)
			(effects
				(font
					(size 1 1)
					(thickness 0.15)
				)
				(justify mirror)
			)
		)
		(sheetname "/Compute module/")
		(sheetfile "compute-module.kicad_sch")
		(attr smd exclude_from_pos_files exclude_from_bom dnp)
		(fp_rect
			(start -0.925 0.47)
			(end 0.925 -0.47)
			(stroke
				(width 0.05)
				(type default)
			)
			(fill no)
			(layer "B.CrtYd")
		)
		(fp_rect
			(start -0.5 0.25)
			(end 0.5 -0.25)
			(stroke
				(width 0.15)
				(type solid)
			)
			(fill no)
			(layer "B.Fab")
		)
		(fp_text user "License: Apache-2.0"
			(at -0.95 -5.169 180)
			(layer "B.Fab")
			(effects
				(font
					(size 0.7 0.7)
					(thickness 0.15)
				)
				(justify left bottom mirror)
			)
		)
		(fp_text user "${REFERENCE}"
			(at -0.95 -3.168 180)
			(layer "B.Fab")
			(effects
				(font
					(size 0.7 0.7)
					(thickness 0.15)
				)
				(justify left bottom mirror)
			)
		)
		(fp_text user "Author: Antmicro"
			(at -0.95 -4.169 180)
			(layer "B.Fab")
			(effects
				(font
					(size 0.7 0.7)
					(thickness 0.15)
				)
				(justify left bottom mirror)
			)
		)
		(pad "1" smd roundrect
			(at -0.48 0)
			(size 0.59 0.64)
			(layers "B.Cu" "B.Mask" "B.Paste")
			(roundrect_rratio 0.25)
			(net 346 "Net-(U204-A1)")
			(pintype "passive")
		)
		(pad "2" smd roundrect
			(at 0.48 0)
			(size 0.59 0.64)
			(layers "B.Cu" "B.Mask" "B.Paste")
			(roundrect_rratio 0.25)
			(net 9 "+3V3")
			(pintype "passive")
		)
	)
	(footprint "antmicro-footprints:R_Array_4x0402_Panasonic_EXB28V"
		(layer "B.Cu")
		(at 99.017962 172.5415 90)
		(property "Reference" "R705"
			(at 3.695 1.2 90)
			(layer "B.SilkS")
			(effects
				(font
					(size 0.7 0.7)
					(thickness 0.15)
				)
				(justify right bottom mirror)
			)
		)
		(property "Value" "R_4x100R_0402_array"
			(at -1.5 -2 90)
			(layer "B.Fab")
			(effects
				(font
					(size 0.7 0.7)
					(thickness 0.15)
				)
				(justify right bottom mirror)
			)
		)
		(property "Datasheet" "http://industrial.panasonic.com/cdbs/www-data/pdf/AOC0000/AOC0000C14.pdf"
			(at 0 0 90)
			(layer "B.Fab")
			(hide yes)
			(effects
				(font
					(size 1.27 1.27)
					(thickness 0.15)
				)
			)
		)
		(property "MPN" "EXB-28V101JX"
			(at 0 0 90)
			(unlocked yes)
			(layer "B.Fab")
			(hide yes)
			(effects
				(font
					(size 1 1)
					(thickness 0.15)
				)
				(justify mirror)
			)
		)
		(property "Manufacturer" "Panasonic"
			(at 0 0 90)
			(unlocked yes)
			(layer "B.Fab")
			(hide yes)
			(effects
				(font
					(size 1 1)
					(thickness 0.15)
				)
				(justify mirror)
			)
		)
		(property "Author" "Antmicro"
			(at 0 0 90)
			(unlocked yes)
			(layer "B.Fab")
			(hide yes)
			(effects
				(font
					(size 1 1)
					(thickness 0.15)
				)
				(justify mirror)
			)
		)
		(property "License" "Apache-2.0"
			(at 0 0 90)
			(unlocked yes)
			(layer "B.Fab")
			(hide yes)
			(effects
				(font
					(size 1 1)
					(thickness 0.15)
				)
				(justify mirror)
			)
		)
		(property "Val" "R_4x100R_0402"
			(at 0 0 90)
			(unlocked yes)
			(layer "B.Fab")
			(hide yes)
			(effects
				(font
					(size 1 1)
					(thickness 0.15)
				)
				(justify mirror)
			)
		)
		(sheetname "/Display/")
		(sheetfile "display.kicad_sch")
		(attr smd)
		(fp_line
			(start 1.25 -0.499)
			(end 1.25 0.499)
			(stroke
				(width 0.15)
				(type solid)
			)
			(layer "B.SilkS")
		)
		(fp_line
			(start -1.25 0.5)
			(end -1.25 -0.498)
			(stroke
				(width 0.15)
				(type solid)
			)
			(layer "B.SilkS")
		)
		(fp_rect
			(start -1.25 0.8)
			(end 1.25 -0.8)
			(stroke
				(width 0.05)
				(type solid)
			)
			(fill no)
			(layer "B.CrtYd")
		)
		(fp_line
			(start 0.998 -0.498)
			(end -1 -0.498)
			(stroke
				(width 0.15)
				(type solid)
			)
			(layer "B.Fab")
		)
		(fp_line
			(start -1 -0.498)
			(end -1 0.5)
			(stroke
				(width 0.15)
				(type solid)
			)
			(layer "B.Fab")
		)
		(fp_line
			(start 0.998 0.5)
			(end 0.998 -0.498)
			(stroke
				(width 0.15)
				(type solid)
			)
			(layer "B.Fab")
		)
		(fp_line
			(start -1 0.5)
			(end 0.998 0.5)
			(stroke
				(width 0.15)
				(type solid)
			)
			(layer "B.Fab")
		)
		(fp_text user "Author: Antmicro"
			(at -1.5 -4.5 270)
			(layer "B.Fab")
			(effects
				(font
					(size 0.7 0.7)
					(thickness 0.15)
				)
				(justify left bottom mirror)
			)
		)
		(fp_text user "License: Apache-2.0"
			(at -1.5 -5.75 270)
			(layer "B.Fab")
			(effects
				(font
					(size 0.7 0.7)
					(thickness 0.15)
				)
				(justify left bottom mirror)
			)
		)
		(fp_text user "${REFERENCE}"
			(at -1.5 -3.25 270)
			(layer "B.Fab")
			(effects
				(font
					(size 0.7 0.7)
					(thickness 0.15)
				)
				(justify left bottom mirror)
			)
		)
		(pad "1" smd roundrect
			(at -0.8875 -0.45 90)
			(size 0.525 0.5)
			(layers "B.Cu" "B.Mask" "B.Paste")
			(roundrect_rratio 0.25)
			(net 301 "Net-(R705-R1.1)")
			(pinfunction "R1.1")
			(pintype "passive")
		)
		(pad "2" smd roundrect
			(at -0.25 -0.45 90)
			(size 0.25 0.5)
			(layers "B.Cu" "B.Mask" "B.Paste")
			(roundrect_rratio 0.25)
			(net 302 "Net-(R705-R2.1)")
			(pinfunction "R2.1")
			(pintype "passive")
		)
		(pad "3" smd roundrect
			(at 0.25 -0.45 90)
			(size 0.25 0.5)
			(layers "B.Cu" "B.Mask" "B.Paste")
			(roundrect_rratio 0.25)
			(net 303 "Net-(R705-R3.1)")
			(pinfunction "R3.1")
			(pintype "passive")
		)
		(pad "4" smd roundrect
			(at 0.8875 -0.45 90)
			(size 0.525 0.5)
			(layers "B.Cu" "B.Mask" "B.Paste")
			(roundrect_rratio 0.25)
			(net 304 "Net-(R705-R4.1)")
			(pinfunction "R4.1")
			(pintype "passive")
		)
		(pad "5" smd roundrect
			(at 0.8875 0.45 90)
			(size 0.525 0.5)
			(layers "B.Cu" "B.Mask" "B.Paste")
			(roundrect_rratio 0.25)
			(net 121 "/Compute module/DSICtrl.~{IRQ2}")
			(pinfunction "R4.2")
			(pintype "passive")
		)
		(pad "6" smd roundrect
			(at 0.25 0.45 90)
			(size 0.25 0.5)
			(layers "B.Cu" "B.Mask" "B.Paste")
			(roundrect_rratio 0.25)
			(net 120 "/Compute module/DSICtrl.IRQ1")
			(pinfunction "R3.2")
			(pintype "passive")
		)
		(pad "7" smd roundrect
			(at -0.25 0.45 90)
			(size 0.25 0.5)
			(layers "B.Cu" "B.Mask" "B.Paste")
			(roundrect_rratio 0.25)
			(net 142 "/CSI/I_{2}C1.SCL")
			(pinfunction "R2.2")
			(pintype "passive")
		)
		(pad "8" smd roundrect
			(at -0.8875 0.45 90)
			(size 0.525 0.5)
			(layers "B.Cu" "B.Mask" "B.Paste")
			(roundrect_rratio 0.25)
			(net 143 "/CSI/I_{2}C1.SDA")
			(pinfunction "R1.2")
			(pintype "passive")
		)
	)
	(footprint "antmicro-footprints:C_0402_1005Metric"
		(layer "B.Cu")
		(at 60.417962 170.7565 -90)
		(descr "Capacitor SMD 0402")
		(tags "capacitor SMD 0402")
		(property "Reference" "C411"
			(at 1.33 -0.42 90)
			(layer "B.SilkS")
			(effects
				(font
					(size 0.7 0.7)
					(thickness 0.15)
				)
				(justify left bottom mirror)
			)
		)
		(property "Value" "C_100n_0402"
			(at -1.022927 -2.155213 90)
			(layer "B.Fab")
			(effects
				(font
					(size 0.7 0.7)
					(thickness 0.15)
				)
				(justify left bottom mirror)
			)
		)
		(property "Datasheet" "https://www.murata.com/products/productdetail?partno=GRM155R61H104KE14%23"
			(at 0 0 270)
			(layer "B.Fab")
			(hide yes)
			(effects
				(font
					(size 1.27 1.27)
					(thickness 0.15)
				)
			)
		)
		(property "MPN" "GRM155R61H104KE14D"
			(at 0 0 270)
			(unlocked yes)
			(layer "B.Fab")
			(hide yes)
			(effects
				(font
					(size 1 1)
					(thickness 0.15)
				)
				(justify mirror)
			)
		)
		(property "Manufacturer" "Murata"
			(at 0 0 270)
			(unlocked yes)
			(layer "B.Fab")
			(hide yes)
			(effects
				(font
					(size 1 1)
					(thickness 0.15)
				)
				(justify mirror)
			)
		)
		(property "Val" "100n"
			(at 0 0 270)
			(unlocked yes)
			(layer "B.Fab")
			(hide yes)
			(effects
				(font
					(size 1 1)
					(thickness 0.15)
				)
				(justify mirror)
			)
		)
		(property "License" "Apache-2.0"
			(at 0 0 270)
			(unlocked yes)
			(layer "B.Fab")
			(hide yes)
			(effects
				(font
					(size 1 1)
					(thickness 0.15)
				)
				(justify mirror)
			)
		)
		(property "Author" "Antmicro"
			(at 0 0 270)
			(unlocked yes)
			(layer "B.Fab")
			(hide yes)
			(effects
				(font
					(size 1 1)
					(thickness 0.15)
				)
				(justify mirror)
			)
		)
		(property "Voltage" "50V"
			(at 0 0 270)
			(unlocked yes)
			(layer "B.Fab")
			(hide yes)
			(effects
				(font
					(size 1 1)
					(thickness 0.15)
				)
				(justify mirror)
			)
		)
		(property "Dielectric" "X5R"
			(at 0 0 270)
			(unlocked yes)
			(layer "B.Fab")
			(hide yes)
			(effects
				(font
					(size 1 1)
					(thickness 0.15)
				)
				(justify mirror)
			)
		)
		(sheetname "/Ethernet/")
		(sheetfile "ethernet.kicad_sch")
		(attr smd)
		(fp_rect
			(start -0.925 0.47)
			(end 0.925 -0.47)
			(stroke
				(width 0.05)
				(type default)
			)
			(fill no)
			(layer "B.CrtYd")
		)
		(fp_line
			(start -0.494 0.25)
			(end 0.504 0.25)
			(stroke
				(width 0.15)
				(type solid)
			)
			(layer "B.Fab")
		)
		(fp_line
			(start 0.504 0.25)
			(end 0.504 -0.248)
			(stroke
				(width 0.15)
				(type solid)
			)
			(layer "B.Fab")
		)
		(fp_line
			(start -0.494 -0.248)
			(end -0.494 0.25)
			(stroke
				(width 0.15)
				(type solid)
			)
			(layer "B.Fab")
		)
		(fp_line
			(start 0.504 -0.248)
			(end -0.494 -0.248)
			(stroke
				(width 0.15)
				(type solid)
			)
			(layer "B.Fab")
		)
		(fp_text user "License: Apache-2.0"
			(at -0.939 -5.799 90)
			(layer "B.Fab")
			(effects
				(font
					(size 0.7 0.7)
					(thickness 0.15)
				)
				(justify left bottom mirror)
			)
		)
		(fp_text user "${REFERENCE}"
			(at -0.939 -4.599 90)
			(layer "B.Fab")
			(effects
				(font
					(size 0.7 0.7)
					(thickness 0.15)
				)
				(justify left bottom mirror)
			)
		)
		(fp_text user "Author: Antmicro"
			(at -0.939 -3.399 90)
			(layer "B.Fab")
			(effects
				(font
					(size 0.7 0.7)
					(thickness 0.15)
				)
				(justify left bottom mirror)
			)
		)
		(pad "1" smd roundrect
			(at -0.48 0 270)
			(size 0.59 0.64)
			(layers "B.Cu" "B.Mask" "B.Paste")
			(roundrect_rratio 0.25)
			(net 47 "/Ethernet/POE_12V")
			(pintype "passive")
		)
		(pad "2" smd roundrect
			(at 0.48 0 270)
			(size 0.59 0.64)
			(layers "B.Cu" "B.Mask" "B.Paste")
			(roundrect_rratio 0.25)
			(net 3 "GND")
			(pintype "passive")
		)
	)
	(footprint "antmicro-footprints:C_0402_1005Metric"
		(layer "B.Cu")
		(at 66.217962 177.1915 180)
		(descr "Capacitor SMD 0402")
		(tags "capacitor SMD 0402")
		(property "Reference" "C812"
			(at -3.782038 0.1915 0)
			(layer "B.SilkS")
			(effects
				(font
					(size 0.7 0.7)
					(thickness 0.15)
				)
				(justify left top mirror)
			)
		)
		(property "Value" "C_1n_0402"
			(at -1.022927 -2.155213 0)
			(layer "B.Fab")
			(effects
				(font
					(size 0.7 0.7)
					(thickness 0.15)
				)
				(justify left top mirror)
			)
		)
		(property "Datasheet" "https://www.murata.com/products/productdetail?partno=GRM1555C1H102JA01%23"
			(at 0 0 0)
			(layer "B.Fab")
			(hide yes)
			(effects
				(font
					(size 1.27 1.27)
					(thickness 0.15)
				)
			)
		)
		(property "Description" "SMD Multilayer Ceramic Capacitor, 1000 pF, 50 V, 0402 [1005 Metric], ± 5%, C0G / NP0, GRM Series"
			(at 0 0 0)
			(layer "B.Fab")
			(hide yes)
			(effects
				(font
					(size 1.27 1.27)
					(thickness 0.15)
				)
			)
		)
		(property "MPN" "GRM1555C1H102JA01D"
			(at 0 0 180)
			(unlocked yes)
			(layer "B.Fab")
			(hide yes)
			(effects
				(font
					(size 1 1)
					(thickness 0.15)
				)
				(justify mirror)
			)
		)
		(property "Manufacturer" "Murata"
			(at 0 0 180)
			(unlocked yes)
			(layer "B.Fab")
			(hide yes)
			(effects
				(font
					(size 1 1)
					(thickness 0.15)
				)
				(justify mirror)
			)
		)
		(property "License" "Apache-2.0"
			(at 0 0 180)
			(unlocked yes)
			(layer "B.Fab")
			(hide yes)
			(effects
				(font
					(size 1 1)
					(thickness 0.15)
				)
				(justify mirror)
			)
		)
		(property "Author" "Antmicro"
			(at 0 0 180)
			(unlocked yes)
			(layer "B.Fab")
			(hide yes)
			(effects
				(font
					(size 1 1)
					(thickness 0.15)
				)
				(justify mirror)
			)
		)
		(property "Val" "1n"
			(at 0 0 180)
			(unlocked yes)
			(layer "B.Fab")
			(hide yes)
			(effects
				(font
					(size 1 1)
					(thickness 0.15)
				)
				(justify mirror)
			)
		)
		(property "Voltage" "50V"
			(at 0 0 180)
			(unlocked yes)
			(layer "B.Fab")
			(hide yes)
			(effects
				(font
					(size 1 1)
					(thickness 0.15)
				)
				(justify mirror)
			)
		)
		(property "Dielectric" "C0G"
			(at 0 0 180)
			(unlocked yes)
			(layer "B.Fab")
			(hide yes)
			(effects
				(font
					(size 1 1)
					(thickness 0.15)
				)
				(justify mirror)
			)
		)
		(sheetname "/Peripherals/")
		(sheetfile "peripherals.kicad_sch")
		(attr smd)
		(fp_rect
			(start -0.925 0.47)
			(end 0.925 -0.47)
			(stroke
				(width 0.05)
				(type default)
			)
			(fill no)
			(layer "B.CrtYd")
		)
		(fp_line
			(start 0.504 0.25)
			(end 0.504 -0.248)
			(stroke
				(width 0.15)
				(type solid)
			)
			(layer "B.Fab")
		)
		(fp_line
			(start 0.504 -0.248)
			(end -0.494 -0.248)
			(stroke
				(width 0.15)
				(type solid)
			)
			(layer "B.Fab")
		)
		(fp_line
			(start -0.494 0.25)
			(end 0.504 0.25)
			(stroke
				(width 0.15)
				(type solid)
			)
			(layer "B.Fab")
		)
		(fp_line
			(start -0.494 -0.248)
			(end -0.494 0.25)
			(stroke
				(width 0.15)
				(type solid)
			)
			(layer "B.Fab")
		)
		(fp_text user "License: Apache-2.0"
			(at -0.939 -5.799 0)
			(layer "B.Fab")
			(effects
				(font
					(size 0.7 0.7)
					(thickness 0.15)
				)
				(justify left bottom mirror)
			)
		)
		(fp_text user "${REFERENCE}"
			(at -0.939 -4.599 0)
			(layer "B.Fab")
			(effects
				(font
					(size 0.7 0.7)
					(thickness 0.15)
				)
				(justify left bottom mirror)
			)
		)
		(fp_text user "Author: Antmicro"
			(at -0.939 -3.399 0)
			(layer "B.Fab")
			(effects
				(font
					(size 0.7 0.7)
					(thickness 0.15)
				)
				(justify left bottom mirror)
			)
		)
		(pad "1" smd roundrect
			(at -0.48 0 180)
			(size 0.59 0.64)
			(layers "B.Cu" "B.Mask" "B.Paste")
			(roundrect_rratio 0.25)
			(net 103 "Net-(U801-RXP)")
			(pintype "passive")
		)
		(pad "2" smd roundrect
			(at 0.48 0 180)
			(size 0.59 0.64)
			(layers "B.Cu" "B.Mask" "B.Paste")
			(roundrect_rratio 0.25)
			(net 102 "Net-(C812-Pad2)")
			(pintype "passive")
		)
	)
	(footprint "antmicro-footprints:R_0402_1005Metric"
		(layer "B.Cu")
		(at 129.267962 156.5415 180)
		(descr "Resistor SMD 0402")
		(tags "resistor SMD 0402")
		(property "Reference" "R512"
			(at -3.68 -0.245 0)
			(layer "B.SilkS")
			(effects
				(font
					(size 0.7 0.7)
					(thickness 0.15)
				)
				(justify left bottom mirror)
			)
		)
		(property "Value" "R_470R_0402"
			(at -1.011843 -1.772047 0)
			(layer "B.Fab")
			(effects
				(font
					(size 0.7 0.7)
					(thickness 0.15)
				)
				(justify left bottom mirror)
			)
		)
		(property "Datasheet" "https://www.bourns.com/docs/product-datasheets/cr.pdf"
			(at 0 0 180)
			(layer "B.Fab")
			(hide yes)
			(effects
				(font
					(size 1.27 1.27)
					(thickness 0.15)
				)
			)
		)
		(property "Manufacturer" "Bourns"
			(at 0 0 180)
			(unlocked yes)
			(layer "B.Fab")
			(hide yes)
			(effects
				(font
					(size 1 1)
					(thickness 0.15)
				)
				(justify mirror)
			)
		)
		(property "MPN" "CR0402-FX-4700GLF"
			(at 0 0 180)
			(unlocked yes)
			(layer "B.Fab")
			(hide yes)
			(effects
				(font
					(size 1 1)
					(thickness 0.15)
				)
				(justify mirror)
			)
		)
		(property "Val" "470R"
			(at 0 0 180)
			(unlocked yes)
			(layer "B.Fab")
			(hide yes)
			(effects
				(font
					(size 1 1)
					(thickness 0.15)
				)
				(justify mirror)
			)
		)
		(property "License" "Apache-2.0"
			(at 0 0 180)
			(unlocked yes)
			(layer "B.Fab")
			(hide yes)
			(effects
				(font
					(size 1 1)
					(thickness 0.15)
				)
				(justify mirror)
			)
		)
		(property "Author" "Antmicro"
			(at 0 0 180)
			(unlocked yes)
			(layer "B.Fab")
			(hide yes)
			(effects
				(font
					(size 1 1)
					(thickness 0.15)
				)
				(justify mirror)
			)
		)
		(property "Tolerance" "1%"
			(at 0 0 180)
			(unlocked yes)
			(layer "B.Fab")
			(hide yes)
			(effects
				(font
					(size 1 1)
					(thickness 0.15)
				)
				(justify mirror)
			)
		)
		(sheetname "/NVMe & microSD/")
		(sheetfile "nvme-micro-sd.kicad_sch")
		(attr smd)
		(fp_rect
			(start -0.925 0.47)
			(end 0.925 -0.47)
			(stroke
				(width 0.05)
				(type default)
			)
			(fill no)
			(layer "B.CrtYd")
		)
		(fp_rect
			(start -0.5 0.25)
			(end 0.5 -0.25)
			(stroke
				(width 0.15)
				(type solid)
			)
			(fill no)
			(layer "B.Fab")
		)
		(fp_text user "License: Apache-2.0"
			(at -0.95 -5.169 0)
			(layer "B.Fab")
			(effects
				(font
					(size 0.7 0.7)
					(thickness 0.15)
				)
				(justify left bottom mirror)
			)
		)
		(fp_text user "Author: Antmicro"
			(at -0.95 -4.169 0)
			(layer "B.Fab")
			(effects
				(font
					(size 0.7 0.7)
					(thickness 0.15)
				)
				(justify left bottom mirror)
			)
		)
		(fp_text user "${REFERENCE}"
			(at -0.95 -3.168 0)
			(layer "B.Fab")
			(effects
				(font
					(size 0.7 0.7)
					(thickness 0.15)
				)
				(justify left bottom mirror)
			)
		)
		(pad "1" smd roundrect
			(at -0.48 0 180)
			(size 0.59 0.64)
			(layers "B.Cu" "B.Mask" "B.Paste")
			(roundrect_rratio 0.25)
			(net 268 "Net-(J502-CD1)")
			(pintype "passive")
		)
		(pad "2" smd roundrect
			(at 0.48 0 180)
			(size 0.59 0.64)
			(layers "B.Cu" "B.Mask" "B.Paste")
			(roundrect_rratio 0.25)
			(net 9 "+3V3")
			(pintype "passive")
		)
	)
	(footprint "antmicro-footprints:C_0402_1005Metric"
		(layer "B.Cu")
		(at 117.8 173)
		(descr "Capacitor SMD 0402")
		(tags "capacitor SMD 0402")
		(property "Reference" "C828"
			(at -1.341 -1.296 0)
			(layer "B.SilkS")
			(effects
				(font
					(size 0.7 0.7)
					(thickness 0.15)
				)
				(justify right top mirror)
			)
		)
		(property "Value" "C_100n_0402"
			(at -1.022927 -2.155213 0)
			(layer "B.Fab")
			(effects
				(font
					(size 0.7 0.7)
					(thickness 0.15)
				)
				(justify right top mirror)
			)
		)
		(property "Datasheet" "https://www.murata.com/products/productdetail?partno=GRM155R61H104KE14%23"
			(at 0 0 0)
			(layer "B.Fab")
			(hide yes)
			(effects
				(font
					(size 1.27 1.27)
					(thickness 0.15)
				)
				(justify mirror)
			)
		)
		(property "Description" "SMD Multilayer Ceramic Capacitor, 0.1 µF, 50 V, 0402 [1005 Metric], ± 10%, X5R, GRM Series"
			(at 0 0 0)
			(layer "B.Fab")
			(hide yes)
			(effects
				(font
					(size 1.27 1.27)
					(thickness 0.15)
				)
				(justify mirror)
			)
		)
		(property "MPN" "GRM155R61H104KE14D"
			(at 0 0 0)
			(unlocked yes)
			(layer "B.Fab")
			(hide yes)
			(effects
				(font
					(size 1 1)
					(thickness 0.15)
				)
				(justify mirror)
			)
		)
		(property "Manufacturer" "Murata"
			(at 0 0 0)
			(unlocked yes)
			(layer "B.Fab")
			(hide yes)
			(effects
				(font
					(size 1 1)
					(thickness 0.15)
				)
				(justify mirror)
			)
		)
		(property "License" "Apache-2.0"
			(at 0 0 0)
			(unlocked yes)
			(layer "B.Fab")
			(hide yes)
			(effects
				(font
					(size 1 1)
					(thickness 0.15)
				)
				(justify mirror)
			)
		)
		(property "Author" "Antmicro"
			(at 0 0 0)
			(unlocked yes)
			(layer "B.Fab")
			(hide yes)
			(effects
				(font
					(size 1 1)
					(thickness 0.15)
				)
				(justify mirror)
			)
		)
		(property "Val" "100n"
			(at 0 0 0)
			(unlocked yes)
			(layer "B.Fab")
			(hide yes)
			(effects
				(font
					(size 1 1)
					(thickness 0.15)
				)
				(justify mirror)
			)
		)
		(property "Voltage" "50V"
			(at 0 0 0)
			(unlocked yes)
			(layer "B.Fab")
			(hide yes)
			(effects
				(font
					(size 1 1)
					(thickness 0.15)
				)
				(justify mirror)
			)
		)
		(property "Dielectric" "X5R"
			(at 0 0 0)
			(unlocked yes)
			(layer "B.Fab")
			(hide yes)
			(effects
				(font
					(size 1 1)
					(thickness 0.15)
				)
				(justify mirror)
			)
		)
		(sheetname "/Peripherals/")
		(sheetfile "peripherals.kicad_sch")
		(attr smd)
		(fp_rect
			(start -0.925 0.47)
			(end 0.925 -0.47)
			(stroke
				(width 0.05)
				(type default)
			)
			(fill no)
			(layer "B.CrtYd")
		)
		(fp_line
			(start -0.494 -0.248)
			(end -0.494 0.25)
			(stroke
				(width 0.15)
				(type solid)
			)
			(layer "B.Fab")
		)
		(fp_line
			(start -0.494 0.25)
			(end 0.504 0.25)
			(stroke
				(width 0.15)
				(type solid)
			)
			(layer "B.Fab")
		)
		(fp_line
			(start 0.504 -0.248)
			(end -0.494 -0.248)
			(stroke
				(width 0.15)
				(type solid)
			)
			(layer "B.Fab")
		)
		(fp_line
			(start 0.504 0.25)
			(end 0.504 -0.248)
			(stroke
				(width 0.15)
				(type solid)
			)
			(layer "B.Fab")
		)
		(fp_text user "Author: Antmicro"
			(at -0.939 -3.399 0)
			(layer "B.Fab")
			(effects
				(font
					(size 0.7 0.7)
					(thickness 0.15)
				)
				(justify right top mirror)
			)
		)
		(fp_text user "License: Apache-2.0"
			(at -0.939 -5.799 0)
			(layer "B.Fab")
			(effects
				(font
					(size 0.7 0.7)
					(thickness 0.15)
				)
				(justify right top mirror)
			)
		)
		(fp_text user "${REFERENCE}"
			(at -0.939 -4.599 0)
			(layer "B.Fab")
			(effects
				(font
					(size 0.7 0.7)
					(thickness 0.15)
				)
				(justify right top mirror)
			)
		)
		(pad "1" smd roundrect
			(at -0.48 0)
			(size 0.59 0.64)
			(layers "B.Cu" "B.Mask" "B.Paste")
			(roundrect_rratio 0.25)
			(net 9 "+3V3")
			(pintype "passive")
		)
		(pad "2" smd roundrect
			(at 0.48 0)
			(size 0.59 0.64)
			(layers "B.Cu" "B.Mask" "B.Paste")
			(roundrect_rratio 0.25)
			(net 3 "GND")
			(pintype "passive")
		)
	)
	(footprint "antmicro-footprints:R_0402_1005Metric"
		(layer "B.Cu")
		(at 90.387962 153.3915)
		(descr "Resistor SMD 0402")
		(tags "resistor SMD 0402")
		(property "Reference" "R233"
			(at -1.71 3.94 0)
			(layer "B.SilkS")
			(effects
				(font
					(size 0.7 0.7)
					(thickness 0.15)
				)
				(justify right bottom mirror)
			)
		)
		(property "Value" "R_10k_0402"
			(at -1.011843 -1.772047 0)
			(layer "B.Fab")
			(effects
				(font
					(size 0.7 0.7)
					(thickness 0.15)
				)
				(justify right bottom mirror)
			)
		)
		(property "Datasheet" "https://www.bourns.com/docs/product-datasheets/cr.pdf"
			(at 0 0 0)
			(layer "B.Fab")
			(hide yes)
			(effects
				(font
					(size 1.27 1.27)
					(thickness 0.15)
				)
			)
		)
		(property "MPN" "CR0402-FX-1002GLF"
			(at 0 0 0)
			(unlocked yes)
			(layer "B.Fab")
			(hide yes)
			(effects
				(font
					(size 1 1)
					(thickness 0.15)
				)
				(justify mirror)
			)
		)
		(property "Manufacturer" "Bourns"
			(at 0 0 0)
			(unlocked yes)
			(layer "B.Fab")
			(hide yes)
			(effects
				(font
					(size 1 1)
					(thickness 0.15)
				)
				(justify mirror)
			)
		)
		(property "License" "Apache-2.0"
			(at 0 0 0)
			(unlocked yes)
			(layer "B.Fab")
			(hide yes)
			(effects
				(font
					(size 1 1)
					(thickness 0.15)
				)
				(justify mirror)
			)
		)
		(property "Author" "Antmicro"
			(at 0 0 0)
			(unlocked yes)
			(layer "B.Fab")
			(hide yes)
			(effects
				(font
					(size 1 1)
					(thickness 0.15)
				)
				(justify mirror)
			)
		)
		(property "Val" "10k"
			(at 0 0 0)
			(unlocked yes)
			(layer "B.Fab")
			(hide yes)
			(effects
				(font
					(size 1 1)
					(thickness 0.15)
				)
				(justify mirror)
			)
		)
		(property "Tolerance" "1%"
			(at 0 0 0)
			(unlocked yes)
			(layer "B.Fab")
			(hide yes)
			(effects
				(font
					(size 1 1)
					(thickness 0.15)
				)
				(justify mirror)
			)
		)
		(sheetname "/Compute module/")
		(sheetfile "compute-module.kicad_sch")
		(attr smd)
		(fp_rect
			(start -0.925 0.47)
			(end 0.925 -0.47)
			(stroke
				(width 0.05)
				(type default)
			)
			(fill no)
			(layer "B.CrtYd")
		)
		(fp_rect
			(start -0.5 0.25)
			(end 0.5 -0.25)
			(stroke
				(width 0.15)
				(type solid)
			)
			(fill no)
			(layer "B.Fab")
		)
		(fp_text user "License: Apache-2.0"
			(at -0.95 -5.169 180)
			(layer "B.Fab")
			(effects
				(font
					(size 0.7 0.7)
					(thickness 0.15)
				)
				(justify left bottom mirror)
			)
		)
		(fp_text user "${REFERENCE}"
			(at -0.95 -3.168 180)
			(layer "B.Fab")
			(effects
				(font
					(size 0.7 0.7)
					(thickness 0.15)
				)
				(justify left bottom mirror)
			)
		)
		(fp_text user "Author: Antmicro"
			(at -0.95 -4.169 180)
			(layer "B.Fab")
			(effects
				(font
					(size 0.7 0.7)
					(thickness 0.15)
				)
				(justify left bottom mirror)
			)
		)
		(pad "1" smd roundrect
			(at -0.48 0)
			(size 0.59 0.64)
			(layers "B.Cu" "B.Mask" "B.Paste")
			(roundrect_rratio 0.25)
			(net 3 "GND")
			(pintype "passive")
		)
		(pad "2" smd roundrect
			(at 0.48 0)
			(size 0.59 0.64)
			(layers "B.Cu" "B.Mask" "B.Paste")
			(roundrect_rratio 0.25)
			(net 346 "Net-(U204-A1)")
			(pintype "passive")
		)
	)
	(footprint "antmicro-footprints:C_0402_1005Metric"
		(layer "B.Cu")
		(at 66.217962 176.2415 180)
		(descr "Capacitor SMD 0402")
		(tags "capacitor SMD 0402")
		(property "Reference" "C813"
			(at -3.782038 0.545 0)
			(layer "B.SilkS")
			(effects
				(font
					(size 0.7 0.7)
					(thickness 0.15)
				)
				(justify left top mirror)
			)
		)
		(property "Value" "C_1n_0402"
			(at -1.022927 -2.155213 0)
			(layer "B.Fab")
			(effects
				(font
					(size 0.7 0.7)
					(thickness 0.15)
				)
				(justify left top mirror)
			)
		)
		(property "Datasheet" "https://www.murata.com/products/productdetail?partno=GRM1555C1H102JA01%23"
			(at 0 0 0)
			(layer "B.Fab")
			(hide yes)
			(effects
				(font
					(size 1.27 1.27)
					(thickness 0.15)
				)
			)
		)
		(property "Description" "SMD Multilayer Ceramic Capacitor, 1000 pF, 50 V, 0402 [1005 Metric], ± 5%, C0G / NP0, GRM Series"
			(at 0 0 0)
			(layer "B.Fab")
			(hide yes)
			(effects
				(font
					(size 1.27 1.27)
					(thickness 0.15)
				)
			)
		)
		(property "MPN" "GRM1555C1H102JA01D"
			(at 0 0 180)
			(unlocked yes)
			(layer "B.Fab")
			(hide yes)
			(effects
				(font
					(size 1 1)
					(thickness 0.15)
				)
				(justify mirror)
			)
		)
		(property "Manufacturer" "Murata"
			(at 0 0 180)
			(unlocked yes)
			(layer "B.Fab")
			(hide yes)
			(effects
				(font
					(size 1 1)
					(thickness 0.15)
				)
				(justify mirror)
			)
		)
		(property "License" "Apache-2.0"
			(at 0 0 180)
			(unlocked yes)
			(layer "B.Fab")
			(hide yes)
			(effects
				(font
					(size 1 1)
					(thickness 0.15)
				)
				(justify mirror)
			)
		)
		(property "Author" "Antmicro"
			(at 0 0 180)
			(unlocked yes)
			(layer "B.Fab")
			(hide yes)
			(effects
				(font
					(size 1 1)
					(thickness 0.15)
				)
				(justify mirror)
			)
		)
		(property "Val" "1n"
			(at 0 0 180)
			(unlocked yes)
			(layer "B.Fab")
			(hide yes)
			(effects
				(font
					(size 1 1)
					(thickness 0.15)
				)
				(justify mirror)
			)
		)
		(property "Voltage" "50V"
			(at 0 0 180)
			(unlocked yes)
			(layer "B.Fab")
			(hide yes)
			(effects
				(font
					(size 1 1)
					(thickness 0.15)
				)
				(justify mirror)
			)
		)
		(property "Dielectric" "C0G"
			(at 0 0 180)
			(unlocked yes)
			(layer "B.Fab")
			(hide yes)
			(effects
				(font
					(size 1 1)
					(thickness 0.15)
				)
				(justify mirror)
			)
		)
		(sheetname "/Peripherals/")
		(sheetfile "peripherals.kicad_sch")
		(attr smd)
		(fp_rect
			(start -0.925 0.47)
			(end 0.925 -0.47)
			(stroke
				(width 0.05)
				(type default)
			)
			(fill no)
			(layer "B.CrtYd")
		)
		(fp_line
			(start 0.504 0.25)
			(end 0.504 -0.248)
			(stroke
				(width 0.15)
				(type solid)
			)
			(layer "B.Fab")
		)
		(fp_line
			(start 0.504 -0.248)
			(end -0.494 -0.248)
			(stroke
				(width 0.15)
				(type solid)
			)
			(layer "B.Fab")
		)
		(fp_line
			(start -0.494 0.25)
			(end 0.504 0.25)
			(stroke
				(width 0.15)
				(type solid)
			)
			(layer "B.Fab")
		)
		(fp_line
			(start -0.494 -0.248)
			(end -0.494 0.25)
			(stroke
				(width 0.15)
				(type solid)
			)
			(layer "B.Fab")
		)
		(fp_text user "${REFERENCE}"
			(at -0.939 -4.599 0)
			(layer "B.Fab")
			(effects
				(font
					(size 0.7 0.7)
					(thickness 0.15)
				)
				(justify left bottom mirror)
			)
		)
		(fp_text user "License: Apache-2.0"
			(at -0.939 -5.799 0)
			(layer "B.Fab")
			(effects
				(font
					(size 0.7 0.7)
					(thickness 0.15)
				)
				(justify left bottom mirror)
			)
		)
		(fp_text user "Author: Antmicro"
			(at -0.939 -3.399 0)
			(layer "B.Fab")
			(effects
				(font
					(size 0.7 0.7)
					(thickness 0.15)
				)
				(justify left bottom mirror)
			)
		)
		(pad "1" smd roundrect
			(at -0.48 0 180)
			(size 0.59 0.64)
			(layers "B.Cu" "B.Mask" "B.Paste")
			(roundrect_rratio 0.25)
			(net 105 "Net-(U801-RXN)")
			(pintype "passive")
		)
		(pad "2" smd roundrect
			(at 0.48 0 180)
			(size 0.59 0.64)
			(layers "B.Cu" "B.Mask" "B.Paste")
			(roundrect_rratio 0.25)
			(net 104 "Net-(C813-Pad2)")
			(pintype "passive")
		)
	)
	(footprint "antmicro-footprints:R_0402_1005Metric"
		(layer "B.Cu")
		(at 45.332962 165.4375)
		(descr "Resistor SMD 0402")
		(tags "resistor SMD 0402")
		(property "Reference" "R301"
			(at -0.13 1.244 0)
			(layer "B.SilkS")
			(effects
				(font
					(size 0.7 0.7)
					(thickness 0.15)
				)
				(justify right bottom mirror)
			)
		)
		(property "Value" "R_33k_0402"
			(at -1.011843 -1.772047 0)
			(layer "B.Fab")
			(effects
				(font
					(size 0.7 0.7)
					(thickness 0.15)
				)
				(justify right bottom mirror)
			)
		)
		(property "Datasheet" "https://www.bourns.com/docs/product-datasheets/cr.pdf"
			(at 0 0 0)
			(layer "B.Fab")
			(hide yes)
			(effects
				(font
					(size 1.27 1.27)
					(thickness 0.15)
				)
			)
		)
		(property "MPN" "CR0402-FX-3302GLF"
			(at 0 0 0)
			(unlocked yes)
			(layer "B.Fab")
			(hide yes)
			(effects
				(font
					(size 1 1)
					(thickness 0.15)
				)
				(justify mirror)
			)
		)
		(property "Manufacturer" "Bourns"
			(at 0 0 0)
			(unlocked yes)
			(layer "B.Fab")
			(hide yes)
			(effects
				(font
					(size 1 1)
					(thickness 0.15)
				)
				(justify mirror)
			)
		)
		(property "License" "Apache-2.0"
			(at 0 0 0)
			(unlocked yes)
			(layer "B.Fab")
			(hide yes)
			(effects
				(font
					(size 1 1)
					(thickness 0.15)
				)
				(justify mirror)
			)
		)
		(property "Author" "Antmicro"
			(at 0 0 0)
			(unlocked yes)
			(layer "B.Fab")
			(hide yes)
			(effects
				(font
					(size 1 1)
					(thickness 0.15)
				)
				(justify mirror)
			)
		)
		(property "Val" "33k"
			(at 0 0 0)
			(unlocked yes)
			(layer "B.Fab")
			(hide yes)
			(effects
				(font
					(size 1 1)
					(thickness 0.15)
				)
				(justify mirror)
			)
		)
		(property "Tolerance" "1%"
			(at 0 0 0)
			(unlocked yes)
			(layer "B.Fab")
			(hide yes)
			(effects
				(font
					(size 1 1)
					(thickness 0.15)
				)
				(justify mirror)
			)
		)
		(sheetname "/Supply/")
		(sheetfile "supply.kicad_sch")
		(attr smd)
		(fp_rect
			(start -0.925 0.47)
			(end 0.925 -0.47)
			(stroke
				(width 0.05)
				(type default)
			)
			(fill no)
			(layer "B.CrtYd")
		)
		(fp_rect
			(start -0.5 0.25)
			(end 0.5 -0.25)
			(stroke
				(width 0.15)
				(type solid)
			)
			(fill no)
			(layer "B.Fab")
		)
		(fp_text user "${REFERENCE}"
			(at -0.95 -3.168 180)
			(layer "B.Fab")
			(effects
				(font
					(size 0.7 0.7)
					(thickness 0.15)
				)
				(justify left bottom mirror)
			)
		)
		(fp_text user "License: Apache-2.0"
			(at -0.95 -5.169 180)
			(layer "B.Fab")
			(effects
				(font
					(size 0.7 0.7)
					(thickness 0.15)
				)
				(justify left bottom mirror)
			)
		)
		(fp_text user "Author: Antmicro"
			(at -0.95 -4.169 180)
			(layer "B.Fab")
			(effects
				(font
					(size 0.7 0.7)
					(thickness 0.15)
				)
				(justify left bottom mirror)
			)
		)
		(pad "1" smd roundrect
			(at -0.48 0)
			(size 0.59 0.64)
			(layers "B.Cu" "B.Mask" "B.Paste")
			(roundrect_rratio 0.25)
			(net 3 "GND")
			(pintype "passive")
		)
		(pad "2" smd roundrect
			(at 0.48 0)
			(size 0.59 0.64)
			(layers "B.Cu" "B.Mask" "B.Paste")
			(roundrect_rratio 0.25)
			(net 332 "Net-(Q301-REF)")
			(pintype "passive")
		)
	)
	(footprint "antmicro-footprints:Spacer_Drill3.7mm_H6mm_9774060151R"
		(layer "B.Cu")
		(at 41.917962 116.7165)
		(descr "Spacer M=3 h=36mm fi=5.1mm")
		(property "Reference" "H103"
			(at 1.46 -3.3 180)
			(layer "B.SilkS")
			(effects
				(font
					(size 0.7 0.7)
					(thickness 0.15)
				)
				(justify left bottom mirror)
			)
		)
		(property "Value" "Spacer_Drill3.7mm_H6mm_9774060151R"
			(at 0 -4 180)
			(layer "B.Fab")
			(effects
				(font
					(size 0.7 0.7)
					(thickness 0.15)
				)
				(justify left bottom mirror)
			)
		)
		(property "Datasheet" "https://www.we-online.com/components/products/datasheet/9774060151R.pdf"
			(at 0 0 0)
			(layer "B.Fab")
			(hide yes)
			(effects
				(font
					(size 1.27 1.27)
					(thickness 0.15)
				)
			)
		)
		(property "Manufacturer" "Würth Elektronik"
			(at 0 0 0)
			(unlocked yes)
			(layer "B.Fab")
			(hide yes)
			(effects
				(font
					(size 1 1)
					(thickness 0.15)
				)
				(justify mirror)
			)
		)
		(property "MPN" "9774060151R"
			(at 0 0 0)
			(unlocked yes)
			(layer "B.Fab")
			(hide yes)
			(effects
				(font
					(size 1 1)
					(thickness 0.15)
				)
				(justify mirror)
			)
		)
		(property "Author" "Antmicro"
			(at 0 0 0)
			(unlocked yes)
			(layer "B.Fab")
			(hide yes)
			(effects
				(font
					(size 1 1)
					(thickness 0.15)
				)
				(justify mirror)
			)
		)
		(property "License" "Apache-2.0"
			(at 0 0 0)
			(unlocked yes)
			(layer "B.Fab")
			(hide yes)
			(effects
				(font
					(size 1 1)
					(thickness 0.15)
				)
				(justify mirror)
			)
		)
		(sheetname "/")
		(sheetfile "cm4-baseboard.kicad_sch")
		(solder_paste_margin_ratio -1)
		(attr smd)
		(fp_circle
			(center 0 0)
			(end 3.05 0)
			(stroke
				(width 0.05)
				(type solid)
			)
			(fill no)
			(layer "B.CrtYd")
		)
		(fp_circle
			(center 0 0)
			(end 2.6 0)
			(stroke
				(width 0.15)
				(type solid)
			)
			(fill no)
			(layer "B.Fab")
		)
		(fp_text user "${REFERENCE}"
			(at -9.6 -6.5 180)
			(layer "B.Fab")
			(effects
				(font
					(size 0.7 0.7)
					(thickness 0.15)
				)
				(justify left bottom mirror)
			)
		)
		(fp_text user "License: Apache-2.0"
			(at -9.6 -8.9 180)
			(layer "B.Fab")
			(effects
				(font
					(size 0.7 0.7)
					(thickness 0.15)
				)
				(justify left bottom mirror)
			)
		)
		(fp_text user "Author: Antmicro"
			(at -9.6 -7.7 180)
			(layer "B.Fab")
			(effects
				(font
					(size 0.7 0.7)
					(thickness 0.15)
				)
				(justify left bottom mirror)
			)
		)
		(pad "" smd custom
			(at -1.7 -1.7 270)
			(size 0.62 0.62)
			(layers "B.Paste")
			(thermal_bridge_angle 90)
			(options
				(clearance outline)
				(anchor circle)
			)
			(primitives
				(gr_arc
					(start 1.266786 0.24747)
					(mid 0.285453 -0.29439)
					(end -0.250195 -1.279127)
					(width 0.2)
				)
				(gr_arc
					(start 1.259603 0.339191)
					(mid 0.218448 -0.232561)
					(end -0.34334 -1.279127)
					(width 0.2)
				)
				(gr_arc
					(start 1.255279 0.431435)
					(mid 0.152481 -0.169693)
					(end -0.436309 -1.279127)
					(width 0.2)
				)
				(gr_arc
					(start 1.253811 0.524161)
					(mid 0.087542 -0.105784)
					(end -0.529126 -1.279127)
					(width 0.2)
				)
				(gr_arc
					(start 1.275473 0.621136)
					(mid 0.0309 -0.033527)
					(end -0.621807 -1.279127)
					(width 0.2)
				)
				(gr_arc
					(start 1.263664 0.711602)
					(mid -0.037759 0.026651)
					(end -0.71437 -1.279127)
					(width 0.2)
				)
				(gr_arc
					(start 1.253435 0.802342)
					(mid -0.105837 0.087395)
					(end -0.806826 -1.279127)
					(width 0.2)
				)
				(gr_arc
					(start 1.267475 0.897258)
					(mid -0.165236 0.156885)
					(end -0.899187 -1.279127)
					(width 0.2)
				)
				(gr_arc
					(start 1.270645 0.990112)
					(mid -0.228522 0.222449)
					(end -0.991463 -1.279127)
					(width 0.2)
				)
				(gr_arc
					(start 1.266278 1.081674)
					(mid -0.294507 0.285313)
					(end -1.083663 -1.279127)
					(width 0.2)
				)
				(gr_line
					(start 1.279127 0.250195)
					(end 1.279127 1.083663)
					(width 0.2)
				)
				(gr_line
					(start -0.250195 -1.279127)
					(end -1.083663 -1.279127)
					(width 0.2)
				)
			)
		)
		(pad "" smd custom
			(at -1.7 1.7)
			(size 0.62 0.62)
			(layers "B.Paste")
			(thermal_bridge_angle 90)
			(options
				(clearance outline)
				(anchor circle)
			)
			(primitives
				(gr_arc
					(start 1.266786 0.24747)
					(mid 0.285453 -0.29439)
					(end -0.250195 -1.279127)
					(width 0.2)
				)
				(gr_arc
					(start 1.259603 0.339191)
					(mid 0.218448 -0.232561)
					(end -0.34334 -1.279127)
					(width 0.2)
				)
				(gr_arc
					(start 1.255279 0.431435)
					(mid 0.152481 -0.169693)
					(end -0.436309 -1.279127)
					(width 0.2)
				)
				(gr_arc
					(start 1.253811 0.524161)
					(mid 0.087542 -0.105784)
					(end -0.529126 -1.279127)
					(width 0.2)
				)
				(gr_arc
					(start 1.275473 0.621136)
					(mid 0.0309 -0.033527)
					(end -0.621807 -1.279127)
					(width 0.2)
				)
				(gr_arc
					(start 1.263664 0.711602)
					(mid -0.037759 0.026651)
					(end -0.71437 -1.279127)
					(width 0.2)
				)
				(gr_arc
					(start 1.253435 0.802342)
					(mid -0.105837 0.087395)
					(end -0.806826 -1.279127)
					(width 0.2)
				)
				(gr_arc
					(start 1.267475 0.897258)
					(mid -0.165236 0.156885)
					(end -0.899187 -1.279127)
					(width 0.2)
				)
				(gr_arc
					(start 1.270645 0.990112)
					(mid -0.228522 0.222449)
					(end -0.991463 -1.279127)
					(width 0.2)
				)
				(gr_arc
					(start 1.266278 1.081674)
					(mid -0.294507 0.285313)
					(end -1.083663 -1.279127)
					(width 0.2)
				)
				(gr_line
					(start 1.279127 0.250195)
					(end 1.279127 1.083663)
					(width 0.2)
				)
				(gr_line
					(start -0.250195 -1.279127)
					(end -1.083663 -1.279127)
					(width 0.2)
				)
			)
		)
		(pad "" smd custom
			(at 1.7 -1.7 180)
			(size 0.62 0.62)
			(layers "B.Paste")
			(thermal_bridge_angle 90)
			(options
				(clearance outline)
				(anchor circle)
			)
			(primitives
				(gr_arc
					(start 1.266786 0.24747)
					(mid 0.285453 -0.29439)
					(end -0.250195 -1.279127)
					(width 0.2)
				)
				(gr_arc
					(start 1.259603 0.339191)
					(mid 0.218448 -0.232561)
					(end -0.34334 -1.279127)
					(width 0.2)
				)
				(gr_arc
					(start 1.255279 0.431435)
					(mid 0.152481 -0.169693)
					(end -0.436309 -1.279127)
					(width 0.2)
				)
				(gr_arc
					(start 1.253811 0.524161)
					(mid 0.087542 -0.105784)
					(end -0.529126 -1.279127)
					(width 0.2)
				)
				(gr_arc
					(start 1.275473 0.621136)
					(mid 0.0309 -0.033527)
					(end -0.621807 -1.279127)
					(width 0.2)
				)
				(gr_arc
					(start 1.263664 0.711602)
					(mid -0.037759 0.026651)
					(end -0.71437 -1.279127)
					(width 0.2)
				)
				(gr_arc
					(start 1.253435 0.802342)
					(mid -0.105837 0.087395)
					(end -0.806826 -1.279127)
					(width 0.2)
				)
				(gr_arc
					(start 1.267475 0.897258)
					(mid -0.165236 0.156885)
					(end -0.899187 -1.279127)
					(width 0.2)
				)
				(gr_arc
					(start 1.270645 0.990112)
					(mid -0.228522 0.222449)
					(end -0.991463 -1.279127)
					(width 0.2)
				)
				(gr_arc
					(start 1.266278 1.081674)
					(mid -0.294507 0.285313)
					(end -1.083663 -1.279127)
					(width 0.2)
				)
				(gr_line
					(start 1.279127 0.250195)
					(end 1.279127 1.083663)
					(width 0.2)
				)
				(gr_line
					(start -0.250195 -1.279127)
					(end -1.083663 -1.279127)
					(width 0.2)
				)
			)
		)
		(pad "" smd custom
			(at 1.7 1.7 90)
			(size 0.62 0.62)
			(layers "B.Paste")
			(thermal_bridge_angle 90)
			(options
				(clearance outline)
				(anchor circle)
			)
			(primitives
				(gr_arc
					(start 1.266786 0.24747)
					(mid 0.285453 -0.29439)
					(end -0.250195 -1.279127)
					(width 0.2)
				)
				(gr_arc
					(start 1.259603 0.339191)
					(mid 0.218448 -0.232561)
					(end -0.34334 -1.279127)
					(width 0.2)
				)
				(gr_arc
					(start 1.255279 0.431435)
					(mid 0.152481 -0.169693)
					(end -0.436309 -1.279127)
					(width 0.2)
				)
				(gr_arc
					(start 1.253811 0.524161)
					(mid 0.087542 -0.105784)
					(end -0.529126 -1.279127)
					(width 0.2)
				)
				(gr_arc
					(start 1.275473 0.621136)
					(mid 0.0309 -0.033527)
					(end -0.621807 -1.279127)
					(width 0.2)
				)
				(gr_arc
					(start 1.263664 0.711602)
					(mid -0.037759 0.026651)
					(end -0.71437 -1.279127)
					(width 0.2)
				)
				(gr_arc
					(start 1.253435 0.802342)
					(mid -0.105837 0.087395)
					(end -0.806826 -1.279127)
					(width 0.2)
				)
				(gr_arc
					(start 1.267475 0.897258)
					(mid -0.165236 0.156885)
					(end -0.899187 -1.279127)
					(width 0.2)
				)
				(gr_arc
					(start 1.270645 0.990112)
					(mid -0.228522 0.222449)
					(end -0.991463 -1.279127)
					(width 0.2)
				)
				(gr_arc
					(start 1.266278 1.081674)
					(mid -0.294507 0.285313)
					(end -1.083663 -1.279127)
					(width 0.2)
				)
				(gr_line
					(start 1.279127 0.250195)
					(end 1.279127 1.083663)
					(width 0.2)
				)
				(gr_line
					(start -0.250195 -1.279127)
					(end -1.083663 -1.279127)
					(width 0.2)
				)
			)
		)
		(pad "1" thru_hole circle
			(at 0 0)
			(size 6 6)
			(drill 3.7)
			(layers "*.Cu" "*.Mask")
			(remove_unused_layers no)
			(net 3 "GND")
			(pintype "passive")
		)
	)
	(footprint "antmicro-footprints:C_0402_1005Metric"
		(layer "B.Cu")
		(at 119.067962 115.7665 -90)
		(descr "Capacitor SMD 0402")
		(tags "capacitor SMD 0402")
		(property "Reference" "C506"
			(at 1.33 1.88 90)
			(layer "B.SilkS")
			(effects
				(font
					(size 0.7 0.7)
					(thickness 0.15)
				)
				(justify left bottom mirror)
			)
		)
		(property "Value" "C_1u_0402"
			(at -1.022927 -2.155213 90)
			(layer "B.Fab")
			(effects
				(font
					(size 0.7 0.7)
					(thickness 0.15)
				)
				(justify left bottom mirror)
			)
		)
		(property "Datasheet" "https://product.tdk.com/en/search/capacitor/ceramic/mlcc/info?part_no=C1005X6S1A105K050BC"
			(at 0 0 270)
			(layer "B.Fab")
			(hide yes)
			(effects
				(font
					(size 1.27 1.27)
					(thickness 0.15)
				)
			)
		)
		(property "Manufacturer" "TDK"
			(at 0 0 270)
			(unlocked yes)
			(layer "B.Fab")
			(hide yes)
			(effects
				(font
					(size 1 1)
					(thickness 0.15)
				)
				(justify mirror)
			)
		)
		(property "MPN" "C1005X6S1A105K050BC"
			(at 0 0 270)
			(unlocked yes)
			(layer "B.Fab")
			(hide yes)
			(effects
				(font
					(size 1 1)
					(thickness 0.15)
				)
				(justify mirror)
			)
		)
		(property "Val" "1u"
			(at 0 0 270)
			(unlocked yes)
			(layer "B.Fab")
			(hide yes)
			(effects
				(font
					(size 1 1)
					(thickness 0.15)
				)
				(justify mirror)
			)
		)
		(property "License" "Apache-2.0"
			(at 0 0 270)
			(unlocked yes)
			(layer "B.Fab")
			(hide yes)
			(effects
				(font
					(size 1 1)
					(thickness 0.15)
				)
				(justify mirror)
			)
		)
		(property "Author" "Antmicro"
			(at 0 0 270)
			(unlocked yes)
			(layer "B.Fab")
			(hide yes)
			(effects
				(font
					(size 1 1)
					(thickness 0.15)
				)
				(justify mirror)
			)
		)
		(property "Voltage" ""
			(at 0 0 270)
			(unlocked yes)
			(layer "B.Fab")
			(hide yes)
			(effects
				(font
					(size 1 1)
					(thickness 0.15)
				)
				(justify mirror)
			)
		)
		(property "Dielectric" ""
			(at 0 0 270)
			(unlocked yes)
			(layer "B.Fab")
			(hide yes)
			(effects
				(font
					(size 1 1)
					(thickness 0.15)
				)
				(justify mirror)
			)
		)
		(sheetname "/NVMe & microSD/")
		(sheetfile "nvme-micro-sd.kicad_sch")
		(attr smd)
		(fp_rect
			(start -0.925 0.47)
			(end 0.925 -0.47)
			(stroke
				(width 0.05)
				(type default)
			)
			(fill no)
			(layer "B.CrtYd")
		)
		(fp_line
			(start -0.494 0.25)
			(end 0.504 0.25)
			(stroke
				(width 0.15)
				(type solid)
			)
			(layer "B.Fab")
		)
		(fp_line
			(start 0.504 0.25)
			(end 0.504 -0.248)
			(stroke
				(width 0.15)
				(type solid)
			)
			(layer "B.Fab")
		)
		(fp_line
			(start -0.494 -0.248)
			(end -0.494 0.25)
			(stroke
				(width 0.15)
				(type solid)
			)
			(layer "B.Fab")
		)
		(fp_line
			(start 0.504 -0.248)
			(end -0.494 -0.248)
			(stroke
				(width 0.15)
				(type solid)
			)
			(layer "B.Fab")
		)
		(fp_text user "Author: Antmicro"
			(at -0.939 -3.399 90)
			(layer "B.Fab")
			(effects
				(font
					(size 0.7 0.7)
					(thickness 0.15)
				)
				(justify left bottom mirror)
			)
		)
		(fp_text user "License: Apache-2.0"
			(at -0.939 -5.799 90)
			(layer "B.Fab")
			(effects
				(font
					(size 0.7 0.7)
					(thickness 0.15)
				)
				(justify left bottom mirror)
			)
		)
		(fp_text user "${REFERENCE}"
			(at -0.939 -4.599 90)
			(layer "B.Fab")
			(effects
				(font
					(size 0.7 0.7)
					(thickness 0.15)
				)
				(justify left bottom mirror)
			)
		)
		(pad "1" smd roundrect
			(at -0.48 0 270)
			(size 0.59 0.64)
			(layers "B.Cu" "B.Mask" "B.Paste")
			(roundrect_rratio 0.25)
			(net 3 "GND")
			(pintype "passive")
		)
		(pad "2" smd roundrect
			(at 0.48 0 270)
			(size 0.59 0.64)
			(layers "B.Cu" "B.Mask" "B.Paste")
			(roundrect_rratio 0.25)
			(net 65 "3V3_SSD")
			(pintype "passive")
		)
	)
	(footprint "antmicro-footprints:TP_SMD_0.75mm"
		(layer "B.Cu")
		(at 80.55 147.9)
		(property "Reference" "TP204"
			(at 0.375 1.105 0)
			(layer "B.SilkS")
			(effects
				(font
					(size 0.7 0.7)
					(thickness 0.15)
				)
				(justify right bottom mirror)
			)
		)
		(property "Value" "TP_0.75mm_SMD"
			(at 0 -1.2 0)
			(layer "B.Fab")
			(effects
				(font
					(size 0.7 0.7)
					(thickness 0.15)
				)
				(justify right bottom mirror)
			)
		)
		(property "Author" "Antmicro"
			(at 0 0 0)
			(unlocked yes)
			(layer "B.Fab")
			(hide yes)
			(effects
				(font
					(size 1 1)
					(thickness 0.15)
				)
				(justify mirror)
			)
		)
		(property "License" "Apache-2.0"
			(at 0 0 0)
			(unlocked yes)
			(layer "B.Fab")
			(hide yes)
			(effects
				(font
					(size 1 1)
					(thickness 0.15)
				)
				(justify mirror)
			)
		)
		(property "MPN" ""
			(at 0 0 0)
			(unlocked yes)
			(layer "B.Fab")
			(hide yes)
			(effects
				(font
					(size 1 1)
					(thickness 0.15)
				)
				(justify mirror)
			)
		)
		(property "Manufacturer" ""
			(at 0 0 0)
			(unlocked yes)
			(layer "B.Fab")
			(hide yes)
			(effects
				(font
					(size 1 1)
					(thickness 0.15)
				)
				(justify mirror)
			)
		)
		(sheetname "/Compute module/")
		(sheetfile "compute-module.kicad_sch")
		(attr exclude_from_pos_files exclude_from_bom)
		(fp_circle
			(center 0 0)
			(end 0.475 0)
			(stroke
				(width 0.05)
				(type default)
			)
			(fill no)
			(layer "B.CrtYd")
		)
		(fp_text user "Author: Antmicro"
			(at -0.4 -3.901 180)
			(layer "B.Fab")
			(effects
				(font
					(size 0.7 0.7)
					(thickness 0.15)
				)
				(justify left bottom mirror)
			)
		)
		(fp_text user "License: Apache-2.0"
			(at -0.4 -5.101 180)
			(layer "B.Fab")
			(effects
				(font
					(size 0.7 0.7)
					(thickness 0.15)
				)
				(justify left bottom mirror)
			)
		)
		(fp_text user "${REFERENCE}"
			(at -0.4 -2.7 180)
			(layer "B.Fab")
			(effects
				(font
					(size 0.7 0.7)
					(thickness 0.15)
				)
				(justify left bottom mirror)
			)
		)
		(pad "1" smd circle
			(at 0 0)
			(size 0.75 0.75)
			(layers "B.Cu" "B.Mask")
			(net 215 "/Compute module/SYNC_OUT")
			(pinfunction "1")
			(pintype "passive")
		)
	)
	(footprint "antmicro-footprints:R_0402_1005Metric"
		(layer "B.Cu")
		(at 41.857962 159.5865 180)
		(descr "Resistor SMD 0402")
		(tags "resistor SMD 0402")
		(property "Reference" "R307"
			(at 0.82 -1.07 0)
			(layer "B.SilkS")
			(effects
				(font
					(size 0.7 0.7)
					(thickness 0.15)
				)
				(justify left bottom mirror)
			)
		)
		(property "Value" "R_4k7_0402"
			(at -1.011843 -1.772047 0)
			(layer "B.Fab")
			(effects
				(font
					(size 0.7 0.7)
					(thickness 0.15)
				)
				(justify left bottom mirror)
			)
		)
		(property "Datasheet" "https://www.bourns.com/docs/product-datasheets/cr.pdf"
			(at 0 0 180)
			(layer "B.Fab")
			(hide yes)
			(effects
				(font
					(size 1.27 1.27)
					(thickness 0.15)
				)
			)
		)
		(property "Manufacturer" "Bourns"
			(at 0 0 180)
			(unlocked yes)
			(layer "B.Fab")
			(hide yes)
			(effects
				(font
					(size 1 1)
					(thickness 0.15)
				)
				(justify mirror)
			)
		)
		(property "MPN" "CR0402-FX-4701GLF"
			(at 0 0 180)
			(unlocked yes)
			(layer "B.Fab")
			(hide yes)
			(effects
				(font
					(size 1 1)
					(thickness 0.15)
				)
				(justify mirror)
			)
		)
		(property "Val" "4k7"
			(at 0 0 180)
			(unlocked yes)
			(layer "B.Fab")
			(hide yes)
			(effects
				(font
					(size 1 1)
					(thickness 0.15)
				)
				(justify mirror)
			)
		)
		(property "License" "Apache-2.0"
			(at 0 0 180)
			(unlocked yes)
			(layer "B.Fab")
			(hide yes)
			(effects
				(font
					(size 1 1)
					(thickness 0.15)
				)
				(justify mirror)
			)
		)
		(property "Author" "Antmicro"
			(at 0 0 180)
			(unlocked yes)
			(layer "B.Fab")
			(hide yes)
			(effects
				(font
					(size 1 1)
					(thickness 0.15)
				)
				(justify mirror)
			)
		)
		(property "Tolerance" "1%"
			(at 0 0 180)
			(unlocked yes)
			(layer "B.Fab")
			(hide yes)
			(effects
				(font
					(size 1 1)
					(thickness 0.15)
				)
				(justify mirror)
			)
		)
		(sheetname "/Supply/")
		(sheetfile "supply.kicad_sch")
		(attr smd)
		(fp_rect
			(start -0.925 0.47)
			(end 0.925 -0.47)
			(stroke
				(width 0.05)
				(type default)
			)
			(fill no)
			(layer "B.CrtYd")
		)
		(fp_rect
			(start -0.5 0.25)
			(end 0.5 -0.25)
			(stroke
				(width 0.15)
				(type solid)
			)
			(fill no)
			(layer "B.Fab")
		)
		(fp_text user "Author: Antmicro"
			(at -0.95 -4.169 0)
			(layer "B.Fab")
			(effects
				(font
					(size 0.7 0.7)
					(thickness 0.15)
				)
				(justify left bottom mirror)
			)
		)
		(fp_text user "License: Apache-2.0"
			(at -0.95 -5.169 0)
			(layer "B.Fab")
			(effects
				(font
					(size 0.7 0.7)
					(thickness 0.15)
				)
				(justify left bottom mirror)
			)
		)
		(fp_text user "${REFERENCE}"
			(at -0.95 -3.168 0)
			(layer "B.Fab")
			(effects
				(font
					(size 0.7 0.7)
					(thickness 0.15)
				)
				(justify left bottom mirror)
			)
		)
		(pad "1" smd roundrect
			(at -0.48 0 180)
			(size 0.59 0.64)
			(layers "B.Cu" "B.Mask" "B.Paste")
			(roundrect_rratio 0.25)
			(net 17 "Net-(Q307-G)")
			(pintype "passive")
		)
		(pad "2" smd roundrect
			(at 0.48 0 180)
			(size 0.59 0.64)
			(layers "B.Cu" "B.Mask" "B.Paste")
			(roundrect_rratio 0.25)
			(net 21 "/Supply/VCC_IN")
			(pintype "passive")
		)
	)
	(footprint "antmicro-footprints:DFN3538"
		(layer "B.Cu")
		(at 63.917962 121.5665 180)
		(property "Reference" "D402"
			(at -1.412038 2.6765 0)
			(unlocked yes)
			(layer "B.SilkS")
			(effects
				(font
					(size 0.7 0.7)
					(thickness 0.15)
				)
				(justify left bottom mirror)
			)
		)
		(property "Value" "CD-MMBL110S"
			(at 0 -3.5 0)
			(unlocked yes)
			(layer "B.Fab")
			(effects
				(font
					(size 0.7 0.7)
					(thickness 0.15)
				)
				(justify left bottom mirror)
			)
		)
		(property "Datasheet" "https://www.bourns.com/docs/product-datasheets/CD-MMBL110S.pdf"
			(at 0 0 180)
			(layer "B.Fab")
			(hide yes)
			(effects
				(font
					(size 1.27 1.27)
					(thickness 0.15)
				)
			)
		)
		(property "MPN" "CD-MMBL110S"
			(at 0 0 180)
			(unlocked yes)
			(layer "B.Fab")
			(hide yes)
			(effects
				(font
					(size 1 1)
					(thickness 0.15)
				)
				(justify mirror)
			)
		)
		(property "Manufacturer" "Bourns"
			(at 0 0 180)
			(unlocked yes)
			(layer "B.Fab")
			(hide yes)
			(effects
				(font
					(size 1 1)
					(thickness 0.15)
				)
				(justify mirror)
			)
		)
		(property "Author" "Antmicro"
			(at 0 0 180)
			(unlocked yes)
			(layer "B.Fab")
			(hide yes)
			(effects
				(font
					(size 1 1)
					(thickness 0.15)
				)
				(justify mirror)
			)
		)
		(property "License" "Apache-2.0"
			(at 0 0 180)
			(unlocked yes)
			(layer "B.Fab")
			(hide yes)
			(effects
				(font
					(size 1 1)
					(thickness 0.15)
				)
				(justify mirror)
			)
		)
		(sheetname "/Ethernet/")
		(sheetfile "ethernet.kicad_sch")
		(attr smd)
		(fp_line
			(start 1.8 2)
			(end 1.8 -2.05)
			(stroke
				(width 0.15)
				(type solid)
			)
			(layer "B.SilkS")
		)
		(fp_line
			(start 1.6 2)
			(end 1.8 2)
			(stroke
				(width 0.15)
				(type solid)
			)
			(layer "B.SilkS")
		)
		(fp_line
			(start 1.6 -2.05)
			(end 1.8 -2.05)
			(stroke
				(width 0.15)
				(type solid)
			)
			(layer "B.SilkS")
		)
		(fp_line
			(start 0.9 2.301)
			(end 0.598 2.301)
			(stroke
				(width 0.15)
				(type solid)
			)
			(layer "B.SilkS")
		)
		(fp_line
			(start 0.748 2.452)
			(end 0.748 2.15)
			(stroke
				(width 0.15)
				(type solid)
			)
			(layer "B.SilkS")
		)
		(fp_line
			(start -0.902 2.25)
			(end -0.6 2.25)
			(stroke
				(width 0.15)
				(type solid)
			)
			(layer "B.SilkS")
		)
		(fp_line
			(start -0.95 2)
			(end 0.95 2)
			(stroke
				(width 0.15)
				(type solid)
			)
			(layer "B.SilkS")
		)
		(fp_line
			(start -0.95 -2.05)
			(end 0.95 -2.05)
			(stroke
				(width 0.15)
				(type solid)
			)
			(layer "B.SilkS")
		)
		(fp_line
			(start -1.8 1.5)
			(end -1.8 -2.05)
			(stroke
				(width 0.15)
				(type solid)
			)
			(layer "B.SilkS")
		)
		(fp_line
			(start -1.8 -2.05)
			(end -1.6 -2.05)
			(stroke
				(width 0.15)
				(type solid)
			)
			(layer "B.SilkS")
		)
		(fp_rect
			(start -2.1 2.6)
			(end 2.1 -2.6)
			(stroke
				(width 0.05)
				(type solid)
			)
			(fill no)
			(layer "B.CrtYd")
		)
		(fp_line
			(start -1.051 2)
			(end -1.801 1.25)
			(stroke
				(width 0.15)
				(type solid)
			)
			(layer "B.Fab")
		)
		(fp_rect
			(start 1.8 -2.048)
			(end -1.8 2)
			(stroke
				(width 0.15)
				(type solid)
			)
			(fill no)
			(layer "B.Fab")
		)
		(fp_text user "~"
			(at -0.31 -2.7 0)
			(unlocked yes)
			(layer "B.SilkS")
			(effects
				(font
					(size 0.7 0.7)
					(thickness 0.15)
				)
				(justify left bottom mirror)
			)
		)
		(fp_text user "License: Apache-2.0"
			(at -2.1 -6.599 0)
			(layer "B.Fab")
			(effects
				(font
					(size 0.7 0.7)
					(thickness 0.15)
				)
				(justify left bottom mirror)
			)
		)
		(fp_text user "Author: Antmicro"
			(at -2.1 -5.599 0)
			(layer "B.Fab")
			(effects
				(font
					(size 0.7 0.7)
					(thickness 0.15)
				)
				(justify left bottom mirror)
			)
		)
		(fp_text user "${REFERENCE}"
			(at -2.1 -4.599 0)
			(layer "B.Fab")
			(effects
				(font
					(size 0.7 0.7)
					(thickness 0.15)
				)
				(justify left bottom mirror)
			)
		)
		(pad "1" smd roundrect
			(at -1.27 1.85 90)
			(size 1.4 0.48)
			(layers "B.Cu" "B.Mask" "B.Paste")
			(roundrect_rratio 0.25)
			(net 116 "Net-(D401-Pad1)")
			(pinfunction "1")
			(pintype "passive")
		)
		(pad "2" smd roundrect
			(at 1.27 1.85 90)
			(size 1.4 0.48)
			(layers "B.Cu" "B.Mask" "B.Paste")
			(roundrect_rratio 0.25)
			(net 117 "Net-(D401-Pad2)")
			(pinfunction "2")
			(pintype "passive")
		)
		(pad "3" smd roundrect
			(at -1.27 -1.85 90)
			(size 1.4 0.48)
			(layers "B.Cu" "B.Mask" "B.Paste")
			(roundrect_rratio 0.25)
			(net 63 "/Ethernet/PAIR_910")
			(pinfunction "3")
			(pintype "passive")
		)
		(pad "4" smd roundrect
			(at 1.27 -1.85 90)
			(size 1.4 0.48)
			(layers "B.Cu" "B.Mask" "B.Paste")
			(roundrect_rratio 0.25)
			(net 64 "/Ethernet/PAIR_78")
			(pinfunction "4")
			(pintype "passive")
		)
	)
	(footprint "antmicro-footprints:C_0402_1005Metric"
		(layer "B.Cu")
		(at 118.192962 129.7665 -90)
		(descr "Capacitor SMD 0402")
		(tags "capacitor SMD 0402")
		(property "Reference" "C503"
			(at -1.41 0.575 90)
			(layer "B.SilkS")
			(effects
				(font
					(size 0.7 0.7)
					(thickness 0.15)
				)
				(justify left bottom mirror)
			)
		)
		(property "Value" "C_10u_0402"
			(at -1.022927 -2.155213 90)
			(layer "B.Fab")
			(effects
				(font
					(size 0.7 0.7)
					(thickness 0.15)
				)
				(justify left bottom mirror)
			)
		)
		(property "Datasheet" "https://www.yageo.com/en/Chart/Download/pdf/CC0402MRX5R5BB106"
			(at 0 0 270)
			(layer "B.Fab")
			(hide yes)
			(effects
				(font
					(size 1.27 1.27)
					(thickness 0.15)
				)
			)
		)
		(property "MPN" "CC0402MRX5R5BB106"
			(at 0 0 270)
			(unlocked yes)
			(layer "B.Fab")
			(hide yes)
			(effects
				(font
					(size 1 1)
					(thickness 0.15)
				)
				(justify mirror)
			)
		)
		(property "Manufacturer" "YAGEO"
			(at 0 0 270)
			(unlocked yes)
			(layer "B.Fab")
			(hide yes)
			(effects
				(font
					(size 1 1)
					(thickness 0.15)
				)
				(justify mirror)
			)
		)
		(property "License" "Apache-2.0"
			(at 0 0 270)
			(unlocked yes)
			(layer "B.Fab")
			(hide yes)
			(effects
				(font
					(size 1 1)
					(thickness 0.15)
				)
				(justify mirror)
			)
		)
		(property "Author" "Antmicro"
			(at 0 0 270)
			(unlocked yes)
			(layer "B.Fab")
			(hide yes)
			(effects
				(font
					(size 1 1)
					(thickness 0.15)
				)
				(justify mirror)
			)
		)
		(property "Val" "10u"
			(at 0 0 270)
			(unlocked yes)
			(layer "B.Fab")
			(hide yes)
			(effects
				(font
					(size 1 1)
					(thickness 0.15)
				)
				(justify mirror)
			)
		)
		(property "Voltage" ""
			(at 0 0 270)
			(unlocked yes)
			(layer "B.Fab")
			(hide yes)
			(effects
				(font
					(size 1 1)
					(thickness 0.15)
				)
				(justify mirror)
			)
		)
		(property "Dielectric" ""
			(at 0 0 270)
			(unlocked yes)
			(layer "B.Fab")
			(hide yes)
			(effects
				(font
					(size 1 1)
					(thickness 0.15)
				)
				(justify mirror)
			)
		)
		(sheetname "/NVMe & microSD/")
		(sheetfile "nvme-micro-sd.kicad_sch")
		(attr smd)
		(fp_rect
			(start -0.925 0.47)
			(end 0.925 -0.47)
			(stroke
				(width 0.05)
				(type default)
			)
			(fill no)
			(layer "B.CrtYd")
		)
		(fp_line
			(start -0.494 0.25)
			(end 0.504 0.25)
			(stroke
				(width 0.15)
				(type solid)
			)
			(layer "B.Fab")
		)
		(fp_line
			(start 0.504 0.25)
			(end 0.504 -0.248)
			(stroke
				(width 0.15)
				(type solid)
			)
			(layer "B.Fab")
		)
		(fp_line
			(start -0.494 -0.248)
			(end -0.494 0.25)
			(stroke
				(width 0.15)
				(type solid)
			)
			(layer "B.Fab")
		)
		(fp_line
			(start 0.504 -0.248)
			(end -0.494 -0.248)
			(stroke
				(width 0.15)
				(type solid)
			)
			(layer "B.Fab")
		)
		(fp_text user "Author: Antmicro"
			(at -0.939 -3.399 90)
			(layer "B.Fab")
			(effects
				(font
					(size 0.7 0.7)
					(thickness 0.15)
				)
				(justify left bottom mirror)
			)
		)
		(fp_text user "${REFERENCE}"
			(at -0.939 -4.599 90)
			(layer "B.Fab")
			(effects
				(font
					(size 0.7 0.7)
					(thickness 0.15)
				)
				(justify left bottom mirror)
			)
		)
		(fp_text user "License: Apache-2.0"
			(at -0.939 -5.799 90)
			(layer "B.Fab")
			(effects
				(font
					(size 0.7 0.7)
					(thickness 0.15)
				)
				(justify left bottom mirror)
			)
		)
		(pad "1" smd roundrect
			(at -0.48 0 270)
			(size 0.59 0.64)
			(layers "B.Cu" "B.Mask" "B.Paste")
			(roundrect_rratio 0.25)
			(net 3 "GND")
			(pintype "passive")
		)
		(pad "2" smd roundrect
			(at 0.48 0 270)
			(size 0.59 0.64)
			(layers "B.Cu" "B.Mask" "B.Paste")
			(roundrect_rratio 0.25)
			(net 65 "3V3_SSD")
			(pintype "passive")
		)
	)
	(footprint "antmicro-footprints:R_0402_1005Metric"
		(layer "B.Cu")
		(at 65.692962 161.2165)
		(descr "Resistor SMD 0402")
		(tags "resistor SMD 0402")
		(property "Reference" "R320"
			(at 14.275 0.71 0)
			(layer "B.SilkS")
			(effects
				(font
					(size 0.7 0.7)
					(thickness 0.15)
				)
				(justify right bottom mirror)
			)
		)
		(property "Value" "R_6k8_0402"
			(at -1.011843 -1.772047 0)
			(layer "B.Fab")
			(effects
				(font
					(size 0.7 0.7)
					(thickness 0.15)
				)
				(justify right bottom mirror)
			)
		)
		(property "Datasheet" "https://www.bourns.com/docs/product-datasheets/cr.pdf"
			(at 0 0 0)
			(layer "B.Fab")
			(hide yes)
			(effects
				(font
					(size 1.27 1.27)
					(thickness 0.15)
				)
			)
		)
		(property "MPN" "CR0402-FX-6801GLF"
			(at 0 0 0)
			(unlocked yes)
			(layer "B.Fab")
			(hide yes)
			(effects
				(font
					(size 1 1)
					(thickness 0.15)
				)
				(justify mirror)
			)
		)
		(property "Manufacturer" "Bourns"
			(at 0 0 0)
			(unlocked yes)
			(layer "B.Fab")
			(hide yes)
			(effects
				(font
					(size 1 1)
					(thickness 0.15)
				)
				(justify mirror)
			)
		)
		(property "License" "Apache-2.0"
			(at 0 0 0)
			(unlocked yes)
			(layer "B.Fab")
			(hide yes)
			(effects
				(font
					(size 1 1)
					(thickness 0.15)
				)
				(justify mirror)
			)
		)
		(property "Author" "Antmicro"
			(at 0 0 0)
			(unlocked yes)
			(layer "B.Fab")
			(hide yes)
			(effects
				(font
					(size 1 1)
					(thickness 0.15)
				)
				(justify mirror)
			)
		)
		(property "Val" "6k8"
			(at 0 0 0)
			(unlocked yes)
			(layer "B.Fab")
			(hide yes)
			(effects
				(font
					(size 1 1)
					(thickness 0.15)
				)
				(justify mirror)
			)
		)
		(property "Tolerance" "1%"
			(at 0 0 0)
			(unlocked yes)
			(layer "B.Fab")
			(hide yes)
			(effects
				(font
					(size 1 1)
					(thickness 0.15)
				)
				(justify mirror)
			)
		)
		(sheetname "/Supply/")
		(sheetfile "supply.kicad_sch")
		(attr smd)
		(fp_rect
			(start -0.925 0.47)
			(end 0.925 -0.47)
			(stroke
				(width 0.05)
				(type default)
			)
			(fill no)
			(layer "B.CrtYd")
		)
		(fp_rect
			(start -0.5 0.25)
			(end 0.5 -0.25)
			(stroke
				(width 0.15)
				(type solid)
			)
			(fill no)
			(layer "B.Fab")
		)
		(fp_text user "License: Apache-2.0"
			(at -0.95 -5.169 180)
			(layer "B.Fab")
			(effects
				(font
					(size 0.7 0.7)
					(thickness 0.15)
				)
				(justify left bottom mirror)
			)
		)
		(fp_text user "Author: Antmicro"
			(at -0.95 -4.169 180)
			(layer "B.Fab")
			(effects
				(font
					(size 0.7 0.7)
					(thickness 0.15)
				)
				(justify left bottom mirror)
			)
		)
		(fp_text user "${REFERENCE}"
			(at -0.95 -3.168 180)
			(layer "B.Fab")
			(effects
				(font
					(size 0.7 0.7)
					(thickness 0.15)
				)
				(justify left bottom mirror)
			)
		)
		(pad "1" smd roundrect
			(at -0.48 0)
			(size 0.59 0.64)
			(layers "B.Cu" "B.Mask" "B.Paste")
			(roundrect_rratio 0.25)
			(net 355 "/Supply/FB_3V3")
			(pintype "passive")
		)
		(pad "2" smd roundrect
			(at 0.48 0)
			(size 0.59 0.64)
			(layers "B.Cu" "B.Mask" "B.Paste")
			(roundrect_rratio 0.25)
			(net 89 "/Supply/OUT_3V3")
			(pintype "passive")
		)
	)
	(footprint "antmicro-footprints:R_0402_1005Metric"
		(layer "B.Cu")
		(at 75.342962 135.0565)
		(descr "Resistor SMD 0402")
		(tags "resistor SMD 0402")
		(property "Reference" "R916"
			(at -3.815 0.34 0)
			(layer "B.SilkS")
			(effects
				(font
					(size 0.7 0.7)
					(thickness 0.15)
				)
				(justify right bottom mirror)
			)
		)
		(property "Value" "R_100k_0402"
			(at -1.011843 -1.772047 0)
			(layer "B.Fab")
			(effects
				(font
					(size 0.7 0.7)
					(thickness 0.15)
				)
				(justify right bottom mirror)
			)
		)
		(property "Datasheet" "https://www.bourns.com/docs/product-datasheets/cr.pdf"
			(at 0 0 0)
			(layer "B.Fab")
			(hide yes)
			(effects
				(font
					(size 1.27 1.27)
					(thickness 0.15)
				)
			)
		)
		(property "Manufacturer" "Bourns"
			(at 0 0 0)
			(unlocked yes)
			(layer "B.Fab")
			(hide yes)
			(effects
				(font
					(size 1 1)
					(thickness 0.15)
				)
				(justify mirror)
			)
		)
		(property "MPN" "CR0402-FX-1003GLF"
			(at 0 0 0)
			(unlocked yes)
			(layer "B.Fab")
			(hide yes)
			(effects
				(font
					(size 1 1)
					(thickness 0.15)
				)
				(justify mirror)
			)
		)
		(property "Val" "100k"
			(at 0 0 0)
			(unlocked yes)
			(layer "B.Fab")
			(hide yes)
			(effects
				(font
					(size 1 1)
					(thickness 0.15)
				)
				(justify mirror)
			)
		)
		(property "License" "Apache-2.0"
			(at 0 0 0)
			(unlocked yes)
			(layer "B.Fab")
			(hide yes)
			(effects
				(font
					(size 1 1)
					(thickness 0.15)
				)
				(justify mirror)
			)
		)
		(property "Author" "Antmicro"
			(at 0 0 0)
			(unlocked yes)
			(layer "B.Fab")
			(hide yes)
			(effects
				(font
					(size 1 1)
					(thickness 0.15)
				)
				(justify mirror)
			)
		)
		(property "Tolerance" "1%"
			(at 0 0 0)
			(unlocked yes)
			(layer "B.Fab")
			(hide yes)
			(effects
				(font
					(size 1 1)
					(thickness 0.15)
				)
				(justify mirror)
			)
		)
		(sheetname "/USB/")
		(sheetfile "usb.kicad_sch")
		(attr smd)
		(fp_rect
			(start -0.925 0.47)
			(end 0.925 -0.47)
			(stroke
				(width 0.05)
				(type default)
			)
			(fill no)
			(layer "B.CrtYd")
		)
		(fp_rect
			(start -0.5 0.25)
			(end 0.5 -0.25)
			(stroke
				(width 0.15)
				(type solid)
			)
			(fill no)
			(layer "B.Fab")
		)
		(fp_text user "License: Apache-2.0"
			(at -0.95 -5.169 180)
			(layer "B.Fab")
			(effects
				(font
					(size 0.7 0.7)
					(thickness 0.15)
				)
				(justify left bottom mirror)
			)
		)
		(fp_text user "${REFERENCE}"
			(at -0.95 -3.168 180)
			(layer "B.Fab")
			(effects
				(font
					(size 0.7 0.7)
					(thickness 0.15)
				)
				(justify left bottom mirror)
			)
		)
		(fp_text user "Author: Antmicro"
			(at -0.95 -4.169 180)
			(layer "B.Fab")
			(effects
				(font
					(size 0.7 0.7)
					(thickness 0.15)
				)
				(justify left bottom mirror)
			)
		)
		(pad "1" smd roundrect
			(at -0.48 0)
			(size 0.59 0.64)
			(layers "B.Cu" "B.Mask" "B.Paste")
			(roundrect_rratio 0.25)
			(net 26 "/USB/USBD_VBUS")
			(pintype "passive")
		)
		(pad "2" smd roundrect
			(at 0.48 0)
			(size 0.59 0.64)
			(layers "B.Cu" "B.Mask" "B.Paste")
			(roundrect_rratio 0.25)
			(net 29 "/USB/USBD_SVBUS")
			(pintype "passive")
		)
	)
	(footprint "antmicro-footprints:C_0805_2012Metric"
		(layer "B.Cu")
		(at 112.442962 137.5965 180)
		(descr "Capacitor SMD 0805")
		(tags "capacitor SMD 0805")
		(property "Reference" "C316"
			(at -1.355 -1.87 0)
			(layer "B.SilkS")
			(effects
				(font
					(size 0.7 0.7)
					(thickness 0.15)
				)
				(justify left bottom mirror)
			)
		)
		(property "Value" "C_22u_25V_0805"
			(at -2.055717 -1.963152 0)
			(layer "B.Fab")
			(effects
				(font
					(size 0.7 0.7)
					(thickness 0.15)
				)
				(justify left bottom mirror)
			)
		)
		(property "Datasheet" "https://product.samsungsem.com/mlcc/CL21A226MAYNNN.do"
			(at 0 0 180)
			(layer "B.Fab")
			(hide yes)
			(effects
				(font
					(size 1.27 1.27)
					(thickness 0.15)
				)
			)
		)
		(property "Manufacturer" "Samsung Electro-Mechanics"
			(at 0 0 180)
			(unlocked yes)
			(layer "B.Fab")
			(hide yes)
			(effects
				(font
					(size 1 1)
					(thickness 0.15)
				)
				(justify mirror)
			)
		)
		(property "MPN" "CL21A226MAYNNNE"
			(at 0 0 180)
			(unlocked yes)
			(layer "B.Fab")
			(hide yes)
			(effects
				(font
					(size 1 1)
					(thickness 0.15)
				)
				(justify mirror)
			)
		)
		(property "Val" "22u"
			(at 0 0 180)
			(unlocked yes)
			(layer "B.Fab")
			(hide yes)
			(effects
				(font
					(size 1 1)
					(thickness 0.15)
				)
				(justify mirror)
			)
		)
		(property "License" "Apache-2.0"
			(at 0 0 180)
			(unlocked yes)
			(layer "B.Fab")
			(hide yes)
			(effects
				(font
					(size 1 1)
					(thickness 0.15)
				)
				(justify mirror)
			)
		)
		(property "Author" "Antmicro"
			(at 0 0 180)
			(unlocked yes)
			(layer "B.Fab")
			(hide yes)
			(effects
				(font
					(size 1 1)
					(thickness 0.15)
				)
				(justify mirror)
			)
		)
		(property "Voltage" "25V"
			(at 0 0 180)
			(unlocked yes)
			(layer "B.Fab")
			(hide yes)
			(effects
				(font
					(size 1 1)
					(thickness 0.15)
				)
				(justify mirror)
			)
		)
		(property "Dielectric" "X5R"
			(at 0 0 180)
			(unlocked yes)
			(layer "B.Fab")
			(hide yes)
			(effects
				(font
					(size 1 1)
					(thickness 0.15)
				)
				(justify mirror)
			)
		)
		(property "Public" "False"
			(at 0 0 180)
			(unlocked yes)
			(layer "B.Fab")
			(hide yes)
			(effects
				(font
					(size 1 1)
					(thickness 0.15)
				)
				(justify mirror)
			)
		)
		(sheetname "/Supply/")
		(sheetfile "supply.kicad_sch")
		(attr smd)
		(fp_line
			(start -0.3 0.7)
			(end 0.3 0.7)
			(stroke
				(width 0.15)
				(type solid)
			)
			(layer "B.SilkS")
		)
		(fp_line
			(start -0.3 -0.7)
			(end 0.3 -0.7)
			(stroke
				(width 0.15)
				(type solid)
			)
			(layer "B.SilkS")
		)
		(fp_rect
			(start 1.95 0.9)
			(end -1.95 -0.9)
			(stroke
				(width 0.05)
				(type default)
			)
			(fill no)
			(layer "B.CrtYd")
		)
		(fp_rect
			(start -0.95 0.675)
			(end 0.95 -0.675)
			(stroke
				(width 0.15)
				(type solid)
			)
			(fill no)
			(layer "B.Fab")
		)
		(fp_text user "${REFERENCE}"
			(at -1.9 -3.947 0)
			(layer "B.Fab")
			(effects
				(font
					(size 0.7 0.7)
					(thickness 0.15)
				)
				(justify left bottom mirror)
			)
		)
		(fp_text user "License: Apache-2.0"
			(at -1.9 -4.947 0)
			(layer "B.Fab")
			(effects
				(font
					(size 0.7 0.7)
					(thickness 0.15)
				)
				(justify left bottom mirror)
			)
		)
		(fp_text user "Author: Antmicro"
			(at -1.9 -5.947 0)
			(layer "B.Fab")
			(effects
				(font
					(size 0.7 0.7)
					(thickness 0.15)
				)
				(justify left bottom mirror)
			)
		)
		(pad "1" smd roundrect
			(at -1.1 0 180)
			(size 1.2 1.3)
			(layers "B.Cu" "B.Mask" "B.Paste")
			(roundrect_rratio 0.25)
			(net 78 "/Supply/OUT_M2")
			(pintype "passive")
		)
		(pad "2" smd roundrect
			(at 1.1 0 180)
			(size 1.2 1.3)
			(layers "B.Cu" "B.Mask" "B.Paste")
			(roundrect_rratio 0.25)
			(net 3 "GND")
			(pintype "passive")
		)
	)
	(footprint "antmicro-footprints:R_0402_1005Metric"
		(layer "B.Cu")
		(at 65.242962 178.1665)
		(descr "Resistor SMD 0402")
		(tags "resistor SMD 0402")
		(property "Reference" "R807"
			(at -1.492962 1.28 0)
			(layer "B.SilkS")
			(effects
				(font
					(size 0.7 0.7)
					(thickness 0.15)
				)
				(justify right bottom mirror)
			)
		)
		(property "Value" "R_2k2_0402"
			(at -1.011843 -1.772047 0)
			(layer "B.Fab")
			(effects
				(font
					(size 0.7 0.7)
					(thickness 0.15)
				)
				(justify right bottom mirror)
			)
		)
		(property "Datasheet" "https://www.bourns.com/docs/product-datasheets/cr.pdf"
			(at 0 0 0)
			(layer "B.Fab")
			(hide yes)
			(effects
				(font
					(size 1.27 1.27)
					(thickness 0.15)
				)
			)
		)
		(property "Description" "SMD Chip Resistor, 2.2 kohm, ± 1%, 62.5 mW, 0402 [1005 Metric], Thick Film, General Purpose"
			(at 0 0 0)
			(layer "B.Fab")
			(hide yes)
			(effects
				(font
					(size 1.27 1.27)
					(thickness 0.15)
				)
			)
		)
		(property "MPN" "CR0402-FX-2201GLF"
			(at 0 0 0)
			(unlocked yes)
			(layer "B.Fab")
			(hide yes)
			(effects
				(font
					(size 1 1)
					(thickness 0.15)
				)
				(justify mirror)
			)
		)
		(property "Manufacturer" "Bourns"
			(at 0 0 0)
			(unlocked yes)
			(layer "B.Fab")
			(hide yes)
			(effects
				(font
					(size 1 1)
					(thickness 0.15)
				)
				(justify mirror)
			)
		)
		(property "License" "Apache-2.0"
			(at 0 0 0)
			(unlocked yes)
			(layer "B.Fab")
			(hide yes)
			(effects
				(font
					(size 1 1)
					(thickness 0.15)
				)
				(justify mirror)
			)
		)
		(property "Author" "Antmicro"
			(at 0 0 0)
			(unlocked yes)
			(layer "B.Fab")
			(hide yes)
			(effects
				(font
					(size 1 1)
					(thickness 0.15)
				)
				(justify mirror)
			)
		)
		(property "Val" "2k2"
			(at 0 0 0)
			(unlocked yes)
			(layer "B.Fab")
			(hide yes)
			(effects
				(font
					(size 1 1)
					(thickness 0.15)
				)
				(justify mirror)
			)
		)
		(property "Tolerance" "1%"
			(at 0 0 0)
			(unlocked yes)
			(layer "B.Fab")
			(hide yes)
			(effects
				(font
					(size 1 1)
					(thickness 0.15)
				)
				(justify mirror)
			)
		)
		(sheetname "/Peripherals/")
		(sheetfile "peripherals.kicad_sch")
		(attr smd)
		(fp_rect
			(start -0.925 0.47)
			(end 0.925 -0.47)
			(stroke
				(width 0.05)
				(type default)
			)
			(fill no)
			(layer "B.CrtYd")
		)
		(fp_rect
			(start -0.5 0.25)
			(end 0.5 -0.25)
			(stroke
				(width 0.15)
				(type solid)
			)
			(fill no)
			(layer "B.Fab")
		)
		(fp_text user "${REFERENCE}"
			(at -0.95 -3.168 180)
			(layer "B.Fab")
			(effects
				(font
					(size 0.7 0.7)
					(thickness 0.15)
				)
				(justify left bottom mirror)
			)
		)
		(fp_text user "Author: Antmicro"
			(at -0.95 -4.169 180)
			(layer "B.Fab")
			(effects
				(font
					(size 0.7 0.7)
					(thickness 0.15)
				)
				(justify left bottom mirror)
			)
		)
		(fp_text user "License: Apache-2.0"
			(at -0.95 -5.169 180)
			(layer "B.Fab")
			(effects
				(font
					(size 0.7 0.7)
					(thickness 0.15)
				)
				(justify left bottom mirror)
			)
		)
		(pad "1" smd roundrect
			(at -0.48 0)
			(size 0.59 0.64)
			(layers "B.Cu" "B.Mask" "B.Paste")
			(roundrect_rratio 0.25)
			(net 109 "Net-(C816-Pad2)")
			(pintype "passive")
		)
		(pad "2" smd roundrect
			(at 0.48 0)
			(size 0.59 0.64)
			(layers "B.Cu" "B.Mask" "B.Paste")
			(roundrect_rratio 0.25)
			(net 102 "Net-(C812-Pad2)")
			(pintype "passive")
		)
	)
	(footprint "antmicro-footprints:C_0805_2012Metric"
		(layer "B.Cu")
		(at 54.842962 171.3165 -90)
		(descr "Capacitor SMD 0805")
		(tags "capacitor SMD 0805")
		(property "Reference" "C408"
			(at 1.76 -0.4 90)
			(layer "B.SilkS")
			(effects
				(font
					(size 0.7 0.7)
					(thickness 0.15)
				)
				(justify left bottom mirror)
			)
		)
		(property "Value" "C_22u_25V_0805"
			(at -2.055717 -1.963152 90)
			(layer "B.Fab")
			(effects
				(font
					(size 0.7 0.7)
					(thickness 0.15)
				)
				(justify left bottom mirror)
			)
		)
		(property "Datasheet" "https://product.samsungsem.com/mlcc/CL21A226MAYNNN.do"
			(at 0 0 270)
			(layer "B.Fab")
			(hide yes)
			(effects
				(font
					(size 1.27 1.27)
					(thickness 0.15)
				)
			)
		)
		(property "Manufacturer" "Samsung Electro-Mechanics"
			(at 0 0 270)
			(unlocked yes)
			(layer "B.Fab")
			(hide yes)
			(effects
				(font
					(size 1 1)
					(thickness 0.15)
				)
				(justify mirror)
			)
		)
		(property "MPN" "CL21A226MAYNNNE"
			(at 0 0 270)
			(unlocked yes)
			(layer "B.Fab")
			(hide yes)
			(effects
				(font
					(size 1 1)
					(thickness 0.15)
				)
				(justify mirror)
			)
		)
		(property "Val" "22u"
			(at 0 0 270)
			(unlocked yes)
			(layer "B.Fab")
			(hide yes)
			(effects
				(font
					(size 1 1)
					(thickness 0.15)
				)
				(justify mirror)
			)
		)
		(property "License" "Apache-2.0"
			(at 0 0 270)
			(unlocked yes)
			(layer "B.Fab")
			(hide yes)
			(effects
				(font
					(size 1 1)
					(thickness 0.15)
				)
				(justify mirror)
			)
		)
		(property "Author" "Antmicro"
			(at 0 0 270)
			(unlocked yes)
			(layer "B.Fab")
			(hide yes)
			(effects
				(font
					(size 1 1)
					(thickness 0.15)
				)
				(justify mirror)
			)
		)
		(property "Voltage" "25V"
			(at 0 0 270)
			(unlocked yes)
			(layer "B.Fab")
			(hide yes)
			(effects
				(font
					(size 1 1)
					(thickness 0.15)
				)
				(justify mirror)
			)
		)
		(property "Dielectric" "X5R"
			(at 0 0 270)
			(unlocked yes)
			(layer "B.Fab")
			(hide yes)
			(effects
				(font
					(size 1 1)
					(thickness 0.15)
				)
				(justify mirror)
			)
		)
		(property "Public" "False"
			(at 0 0 270)
			(unlocked yes)
			(layer "B.Fab")
			(hide yes)
			(effects
				(font
					(size 1 1)
					(thickness 0.15)
				)
				(justify mirror)
			)
		)
		(sheetname "/Ethernet/")
		(sheetfile "ethernet.kicad_sch")
		(attr smd)
		(fp_line
			(start -0.3 0.7)
			(end 0.3 0.7)
			(stroke
				(width 0.15)
				(type solid)
			)
			(layer "B.SilkS")
		)
		(fp_line
			(start -0.3 -0.7)
			(end 0.3 -0.7)
			(stroke
				(width 0.15)
				(type solid)
			)
			(layer "B.SilkS")
		)
		(fp_rect
			(start 1.95 0.9)
			(end -1.95 -0.9)
			(stroke
				(width 0.05)
				(type default)
			)
			(fill no)
			(layer "B.CrtYd")
		)
		(fp_rect
			(start -0.95 0.675)
			(end 0.95 -0.675)
			(stroke
				(width 0.15)
				(type solid)
			)
			(fill no)
			(layer "B.Fab")
		)
		(fp_text user "${REFERENCE}"
			(at -1.9 -3.947 90)
			(layer "B.Fab")
			(effects
				(font
					(size 0.7 0.7)
					(thickness 0.15)
				)
				(justify left bottom mirror)
			)
		)
		(fp_text user "License: Apache-2.0"
			(at -1.9 -4.947 90)
			(layer "B.Fab")
			(effects
				(font
					(size 0.7 0.7)
					(thickness 0.15)
				)
				(justify left bottom mirror)
			)
		)
		(fp_text user "Author: Antmicro"
			(at -1.9 -5.947 90)
			(layer "B.Fab")
			(effects
				(font
					(size 0.7 0.7)
					(thickness 0.15)
				)
				(justify left bottom mirror)
			)
		)
		(pad "1" smd roundrect
			(at -1.1 0 270)
			(size 1.2 1.3)
			(layers "B.Cu" "B.Mask" "B.Paste")
			(roundrect_rratio 0.25)
			(net 47 "/Ethernet/POE_12V")
			(pintype "passive")
		)
		(pad "2" smd roundrect
			(at 1.1 0 270)
			(size 1.2 1.3)
			(layers "B.Cu" "B.Mask" "B.Paste")
			(roundrect_rratio 0.25)
			(net 3 "GND")
			(pintype "passive")
		)
	)
	(footprint "antmicro-footprints:TP_SMD_0.75mm"
		(layer "B.Cu")
		(at 80.65 146.9)
		(property "Reference" "TP203"
			(at 0.335 0.1 0)
			(layer "B.SilkS")
			(effects
				(font
					(size 0.7 0.7)
					(thickness 0.15)
				)
				(justify right bottom mirror)
			)
		)
		(property "Value" "TP_0.75mm_SMD"
			(at 0 -1.2 0)
			(layer "B.Fab")
			(effects
				(font
					(size 0.7 0.7)
					(thickness 0.15)
				)
				(justify right bottom mirror)
			)
		)
		(property "Author" "Antmicro"
			(at 0 0 0)
			(unlocked yes)
			(layer "B.Fab")
			(hide yes)
			(effects
				(font
					(size 1 1)
					(thickness 0.15)
				)
				(justify mirror)
			)
		)
		(property "License" "Apache-2.0"
			(at 0 0 0)
			(unlocked yes)
			(layer "B.Fab")
			(hide yes)
			(effects
				(font
					(size 1 1)
					(thickness 0.15)
				)
				(justify mirror)
			)
		)
		(property "MPN" ""
			(at 0 0 0)
			(unlocked yes)
			(layer "B.Fab")
			(hide yes)
			(effects
				(font
					(size 1 1)
					(thickness 0.15)
				)
				(justify mirror)
			)
		)
		(property "Manufacturer" ""
			(at 0 0 0)
			(unlocked yes)
			(layer "B.Fab")
			(hide yes)
			(effects
				(font
					(size 1 1)
					(thickness 0.15)
				)
				(justify mirror)
			)
		)
		(sheetname "/Compute module/")
		(sheetfile "compute-module.kicad_sch")
		(attr exclude_from_pos_files exclude_from_bom)
		(fp_circle
			(center 0 0)
			(end 0.475 0)
			(stroke
				(width 0.05)
				(type default)
			)
			(fill no)
			(layer "B.CrtYd")
		)
		(fp_text user "Author: Antmicro"
			(at -0.4 -3.901 180)
			(layer "B.Fab")
			(effects
				(font
					(size 0.7 0.7)
					(thickness 0.15)
				)
				(justify left bottom mirror)
			)
		)
		(fp_text user "License: Apache-2.0"
			(at -0.4 -5.101 180)
			(layer "B.Fab")
			(effects
				(font
					(size 0.7 0.7)
					(thickness 0.15)
				)
				(justify left bottom mirror)
			)
		)
		(fp_text user "${REFERENCE}"
			(at -0.4 -2.7 180)
			(layer "B.Fab")
			(effects
				(font
					(size 0.7 0.7)
					(thickness 0.15)
				)
				(justify left bottom mirror)
			)
		)
		(pad "1" smd circle
			(at 0 0)
			(size 0.75 0.75)
			(layers "B.Cu" "B.Mask")
			(net 213 "/Compute module/SYNC_IN")
			(pinfunction "1")
			(pintype "passive")
		)
	)
	(footprint "antmicro-footprints:R_0603_1608Metric"
		(layer "B.Cu")
		(at 47.217962 156.0165 90)
		(descr "Resistor SMD 0603")
		(tags "resistor SMD 0603")
		(property "Reference" "R308"
			(at 1.28 0.34 90)
			(layer "B.SilkS")
			(effects
				(font
					(size 0.7 0.7)
					(thickness 0.15)
				)
				(justify right bottom mirror)
			)
		)
		(property "Value" "R_0R_22.4A_0603"
			(at 0 -1.6 90)
			(layer "B.Fab")
			(effects
				(font
					(size 0.7 0.7)
					(thickness 0.15)
				)
				(justify right bottom mirror)
			)
		)
		(property "Datasheet" "https://fscdn.rohm.com/en/products/databook/datasheet/passive/resistor/chip_resistor/pmr-jpw-e.pdf"
			(at 0 0 90)
			(layer "B.Fab")
			(hide yes)
			(effects
				(font
					(size 1.27 1.27)
					(thickness 0.15)
				)
			)
		)
		(property "Manufacturer" "ROHM Semiconductor"
			(at 0 0 90)
			(unlocked yes)
			(layer "B.Fab")
			(hide yes)
			(effects
				(font
					(size 1 1)
					(thickness 0.15)
				)
				(justify mirror)
			)
		)
		(property "MPN" "PMR03EZPJ000"
			(at 0 0 90)
			(unlocked yes)
			(layer "B.Fab")
			(hide yes)
			(effects
				(font
					(size 1 1)
					(thickness 0.15)
				)
				(justify mirror)
			)
		)
		(property "Val" "0R"
			(at 0 0 90)
			(unlocked yes)
			(layer "B.Fab")
			(hide yes)
			(effects
				(font
					(size 1 1)
					(thickness 0.15)
				)
				(justify mirror)
			)
		)
		(property "Author" "Antmicro"
			(at 0 0 90)
			(unlocked yes)
			(layer "B.Fab")
			(hide yes)
			(effects
				(font
					(size 1 1)
					(thickness 0.15)
				)
				(justify mirror)
			)
		)
		(property "License" "Apache-2.0"
			(at 0 0 90)
			(unlocked yes)
			(layer "B.Fab")
			(hide yes)
			(effects
				(font
					(size 1 1)
					(thickness 0.15)
				)
				(justify mirror)
			)
		)
		(property "Max. Curr." "22.4A"
			(at 0 0 90)
			(unlocked yes)
			(layer "B.Fab")
			(hide yes)
			(effects
				(font
					(size 1 1)
					(thickness 0.15)
				)
				(justify mirror)
			)
		)
		(property "Tolerance" "template_tolerance"
			(at 0 0 90)
			(unlocked yes)
			(layer "B.Fab")
			(hide yes)
			(effects
				(font
					(size 1 1)
					(thickness 0.15)
				)
				(justify mirror)
			)
		)
		(sheetname "/Supply/")
		(sheetfile "supply.kicad_sch")
		(attr smd exclude_from_pos_files exclude_from_bom dnp)
		(fp_line
			(start -0.15 -0.4)
			(end 0.15 -0.4)
			(stroke
				(width 0.15)
				(type solid)
			)
			(layer "B.SilkS")
		)
		(fp_line
			(start -0.15 0.4)
			(end 0.15 0.4)
			(stroke
				(width 0.15)
				(type solid)
			)
			(layer "B.SilkS")
		)
		(fp_rect
			(start -1.25 0.65)
			(end 1.25 -0.65)
			(stroke
				(width 0.05)
				(type solid)
			)
			(fill no)
			(layer "B.CrtYd")
		)
		(fp_rect
			(start -0.8 0.4)
			(end 0.8 -0.4)
			(stroke
				(width 0.15)
				(type solid)
			)
			(fill no)
			(layer "B.Fab")
		)
		(fp_text user "Author: Antmicro"
			(at -1.25 -4.9 270)
			(layer "B.Fab")
			(effects
				(font
					(size 0.7 0.7)
					(thickness 0.15)
				)
				(justify left bottom mirror)
			)
		)
		(fp_text user "License: Apache-2.0"
			(at -1.25 -5.9 270)
			(layer "B.Fab")
			(effects
				(font
					(size 0.7 0.7)
					(thickness 0.15)
				)
				(justify left bottom mirror)
			)
		)
		(fp_text user "${REFERENCE}"
			(at -1.25 -3.898 270)
			(layer "B.Fab")
			(effects
				(font
					(size 0.7 0.7)
					(thickness 0.15)
				)
				(justify left bottom mirror)
			)
		)
		(pad "1" smd roundrect
			(at -0.7 0 90)
			(size 0.8 1)
			(layers "B.Cu" "B.Mask" "B.Paste")
			(roundrect_rratio 0.2)
			(net 21 "/Supply/VCC_IN")
			(pintype "passive")
		)
		(pad "2" smd roundrect
			(at 0.7 0 90)
			(size 0.8 1)
			(layers "B.Cu" "B.Mask" "B.Paste")
			(roundrect_rratio 0.2)
			(net 43 "VCC")
			(pintype "passive")
		)
	)
	(footprint "antmicro-footprints:C_0402_1005Metric"
		(layer "B.Cu")
		(at 54.742962 158.4165)
		(descr "Capacitor SMD 0402")
		(tags "capacitor SMD 0402")
		(property "Reference" "C311"
			(at -1.425 1.95 0)
			(layer "B.SilkS")
			(effects
				(font
					(size 0.7 0.7)
					(thickness 0.15)
				)
				(justify right bottom mirror)
			)
		)
		(property "Value" "C_1u_0402"
			(at -1.022927 -2.155213 0)
			(layer "B.Fab")
			(effects
				(font
					(size 0.7 0.7)
					(thickness 0.15)
				)
				(justify right bottom mirror)
			)
		)
		(property "Datasheet" "https://product.tdk.com/en/search/capacitor/ceramic/mlcc/info?part_no=C1005X6S1A105K050BC"
			(at 0 0 0)
			(layer "B.Fab")
			(hide yes)
			(effects
				(font
					(size 1.27 1.27)
					(thickness 0.15)
				)
			)
		)
		(property "Manufacturer" "TDK"
			(at 0 0 0)
			(unlocked yes)
			(layer "B.Fab")
			(hide yes)
			(effects
				(font
					(size 1 1)
					(thickness 0.15)
				)
				(justify mirror)
			)
		)
		(property "MPN" "C1005X6S1A105K050BC"
			(at 0 0 0)
			(unlocked yes)
			(layer "B.Fab")
			(hide yes)
			(effects
				(font
					(size 1 1)
					(thickness 0.15)
				)
				(justify mirror)
			)
		)
		(property "Val" "1u"
			(at 0 0 0)
			(unlocked yes)
			(layer "B.Fab")
			(hide yes)
			(effects
				(font
					(size 1 1)
					(thickness 0.15)
				)
				(justify mirror)
			)
		)
		(property "License" "Apache-2.0"
			(at 0 0 0)
			(unlocked yes)
			(layer "B.Fab")
			(hide yes)
			(effects
				(font
					(size 1 1)
					(thickness 0.15)
				)
				(justify mirror)
			)
		)
		(property "Author" "Antmicro"
			(at 0 0 0)
			(unlocked yes)
			(layer "B.Fab")
			(hide yes)
			(effects
				(font
					(size 1 1)
					(thickness 0.15)
				)
				(justify mirror)
			)
		)
		(property "Voltage" ""
			(at 0 0 0)
			(unlocked yes)
			(layer "B.Fab")
			(hide yes)
			(effects
				(font
					(size 1 1)
					(thickness 0.15)
				)
				(justify mirror)
			)
		)
		(property "Dielectric" ""
			(at 0 0 0)
			(unlocked yes)
			(layer "B.Fab")
			(hide yes)
			(effects
				(font
					(size 1 1)
					(thickness 0.15)
				)
				(justify mirror)
			)
		)
		(sheetname "/Supply/")
		(sheetfile "supply.kicad_sch")
		(attr smd)
		(fp_rect
			(start -0.925 0.47)
			(end 0.925 -0.47)
			(stroke
				(width 0.05)
				(type default)
			)
			(fill no)
			(layer "B.CrtYd")
		)
		(fp_line
			(start -0.494 -0.248)
			(end -0.494 0.25)
			(stroke
				(width 0.15)
				(type solid)
			)
			(layer "B.Fab")
		)
		(fp_line
			(start -0.494 0.25)
			(end 0.504 0.25)
			(stroke
				(width 0.15)
				(type solid)
			)
			(layer "B.Fab")
		)
		(fp_line
			(start 0.504 -0.248)
			(end -0.494 -0.248)
			(stroke
				(width 0.15)
				(type solid)
			)
			(layer "B.Fab")
		)
		(fp_line
			(start 0.504 0.25)
			(end 0.504 -0.248)
			(stroke
				(width 0.15)
				(type solid)
			)
			(layer "B.Fab")
		)
		(fp_text user "Author: Antmicro"
			(at -0.939 -3.399 180)
			(layer "B.Fab")
			(effects
				(font
					(size 0.7 0.7)
					(thickness 0.15)
				)
				(justify left bottom mirror)
			)
		)
		(fp_text user "License: Apache-2.0"
			(at -0.939 -5.799 180)
			(layer "B.Fab")
			(effects
				(font
					(size 0.7 0.7)
					(thickness 0.15)
				)
				(justify left bottom mirror)
			)
		)
		(fp_text user "${REFERENCE}"
			(at -0.939 -4.599 180)
			(layer "B.Fab")
			(effects
				(font
					(size 0.7 0.7)
					(thickness 0.15)
				)
				(justify left bottom mirror)
			)
		)
		(pad "1" smd roundrect
			(at -0.48 0)
			(size 0.59 0.64)
			(layers "B.Cu" "B.Mask" "B.Paste")
			(roundrect_rratio 0.25)
			(net 3 "GND")
			(pintype "passive")
		)
		(pad "2" smd roundrect
			(at 0.48 0)
			(size 0.59 0.64)
			(layers "B.Cu" "B.Mask" "B.Paste")
			(roundrect_rratio 0.25)
			(net 66 "/Supply/VCC_5V")
			(pintype "passive")
		)
	)
	(footprint "antmicro-footprints:C_0402_1005Metric"
		(layer "B.Cu")
		(at 99.417962 176.9665 90)
		(descr "Capacitor SMD 0402")
		(tags "capacitor SMD 0402")
		(property "Reference" "C701"
			(at -2.76 2.33 90)
			(layer "B.SilkS")
			(effects
				(font
					(size 0.7 0.7)
					(thickness 0.15)
				)
				(justify right bottom mirror)
			)
		)
		(property "Value" "C_10u_0402"
			(at -1.022927 -2.155213 90)
			(layer "B.Fab")
			(effects
				(font
					(size 0.7 0.7)
					(thickness 0.15)
				)
				(justify right bottom mirror)
			)
		)
		(property "Datasheet" "https://www.yageo.com/en/Chart/Download/pdf/CC0402MRX5R5BB106"
			(at 0 0 90)
			(layer "B.Fab")
			(hide yes)
			(effects
				(font
					(size 1.27 1.27)
					(thickness 0.15)
				)
			)
		)
		(property "MPN" "CC0402MRX5R5BB106"
			(at 0 0 90)
			(unlocked yes)
			(layer "B.Fab")
			(hide yes)
			(effects
				(font
					(size 1 1)
					(thickness 0.15)
				)
				(justify mirror)
			)
		)
		(property "Manufacturer" "YAGEO"
			(at 0 0 90)
			(unlocked yes)
			(layer "B.Fab")
			(hide yes)
			(effects
				(font
					(size 1 1)
					(thickness 0.15)
				)
				(justify mirror)
			)
		)
		(property "License" "Apache-2.0"
			(at 0 0 90)
			(unlocked yes)
			(layer "B.Fab")
			(hide yes)
			(effects
				(font
					(size 1 1)
					(thickness 0.15)
				)
				(justify mirror)
			)
		)
		(property "Author" "Antmicro"
			(at 0 0 90)
			(unlocked yes)
			(layer "B.Fab")
			(hide yes)
			(effects
				(font
					(size 1 1)
					(thickness 0.15)
				)
				(justify mirror)
			)
		)
		(property "Val" "10u"
			(at 0 0 90)
			(unlocked yes)
			(layer "B.Fab")
			(hide yes)
			(effects
				(font
					(size 1 1)
					(thickness 0.15)
				)
				(justify mirror)
			)
		)
		(property "Voltage" ""
			(at 0 0 90)
			(unlocked yes)
			(layer "B.Fab")
			(hide yes)
			(effects
				(font
					(size 1 1)
					(thickness 0.15)
				)
				(justify mirror)
			)
		)
		(property "Dielectric" ""
			(at 0 0 90)
			(unlocked yes)
			(layer "B.Fab")
			(hide yes)
			(effects
				(font
					(size 1 1)
					(thickness 0.15)
				)
				(justify mirror)
			)
		)
		(sheetname "/Display/")
		(sheetfile "display.kicad_sch")
		(attr smd)
		(fp_rect
			(start -0.925 0.47)
			(end 0.925 -0.47)
			(stroke
				(width 0.05)
				(type default)
			)
			(fill no)
			(layer "B.CrtYd")
		)
		(fp_line
			(start 0.504 -0.248)
			(end -0.494 -0.248)
			(stroke
				(width 0.15)
				(type solid)
			)
			(layer "B.Fab")
		)
		(fp_line
			(start -0.494 -0.248)
			(end -0.494 0.25)
			(stroke
				(width 0.15)
				(type solid)
			)
			(layer "B.Fab")
		)
		(fp_line
			(start 0.504 0.25)
			(end 0.504 -0.248)
			(stroke
				(width 0.15)
				(type solid)
			)
			(layer "B.Fab")
		)
		(fp_line
			(start -0.494 0.25)
			(end 0.504 0.25)
			(stroke
				(width 0.15)
				(type solid)
			)
			(layer "B.Fab")
		)
		(fp_text user "${REFERENCE}"
			(at -0.939 -4.599 270)
			(layer "B.Fab")
			(effects
				(font
					(size 0.7 0.7)
					(thickness 0.15)
				)
				(justify left bottom mirror)
			)
		)
		(fp_text user "Author: Antmicro"
			(at -0.939 -3.399 270)
			(layer "B.Fab")
			(effects
				(font
					(size 0.7 0.7)
					(thickness 0.15)
				)
				(justify left bottom mirror)
			)
		)
		(fp_text user "License: Apache-2.0"
			(at -0.939 -5.799 270)
			(layer "B.Fab")
			(effects
				(font
					(size 0.7 0.7)
					(thickness 0.15)
				)
				(justify left bottom mirror)
			)
		)
		(pad "1" smd roundrect
			(at -0.48 0 90)
			(size 0.59 0.64)
			(layers "B.Cu" "B.Mask" "B.Paste")
			(roundrect_rratio 0.25)
			(net 3 "GND")
			(pintype "passive")
		)
		(pad "2" smd roundrect
			(at 0.48 0 90)
			(size 0.59 0.64)
			(layers "B.Cu" "B.Mask" "B.Paste")
			(roundrect_rratio 0.25)
			(net 464 "Net-(D709-C)")
			(pintype "passive")
		)
	)
	(footprint "antmicro-footprints:R_0402_1005Metric"
		(layer "B.Cu")
		(at 86 116.95 -90)
		(descr "Resistor SMD 0402")
		(tags "resistor SMD 0402")
		(property "Reference" "R933"
			(at -3.78 -0.4 90)
			(layer "B.SilkS")
			(effects
				(font
					(size 0.7 0.7)
					(thickness 0.15)
				)
				(justify left bottom mirror)
			)
		)
		(property "Value" "R_10k_0402"
			(at -1.011843 -1.772047 90)
			(layer "B.Fab")
			(effects
				(font
					(size 0.7 0.7)
					(thickness 0.15)
				)
				(justify left bottom mirror)
			)
		)
		(property "Datasheet" "https://www.bourns.com/docs/product-datasheets/cr.pdf"
			(at 0 0 270)
			(layer "B.Fab")
			(hide yes)
			(effects
				(font
					(size 1.27 1.27)
					(thickness 0.15)
				)
			)
		)
		(property "Manufacturer" "Bourns"
			(at 0 0 270)
			(unlocked yes)
			(layer "B.Fab")
			(hide yes)
			(effects
				(font
					(size 1 1)
					(thickness 0.15)
				)
				(justify mirror)
			)
		)
		(property "MPN" "CR0402-FX-1002GLF"
			(at 0 0 270)
			(unlocked yes)
			(layer "B.Fab")
			(hide yes)
			(effects
				(font
					(size 1 1)
					(thickness 0.15)
				)
				(justify mirror)
			)
		)
		(property "Val" "10k"
			(at 0 0 270)
			(unlocked yes)
			(layer "B.Fab")
			(hide yes)
			(effects
				(font
					(size 1 1)
					(thickness 0.15)
				)
				(justify mirror)
			)
		)
		(property "License" "Apache-2.0"
			(at 0 0 270)
			(unlocked yes)
			(layer "B.Fab")
			(hide yes)
			(effects
				(font
					(size 1 1)
					(thickness 0.15)
				)
				(justify mirror)
			)
		)
		(property "Author" "Antmicro"
			(at 0 0 270)
			(unlocked yes)
			(layer "B.Fab")
			(hide yes)
			(effects
				(font
					(size 1 1)
					(thickness 0.15)
				)
				(justify mirror)
			)
		)
		(property "Tolerance" "1%"
			(at 0 0 270)
			(unlocked yes)
			(layer "B.Fab")
			(hide yes)
			(effects
				(font
					(size 1 1)
					(thickness 0.15)
				)
				(justify mirror)
			)
		)
		(sheetname "/USB/")
		(sheetfile "usb.kicad_sch")
		(attr smd)
		(fp_rect
			(start -0.925 0.47)
			(end 0.925 -0.47)
			(stroke
				(width 0.05)
				(type default)
			)
			(fill no)
			(layer "B.CrtYd")
		)
		(fp_rect
			(start -0.5 0.25)
			(end 0.5 -0.25)
			(stroke
				(width 0.15)
				(type solid)
			)
			(fill no)
			(layer "B.Fab")
		)
		(fp_text user "Author: Antmicro"
			(at -0.95 -4.169 90)
			(layer "B.Fab")
			(effects
				(font
					(size 0.7 0.7)
					(thickness 0.15)
				)
				(justify left bottom mirror)
			)
		)
		(fp_text user "${REFERENCE}"
			(at -0.95 -3.168 90)
			(layer "B.Fab")
			(effects
				(font
					(size 0.7 0.7)
					(thickness 0.15)
				)
				(justify left bottom mirror)
			)
		)
		(fp_text user "License: Apache-2.0"
			(at -0.95 -5.169 90)
			(layer "B.Fab")
			(effects
				(font
					(size 0.7 0.7)
					(thickness 0.15)
				)
				(justify left bottom mirror)
			)
		)
		(pad "1" smd roundrect
			(at -0.48 0 270)
			(size 0.59 0.64)
			(layers "B.Cu" "B.Mask" "B.Paste")
			(roundrect_rratio 0.25)
			(net 26 "/USB/USBD_VBUS")
			(pintype "passive")
		)
		(pad "2" smd roundrect
			(at 0.48 0 270)
			(size 0.59 0.64)
			(layers "B.Cu" "B.Mask" "B.Paste")
			(roundrect_rratio 0.25)
			(net 499 "Net-(Q906-G)")
			(pintype "passive")
		)
	)
	(footprint "antmicro-footprints:R_0402_1005Metric"
		(layer "B.Cu")
		(at 79.667962 146.4915 -90)
		(descr "Resistor SMD 0402")
		(tags "resistor SMD 0402")
		(property "Reference" "R412"
			(at -3.795 -0.42 90)
			(layer "B.SilkS")
			(effects
				(font
					(size 0.7 0.7)
					(thickness 0.15)
				)
				(justify left bottom mirror)
			)
		)
		(property "Value" "R_200R_0402"
			(at -1.011843 -1.772047 90)
			(layer "B.Fab")
			(effects
				(font
					(size 0.7 0.7)
					(thickness 0.15)
				)
				(justify left bottom mirror)
			)
		)
		(property "Datasheet" "https://www.bourns.com/docs/product-datasheets/cr.pdf"
			(at 0 0 270)
			(layer "B.Fab")
			(hide yes)
			(effects
				(font
					(size 1.27 1.27)
					(thickness 0.15)
				)
			)
		)
		(property "Manufacturer" "Bourns"
			(at 0 0 270)
			(unlocked yes)
			(layer "B.Fab")
			(hide yes)
			(effects
				(font
					(size 1 1)
					(thickness 0.15)
				)
				(justify mirror)
			)
		)
		(property "MPN" "CR0402-FX-2000GLF"
			(at 0 0 270)
			(unlocked yes)
			(layer "B.Fab")
			(hide yes)
			(effects
				(font
					(size 1 1)
					(thickness 0.15)
				)
				(justify mirror)
			)
		)
		(property "Val" "200R"
			(at 0 0 270)
			(unlocked yes)
			(layer "B.Fab")
			(hide yes)
			(effects
				(font
					(size 1 1)
					(thickness 0.15)
				)
				(justify mirror)
			)
		)
		(property "License" "Apache-2.0"
			(at 0 0 270)
			(unlocked yes)
			(layer "B.Fab")
			(hide yes)
			(effects
				(font
					(size 1 1)
					(thickness 0.15)
				)
				(justify mirror)
			)
		)
		(property "Author" "Antmicro"
			(at 0 0 270)
			(unlocked yes)
			(layer "B.Fab")
			(hide yes)
			(effects
				(font
					(size 1 1)
					(thickness 0.15)
				)
				(justify mirror)
			)
		)
		(property "Tolerance" "1%"
			(at 0 0 270)
			(unlocked yes)
			(layer "B.Fab")
			(hide yes)
			(effects
				(font
					(size 1 1)
					(thickness 0.15)
				)
				(justify mirror)
			)
		)
		(sheetname "/Ethernet/")
		(sheetfile "ethernet.kicad_sch")
		(attr smd)
		(fp_rect
			(start -0.925 0.47)
			(end 0.925 -0.47)
			(stroke
				(width 0.05)
				(type default)
			)
			(fill no)
			(layer "B.CrtYd")
		)
		(fp_rect
			(start -0.5 0.25)
			(end 0.5 -0.25)
			(stroke
				(width 0.15)
				(type solid)
			)
			(fill no)
			(layer "B.Fab")
		)
		(fp_text user "Author: Antmicro"
			(at -0.95 -4.169 90)
			(layer "B.Fab")
			(effects
				(font
					(size 0.7 0.7)
					(thickness 0.15)
				)
				(justify left bottom mirror)
			)
		)
		(fp_text user "License: Apache-2.0"
			(at -0.95 -5.169 90)
			(layer "B.Fab")
			(effects
				(font
					(size 0.7 0.7)
					(thickness 0.15)
				)
				(justify left bottom mirror)
			)
		)
		(fp_text user "${REFERENCE}"
			(at -0.95 -3.168 90)
			(layer "B.Fab")
			(effects
				(font
					(size 0.7 0.7)
					(thickness 0.15)
				)
				(justify left bottom mirror)
			)
		)
		(pad "1" smd roundrect
			(at -0.48 0 270)
			(size 0.59 0.64)
			(layers "B.Cu" "B.Mask" "B.Paste")
			(roundrect_rratio 0.25)
			(net 176 "Net-(J401-LED_GRN-)")
			(pintype "passive")
		)
		(pad "2" smd roundrect
			(at 0.48 0 270)
			(size 0.59 0.64)
			(layers "B.Cu" "B.Mask" "B.Paste")
			(roundrect_rratio 0.25)
			(net 214 "/Compute module/ETHERNET.LED_LINK")
			(pintype "passive")
		)
	)
	(footprint "antmicro-footprints:C_2220_5650Metric"
		(layer "B.Cu")
		(at 49.192962 145.6465 90)
		(descr "Capacitor SMD 2220")
		(tags "capacitor SMD 2220")
		(property "Reference" "C404"
			(at -4.52 -1.495 180)
			(layer "B.SilkS")
			(effects
				(font
					(size 0.7 0.7)
					(thickness 0.15)
				)
				(justify right bottom mirror)
			)
		)
		(property "Value" "C_22u_100V_2220"
			(at 0 -3.9 90)
			(layer "B.Fab")
			(effects
				(font
					(size 0.7 0.7)
					(thickness 0.15)
				)
				(justify right bottom mirror)
			)
		)
		(property "Datasheet" "https://product.tdk.com/en/search/capacitor/ceramic/mlcc/info?part_no=C5750X7S2A226M280KB"
			(at 0 0 90)
			(layer "B.Fab")
			(hide yes)
			(effects
				(font
					(size 1.27 1.27)
					(thickness 0.15)
				)
			)
		)
		(property "Manufacturer" "TDK"
			(at 0 0 90)
			(unlocked yes)
			(layer "B.Fab")
			(hide yes)
			(effects
				(font
					(size 1 1)
					(thickness 0.15)
				)
				(justify mirror)
			)
		)
		(property "MPN" "C5750X7S2A226M280KB"
			(at 0 0 90)
			(unlocked yes)
			(layer "B.Fab")
			(hide yes)
			(effects
				(font
					(size 1 1)
					(thickness 0.15)
				)
				(justify mirror)
			)
		)
		(property "Val" "22u"
			(at 0 0 90)
			(unlocked yes)
			(layer "B.Fab")
			(hide yes)
			(effects
				(font
					(size 1 1)
					(thickness 0.15)
				)
				(justify mirror)
			)
		)
		(property "License" "Apache-2.0"
			(at 0 0 90)
			(unlocked yes)
			(layer "B.Fab")
			(hide yes)
			(effects
				(font
					(size 1 1)
					(thickness 0.15)
				)
				(justify mirror)
			)
		)
		(property "Author" "Antmicro"
			(at 0 0 90)
			(unlocked yes)
			(layer "B.Fab")
			(hide yes)
			(effects
				(font
					(size 1 1)
					(thickness 0.15)
				)
				(justify mirror)
			)
		)
		(property "Voltage" "100V"
			(at 0 0 90)
			(unlocked yes)
			(layer "B.Fab")
			(hide yes)
			(effects
				(font
					(size 1 1)
					(thickness 0.15)
				)
				(justify mirror)
			)
		)
		(property "Dielectric" "X7S"
			(at 0 0 90)
			(unlocked yes)
			(layer "B.Fab")
			(hide yes)
			(effects
				(font
					(size 1 1)
					(thickness 0.15)
				)
				(justify mirror)
			)
		)
		(property "Public" "False"
			(at 0 0 90)
			(unlocked yes)
			(layer "B.Fab")
			(hide yes)
			(effects
				(font
					(size 1 1)
					(thickness 0.15)
				)
				(justify mirror)
			)
		)
		(sheetname "/Ethernet/")
		(sheetfile "ethernet.kicad_sch")
		(attr smd)
		(fp_line
			(start -1.415 -2.61)
			(end 1.415 -2.61)
			(stroke
				(width 0.15)
				(type solid)
			)
			(layer "B.SilkS")
		)
		(fp_line
			(start -1.415 2.61)
			(end 1.415 2.61)
			(stroke
				(width 0.15)
				(type solid)
			)
			(layer "B.SilkS")
		)
		(fp_rect
			(start -3.7 2.95)
			(end 3.7 -2.95)
			(stroke
				(width 0.05)
				(type solid)
			)
			(fill no)
			(layer "B.CrtYd")
		)
		(fp_rect
			(start -2.85 2.5)
			(end 2.85 -2.5)
			(stroke
				(width 0.15)
				(type solid)
			)
			(fill no)
			(layer "B.Fab")
		)
		(fp_text user "License: Apache-2.0"
			(at -3.7 -6.9 270)
			(layer "B.Fab")
			(effects
				(font
					(size 0.7 0.7)
					(thickness 0.15)
				)
				(justify left bottom mirror)
			)
		)
		(fp_text user "Author: Antmicro"
			(at -3.7 -7.9 270)
			(layer "B.Fab")
			(effects
				(font
					(size 0.7 0.7)
					(thickness 0.15)
				)
				(justify left bottom mirror)
			)
		)
		(fp_text user "${REFERENCE}"
			(at -3.7 -5.9 270)
			(layer "B.Fab")
			(effects
				(font
					(size 0.7 0.7)
					(thickness 0.15)
				)
				(justify left bottom mirror)
			)
		)
		(pad "1" smd roundrect
			(at -2.55 0 90)
			(size 1.8 5.4)
			(layers "B.Cu" "B.Mask" "B.Paste")
			(roundrect_rratio 0.138889)
			(net 1 "GNDD")
			(pintype "passive")
		)
		(pad "2" smd roundrect
			(at 2.55 0 90)
			(size 1.8 5.4)
			(layers "B.Cu" "B.Mask" "B.Paste")
			(roundrect_rratio 0.138889)
			(net 33 "/Ethernet/VDD")
			(pintype "passive")
		)
	)
	(footprint "antmicro-footprints:R_0402_1005Metric"
		(layer "B.Cu")
		(at 59.792962 165.4805)
		(descr "Resistor SMD 0402")
		(tags "resistor SMD 0402")
		(property "Reference" "R302"
			(at 0.507038 0.4195 315)
			(layer "B.SilkS")
			(effects
				(font
					(size 0.7 0.7)
					(thickness 0.15)
				)
				(justify right bottom mirror)
			)
		)
		(property "Value" "R_33k_0402"
			(at -1.011843 -1.772047 0)
			(layer "B.Fab")
			(effects
				(font
					(size 0.7 0.7)
					(thickness 0.15)
				)
				(justify right bottom mirror)
			)
		)
		(property "Datasheet" "https://www.bourns.com/docs/product-datasheets/cr.pdf"
			(at 0 0 0)
			(layer "B.Fab")
			(hide yes)
			(effects
				(font
					(size 1.27 1.27)
					(thickness 0.15)
				)
			)
		)
		(property "MPN" "CR0402-FX-3302GLF"
			(at 0 0 0)
			(unlocked yes)
			(layer "B.Fab")
			(hide yes)
			(effects
				(font
					(size 1 1)
					(thickness 0.15)
				)
				(justify mirror)
			)
		)
		(property "Manufacturer" "Bourns"
			(at 0 0 0)
			(unlocked yes)
			(layer "B.Fab")
			(hide yes)
			(effects
				(font
					(size 1 1)
					(thickness 0.15)
				)
				(justify mirror)
			)
		)
		(property "License" "Apache-2.0"
			(at 0 0 0)
			(unlocked yes)
			(layer "B.Fab")
			(hide yes)
			(effects
				(font
					(size 1 1)
					(thickness 0.15)
				)
				(justify mirror)
			)
		)
		(property "Author" "Antmicro"
			(at 0 0 0)
			(unlocked yes)
			(layer "B.Fab")
			(hide yes)
			(effects
				(font
					(size 1 1)
					(thickness 0.15)
				)
				(justify mirror)
			)
		)
		(property "Val" "33k"
			(at 0 0 0)
			(unlocked yes)
			(layer "B.Fab")
			(hide yes)
			(effects
				(font
					(size 1 1)
					(thickness 0.15)
				)
				(justify mirror)
			)
		)
		(property "Tolerance" "1%"
			(at 0 0 0)
			(unlocked yes)
			(layer "B.Fab")
			(hide yes)
			(effects
				(font
					(size 1 1)
					(thickness 0.15)
				)
				(justify mirror)
			)
		)
		(sheetname "/Supply/")
		(sheetfile "supply.kicad_sch")
		(attr smd)
		(fp_rect
			(start -0.925 0.47)
			(end 0.925 -0.47)
			(stroke
				(width 0.05)
				(type default)
			)
			(fill no)
			(layer "B.CrtYd")
		)
		(fp_rect
			(start -0.5 0.25)
			(end 0.5 -0.25)
			(stroke
				(width 0.15)
				(type solid)
			)
			(fill no)
			(layer "B.Fab")
		)
		(fp_text user "License: Apache-2.0"
			(at -0.95 -5.169 180)
			(layer "B.Fab")
			(effects
				(font
					(size 0.7 0.7)
					(thickness 0.15)
				)
				(justify left bottom mirror)
			)
		)
		(fp_text user "${REFERENCE}"
			(at -0.95 -3.168 180)
			(layer "B.Fab")
			(effects
				(font
					(size 0.7 0.7)
					(thickness 0.15)
				)
				(justify left bottom mirror)
			)
		)
		(fp_text user "Author: Antmicro"
			(at -0.95 -4.169 180)
			(layer "B.Fab")
			(effects
				(font
					(size 0.7 0.7)
					(thickness 0.15)
				)
				(justify left bottom mirror)
			)
		)
		(pad "1" smd roundrect
			(at -0.48 0)
			(size 0.59 0.64)
			(layers "B.Cu" "B.Mask" "B.Paste")
			(roundrect_rratio 0.25)
			(net 3 "GND")
			(pintype "passive")
		)
		(pad "2" smd roundrect
			(at 0.48 0)
			(size 0.59 0.64)
			(layers "B.Cu" "B.Mask" "B.Paste")
			(roundrect_rratio 0.25)
			(net 334 "Net-(Q302-REF)")
			(pintype "passive")
		)
	)
	(footprint "antmicro-footprints:R_0402_1005Metric"
		(layer "B.Cu")
		(at 76.142962 126.6165 180)
		(descr "Resistor SMD 0402")
		(tags "resistor SMD 0402")
		(property "Reference" "R904"
			(at -0.935 0.58 0)
			(layer "B.SilkS")
			(effects
				(font
					(size 0.7 0.7)
					(thickness 0.15)
				)
				(justify left bottom mirror)
			)
		)
		(property "Value" "R_100k_0402"
			(at -1.011843 -1.772047 0)
			(layer "B.Fab")
			(effects
				(font
					(size 0.7 0.7)
					(thickness 0.15)
				)
				(justify left bottom mirror)
			)
		)
		(property "Datasheet" "https://www.bourns.com/docs/product-datasheets/cr.pdf"
			(at 0 0 180)
			(layer "B.Fab")
			(hide yes)
			(effects
				(font
					(size 1.27 1.27)
					(thickness 0.15)
				)
			)
		)
		(property "Manufacturer" "Bourns"
			(at 0 0 180)
			(unlocked yes)
			(layer "B.Fab")
			(hide yes)
			(effects
				(font
					(size 1 1)
					(thickness 0.15)
				)
				(justify mirror)
			)
		)
		(property "MPN" "CR0402-FX-1003GLF"
			(at 0 0 180)
			(unlocked yes)
			(layer "B.Fab")
			(hide yes)
			(effects
				(font
					(size 1 1)
					(thickness 0.15)
				)
				(justify mirror)
			)
		)
		(property "Val" "100k"
			(at 0 0 180)
			(unlocked yes)
			(layer "B.Fab")
			(hide yes)
			(effects
				(font
					(size 1 1)
					(thickness 0.15)
				)
				(justify mirror)
			)
		)
		(property "License" "Apache-2.0"
			(at 0 0 180)
			(unlocked yes)
			(layer "B.Fab")
			(hide yes)
			(effects
				(font
					(size 1 1)
					(thickness 0.15)
				)
				(justify mirror)
			)
		)
		(property "Author" "Antmicro"
			(at 0 0 180)
			(unlocked yes)
			(layer "B.Fab")
			(hide yes)
			(effects
				(font
					(size 1 1)
					(thickness 0.15)
				)
				(justify mirror)
			)
		)
		(property "Tolerance" "1%"
			(at 0 0 180)
			(unlocked yes)
			(layer "B.Fab")
			(hide yes)
			(effects
				(font
					(size 1 1)
					(thickness 0.15)
				)
				(justify mirror)
			)
		)
		(sheetname "/USB/")
		(sheetfile "usb.kicad_sch")
		(attr smd)
		(fp_rect
			(start -0.925 0.47)
			(end 0.925 -0.47)
			(stroke
				(width 0.05)
				(type default)
			)
			(fill no)
			(layer "B.CrtYd")
		)
		(fp_rect
			(start -0.5 0.25)
			(end 0.5 -0.25)
			(stroke
				(width 0.15)
				(type solid)
			)
			(fill no)
			(layer "B.Fab")
		)
		(fp_text user "License: Apache-2.0"
			(at -0.95 -5.169 0)
			(layer "B.Fab")
			(effects
				(font
					(size 0.7 0.7)
					(thickness 0.15)
				)
				(justify left bottom mirror)
			)
		)
		(fp_text user "${REFERENCE}"
			(at -0.95 -3.168 0)
			(layer "B.Fab")
			(effects
				(font
					(size 0.7 0.7)
					(thickness 0.15)
				)
				(justify left bottom mirror)
			)
		)
		(fp_text user "Author: Antmicro"
			(at -0.95 -4.169 0)
			(layer "B.Fab")
			(effects
				(font
					(size 0.7 0.7)
					(thickness 0.15)
				)
				(justify left bottom mirror)
			)
		)
		(pad "1" smd roundrect
			(at -0.48 0 180)
			(size 0.59 0.64)
			(layers "B.Cu" "B.Mask" "B.Paste")
			(roundrect_rratio 0.25)
			(net 26 "/USB/USBD_VBUS")
			(pintype "passive")
		)
		(pad "2" smd roundrect
			(at 0.48 0 180)
			(size 0.59 0.64)
			(layers "B.Cu" "B.Mask" "B.Paste")
			(roundrect_rratio 0.25)
			(net 341 "Net-(Q902-G)")
			(pintype "passive")
		)
	)
	(footprint "antmicro-footprints:R_0402_1005Metric"
		(layer "B.Cu")
		(at 51.542962 136.1165)
		(descr "Resistor SMD 0402")
		(tags "resistor SMD 0402")
		(property "Reference" "R418"
			(at -1.965 1.37 0)
			(layer "B.SilkS")
			(effects
				(font
					(size 0.7 0.7)
					(thickness 0.15)
				)
				(justify right bottom mirror)
			)
		)
		(property "Value" "R_470R_0402"
			(at -1.011843 -1.772047 0)
			(layer "B.Fab")
			(effects
				(font
					(size 0.7 0.7)
					(thickness 0.15)
				)
				(justify right bottom mirror)
			)
		)
		(property "Datasheet" "https://www.bourns.com/docs/product-datasheets/cr.pdf"
			(at 0 0 0)
			(layer "B.Fab")
			(hide yes)
			(effects
				(font
					(size 1.27 1.27)
					(thickness 0.15)
				)
			)
		)
		(property "Manufacturer" "Bourns"
			(at 0 0 0)
			(unlocked yes)
			(layer "B.Fab")
			(hide yes)
			(effects
				(font
					(size 1 1)
					(thickness 0.15)
				)
				(justify mirror)
			)
		)
		(property "MPN" "CR0402-FX-4700GLF"
			(at 0 0 0)
			(unlocked yes)
			(layer "B.Fab")
			(hide yes)
			(effects
				(font
					(size 1 1)
					(thickness 0.15)
				)
				(justify mirror)
			)
		)
		(property "Val" "470R"
			(at 0 0 0)
			(unlocked yes)
			(layer "B.Fab")
			(hide yes)
			(effects
				(font
					(size 1 1)
					(thickness 0.15)
				)
				(justify mirror)
			)
		)
		(property "License" "Apache-2.0"
			(at 0 0 0)
			(unlocked yes)
			(layer "B.Fab")
			(hide yes)
			(effects
				(font
					(size 1 1)
					(thickness 0.15)
				)
				(justify mirror)
			)
		)
		(property "Author" "Antmicro"
			(at 0 0 0)
			(unlocked yes)
			(layer "B.Fab")
			(hide yes)
			(effects
				(font
					(size 1 1)
					(thickness 0.15)
				)
				(justify mirror)
			)
		)
		(property "Tolerance" "1%"
			(at 0 0 0)
			(unlocked yes)
			(layer "B.Fab")
			(hide yes)
			(effects
				(font
					(size 1 1)
					(thickness 0.15)
				)
				(justify mirror)
			)
		)
		(sheetname "/Ethernet/")
		(sheetfile "ethernet.kicad_sch")
		(attr smd)
		(fp_rect
			(start -0.925 0.47)
			(end 0.925 -0.47)
			(stroke
				(width 0.05)
				(type default)
			)
			(fill no)
			(layer "B.CrtYd")
		)
		(fp_rect
			(start -0.5 0.25)
			(end 0.5 -0.25)
			(stroke
				(width 0.15)
				(type solid)
			)
			(fill no)
			(layer "B.Fab")
		)
		(fp_text user "License: Apache-2.0"
			(at -0.95 -5.169 180)
			(layer "B.Fab")
			(effects
				(font
					(size 0.7 0.7)
					(thickness 0.15)
				)
				(justify left bottom mirror)
			)
		)
		(fp_text user "${REFERENCE}"
			(at -0.95 -3.168 180)
			(layer "B.Fab")
			(effects
				(font
					(size 0.7 0.7)
					(thickness 0.15)
				)
				(justify left bottom mirror)
			)
		)
		(fp_text user "Author: Antmicro"
			(at -0.95 -4.169 180)
			(layer "B.Fab")
			(effects
				(font
					(size 0.7 0.7)
					(thickness 0.15)
				)
				(justify left bottom mirror)
			)
		)
		(pad "1" smd roundrect
			(at -0.48 0)
			(size 0.59 0.64)
			(layers "B.Cu" "B.Mask" "B.Paste")
			(roundrect_rratio 0.25)
			(net 1 "GNDD")
			(pintype "passive")
		)
		(pad "2" smd roundrect
			(at 0.48 0)
			(size 0.59 0.64)
			(layers "B.Cu" "B.Mask" "B.Paste")
			(roundrect_rratio 0.25)
			(net 366 "Net-(R418-Pad2)")
			(pintype "passive")
		)
	)
	(footprint "antmicro-footprints:R_0402_1005Metric"
		(layer "B.Cu")
		(at 86.842962 123.1415)
		(descr "Resistor SMD 0402")
		(tags "resistor SMD 0402")
		(property "Reference" "R910"
			(at 0.955 -0.565 0)
			(layer "B.SilkS")
			(effects
				(font
					(size 0.7 0.7)
					(thickness 0.15)
				)
				(justify right bottom mirror)
			)
		)
		(property "Value" "R_10k_0402"
			(at -1.011843 -1.772047 0)
			(layer "B.Fab")
			(effects
				(font
					(size 0.7 0.7)
					(thickness 0.15)
				)
				(justify right bottom mirror)
			)
		)
		(property "Datasheet" "https://www.bourns.com/docs/product-datasheets/cr.pdf"
			(at 0 0 0)
			(layer "B.Fab")
			(hide yes)
			(effects
				(font
					(size 1.27 1.27)
					(thickness 0.15)
				)
			)
		)
		(property "Manufacturer" "Bourns"
			(at 0 0 0)
			(unlocked yes)
			(layer "B.Fab")
			(hide yes)
			(effects
				(font
					(size 1 1)
					(thickness 0.15)
				)
				(justify mirror)
			)
		)
		(property "MPN" "CR0402-FX-1002GLF"
			(at 0 0 0)
			(unlocked yes)
			(layer "B.Fab")
			(hide yes)
			(effects
				(font
					(size 1 1)
					(thickness 0.15)
				)
				(justify mirror)
			)
		)
		(property "Val" "10k"
			(at 0 0 0)
			(unlocked yes)
			(layer "B.Fab")
			(hide yes)
			(effects
				(font
					(size 1 1)
					(thickness 0.15)
				)
				(justify mirror)
			)
		)
		(property "License" "Apache-2.0"
			(at 0 0 0)
			(unlocked yes)
			(layer "B.Fab")
			(hide yes)
			(effects
				(font
					(size 1 1)
					(thickness 0.15)
				)
				(justify mirror)
			)
		)
		(property "Author" "Antmicro"
			(at 0 0 0)
			(unlocked yes)
			(layer "B.Fab")
			(hide yes)
			(effects
				(font
					(size 1 1)
					(thickness 0.15)
				)
				(justify mirror)
			)
		)
		(property "Tolerance" "1%"
			(at 0 0 0)
			(unlocked yes)
			(layer "B.Fab")
			(hide yes)
			(effects
				(font
					(size 1 1)
					(thickness 0.15)
				)
				(justify mirror)
			)
		)
		(sheetname "/USB/")
		(sheetfile "usb.kicad_sch")
		(attr smd)
		(fp_rect
			(start -0.925 0.47)
			(end 0.925 -0.47)
			(stroke
				(width 0.05)
				(type default)
			)
			(fill no)
			(layer "B.CrtYd")
		)
		(fp_rect
			(start -0.5 0.25)
			(end 0.5 -0.25)
			(stroke
				(width 0.15)
				(type solid)
			)
			(fill no)
			(layer "B.Fab")
		)
		(fp_text user "${REFERENCE}"
			(at -0.95 -3.168 180)
			(layer "B.Fab")
			(effects
				(font
					(size 0.7 0.7)
					(thickness 0.15)
				)
				(justify left bottom mirror)
			)
		)
		(fp_text user "Author: Antmicro"
			(at -0.95 -4.169 180)
			(layer "B.Fab")
			(effects
				(font
					(size 0.7 0.7)
					(thickness 0.15)
				)
				(justify left bottom mirror)
			)
		)
		(fp_text user "License: Apache-2.0"
			(at -0.95 -5.169 180)
			(layer "B.Fab")
			(effects
				(font
					(size 0.7 0.7)
					(thickness 0.15)
				)
				(justify left bottom mirror)
			)
		)
		(pad "1" smd roundrect
			(at -0.48 0)
			(size 0.59 0.64)
			(layers "B.Cu" "B.Mask" "B.Paste")
			(roundrect_rratio 0.25)
			(net 3 "GND")
			(pintype "passive")
		)
		(pad "2" smd roundrect
			(at 0.48 0)
			(size 0.59 0.64)
			(layers "B.Cu" "B.Mask" "B.Paste")
			(roundrect_rratio 0.25)
			(net 343 "/USB/EN_FTDI")
			(pintype "passive")
		)
	)
	(footprint "antmicro-footprints:Nexperia_DFN-10_2.5x1mm_P0.5mm"
		(layer "B.Cu")
		(at 101.080962 169.8785 90)
		(property "Reference" "D705"
			(at -0.608 2.597 90)
			(layer "B.SilkS")
			(effects
				(font
					(size 0.7 0.7)
					(thickness 0.15)
				)
				(justify right bottom mirror)
			)
		)
		(property "Value" "PUSB3F96X_PASS"
			(at -0.016 -1.705 90)
			(layer "B.Fab")
			(effects
				(font
					(size 0.7 0.7)
					(thickness 0.15)
				)
				(justify right bottom mirror)
			)
		)
		(property "Datasheet" "https://mouser.com/datasheet/2/916/PUSB3F96-1600324.pdf"
			(at 0 0 90)
			(layer "B.Fab")
			(hide yes)
			(effects
				(font
					(size 1.27 1.27)
					(thickness 0.15)
				)
			)
		)
		(property "Manufacturer" "Nexperia"
			(at 0 0 90)
			(unlocked yes)
			(layer "B.Fab")
			(hide yes)
			(effects
				(font
					(size 1 1)
					(thickness 0.15)
				)
				(justify mirror)
			)
		)
		(property "MPN" "PUSB3F96X"
			(at 0 0 90)
			(unlocked yes)
			(layer "B.Fab")
			(hide yes)
			(effects
				(font
					(size 1 1)
					(thickness 0.15)
				)
				(justify mirror)
			)
		)
		(property "Author" "Antmicro"
			(at 0 0 90)
			(unlocked yes)
			(layer "B.Fab")
			(hide yes)
			(effects
				(font
					(size 1 1)
					(thickness 0.15)
				)
				(justify mirror)
			)
		)
		(property "License" "Apache-2.0"
			(at 0 0 90)
			(unlocked yes)
			(layer "B.Fab")
			(hide yes)
			(effects
				(font
					(size 1 1)
					(thickness 0.15)
				)
				(justify mirror)
			)
		)
		(sheetname "/Display/")
		(sheetfile "display.kicad_sch")
		(attr smd)
		(fp_line
			(start 1.375 -0.4)
			(end 1.375 0.4)
			(stroke
				(width 0.15)
				(type solid)
			)
			(layer "B.SilkS")
		)
		(fp_line
			(start -1.375 0.4)
			(end -1.375 -0.4)
			(stroke
				(width 0.15)
				(type solid)
			)
			(layer "B.SilkS")
		)
		(fp_circle
			(center -1.4 -0.7)
			(end -1.349 -0.7)
			(stroke
				(width 0.15)
				(type solid)
			)
			(fill yes)
			(layer "B.SilkS")
		)
		(fp_rect
			(start -1.4 0.725)
			(end 1.4 -0.725)
			(stroke
				(width 0.05)
				(type solid)
			)
			(fill no)
			(layer "B.CrtYd")
		)
		(fp_line
			(start 1.25 -0.5)
			(end 1.25 0.5)
			(stroke
				(width 0.15)
				(type solid)
			)
			(layer "B.Fab")
		)
		(fp_line
			(start -0.9 -0.5)
			(end 1.25 -0.5)
			(stroke
				(width 0.15)
				(type solid)
			)
			(layer "B.Fab")
		)
		(fp_line
			(start -1.25 -0.15)
			(end -0.9 -0.5)
			(stroke
				(width 0.15)
				(type solid)
			)
			(layer "B.Fab")
		)
		(fp_line
			(start 1.25 0.5)
			(end -1.25 0.5)
			(stroke
				(width 0.15)
				(type solid)
			)
			(layer "B.Fab")
		)
		(fp_line
			(start -1.25 0.5)
			(end -1.25 -0.15)
			(stroke
				(width 0.15)
				(type solid)
			)
			(layer "B.Fab")
		)
		(fp_text user "Author: Antmicro"
			(at -1.367 -4.905 270)
			(layer "B.Fab")
			(effects
				(font
					(size 0.7 0.7)
					(thickness 0.15)
				)
				(justify left bottom mirror)
			)
		)
		(fp_text user "${REFERENCE}"
			(at -1.367 -3.704 270)
			(layer "B.Fab")
			(effects
				(font
					(size 0.7 0.7)
					(thickness 0.15)
				)
				(justify left bottom mirror)
			)
		)
		(fp_text user "License: Apache-2.0"
			(at -1.367 -6.105 270)
			(layer "B.Fab")
			(effects
				(font
					(size 0.7 0.7)
					(thickness 0.15)
				)
				(justify left bottom mirror)
			)
		)
		(pad "1" smd rect
			(at -1 -0.3875 90)
			(size 0.2 0.475)
			(layers "B.Cu" "B.Mask" "B.Paste")
			(net 122 "/Compute module/DSICtrl.EN")
			(pinfunction "CH1")
			(pintype "passive")
			(solder_mask_margin 0.05)
		)
		(pad "2" smd rect
			(at -0.5 -0.3875 90)
			(size 0.2 0.475)
			(layers "B.Cu" "B.Mask" "B.Paste")
			(net 123 "/Compute module/DSICtrl.~{RST}")
			(pinfunction "CH2")
			(pintype "passive")
			(solder_mask_margin 0.05)
		)
		(pad "3" smd rect
			(at 0 -0.3875 90)
			(size 0.2 0.475)
			(layers "B.Cu" "B.Mask" "B.Paste")
			(net 3 "GND")
			(pinfunction "GND")
			(pintype "passive")
			(solder_mask_margin 0.05)
		)
		(pad "4" smd rect
			(at 0.5 -0.3875 90)
			(size 0.2 0.475)
			(layers "B.Cu" "B.Mask" "B.Paste")
			(net 124 "/Compute module/DSICtrl.DIM")
			(pinfunction "CH3")
			(pintype "passive")
			(solder_mask_margin 0.05)
		)
		(pad "5" smd rect
			(at 1 -0.3875 90)
			(size 0.2 0.475)
			(layers "B.Cu" "B.Mask" "B.Paste")
			(net 125 "/Compute module/DSICtrl.GPIO")
			(pinfunction "CH4")
			(pintype "passive")
			(solder_mask_margin 0.05)
		)
		(pad "6" smd rect
			(at 1 0.3875 90)
			(size 0.2 0.475)
			(layers "B.Cu" "B.Mask" "B.Paste")
			(net 125 "/Compute module/DSICtrl.GPIO")
			(pinfunction "CH4")
			(pintype "passive")
			(solder_mask_margin 0.05)
		)
		(pad "7" smd rect
			(at 0.5 0.3875 90)
			(size 0.2 0.475)
			(layers "B.Cu" "B.Mask" "B.Paste")
			(net 124 "/Compute module/DSICtrl.DIM")
			(pinfunction "CH3")
			(pintype "passive")
			(solder_mask_margin 0.05)
		)
		(pad "8" smd rect
			(at 0 0.3875 90)
			(size 0.2 0.475)
			(layers "B.Cu" "B.Mask" "B.Paste")
			(net 3 "GND")
			(pinfunction "GND")
			(pintype "passive")
			(solder_mask_margin 0.05)
		)
		(pad "9" smd rect
			(at -0.501 0.3875 90)
			(size 0.2 0.475)
			(layers "B.Cu" "B.Mask" "B.Paste")
			(net 123 "/Compute module/DSICtrl.~{RST}")
			(pinfunction "CH2")
			(pintype "passive")
			(solder_mask_margin 0.05)
		)
		(pad "10" smd rect
			(at -1 0.3875 90)
			(size 0.2 0.475)
			(layers "B.Cu" "B.Mask" "B.Paste")
			(net 122 "/Compute module/DSICtrl.EN")
			(pinfunction "CH1")
			(pintype "passive")
			(solder_mask_margin 0.05)
		)
	)
	(footprint "antmicro-footprints:MS621FE-FL11E"
		(layer "B.Cu")
		(at 130.6 174.6 -135)
		(property "Reference" "BT801"
			(at -1.838478 -8.202439 0)
			(layer "B.SilkS")
			(effects
				(font
					(size 0.7 0.7)
					(thickness 0.15)
				)
				(justify left bottom mirror)
			)
		)
		(property "Value" "Battery_Holder_MS621FE-FL11E"
			(at -0.001 -6.2 45)
			(layer "B.Fab")
			(effects
				(font
					(size 0.7 0.7)
					(thickness 0.15)
				)
				(justify left bottom mirror)
			)
		)
		(property "Datasheet" "https://www.sii.co.jp/en/me/datasheets/ms-rechargeable/ms621fe/"
			(at 0 0 45)
			(layer "B.Fab")
			(hide yes)
			(effects
				(font
					(size 1.27 1.27)
					(thickness 0.15)
				)
				(justify mirror)
			)
		)
		(property "Description" "Rechargeable Battery, Coin Cell, Single Cell, 3 V, Lithium Manganese Dioxide, 5.5 mAh, Button Cell"
			(at 0 0 45)
			(layer "B.Fab")
			(hide yes)
			(effects
				(font
					(size 1.27 1.27)
					(thickness 0.15)
				)
				(justify mirror)
			)
		)
		(property "Manufacturer" "Seiko Instruments"
			(at 0 0 225)
			(unlocked yes)
			(layer "B.Fab")
			(hide yes)
			(effects
				(font
					(size 1 1)
					(thickness 0.15)
				)
				(justify mirror)
			)
		)
		(property "MPN" "MS621FE-FL11E"
			(at 0 0 225)
			(unlocked yes)
			(layer "B.Fab")
			(hide yes)
			(effects
				(font
					(size 1 1)
					(thickness 0.15)
				)
				(justify mirror)
			)
		)
		(property "Author" "Antmicro"
			(at 0 0 225)
			(unlocked yes)
			(layer "B.Fab")
			(hide yes)
			(effects
				(font
					(size 1 1)
					(thickness 0.15)
				)
				(justify mirror)
			)
		)
		(property "License" "Apache-2.0"
			(at 0 0 225)
			(unlocked yes)
			(layer "B.Fab")
			(hide yes)
			(effects
				(font
					(size 1 1)
					(thickness 0.15)
				)
				(justify mirror)
			)
		)
		(sheetname "/Peripherals/")
		(sheetfile "peripherals.kicad_sch")
		(attr smd)
		(fp_arc
			(start -1.200001 2.15)
			(mid 0 -4.834001)
			(end 1.200001 2.15)
			(stroke
				(width 0.15)
				(type solid)
			)
			(layer "B.SilkS")
		)
		(fp_line
			(start 1.275 5.2)
			(end -1.275 5.2)
			(stroke
				(width 0.05)
				(type solid)
			)
			(layer "B.CrtYd")
		)
		(fp_line
			(start 1.275 5.2)
			(end 1.275 2.425)
			(stroke
				(width 0.05)
				(type solid)
			)
			(layer "B.CrtYd")
		)
		(fp_line
			(start -1.275 5.2)
			(end -1.275 2.425)
			(stroke
				(width 0.05)
				(type solid)
			)
			(layer "B.CrtYd")
		)
		(fp_arc
			(start -1.275 2.425)
			(mid 0 -5.143375)
			(end 1.275 2.425)
			(stroke
				(width 0.05)
				(type solid)
			)
			(layer "B.CrtYd")
		)
		(fp_line
			(start 1.2 5.05)
			(end -0.8 5.05)
			(stroke
				(width 0.15)
				(type solid)
			)
			(layer "B.Fab")
		)
		(fp_line
			(start 1.2 5.05)
			(end 1.2 2.04)
			(stroke
				(width 0.15)
				(type solid)
			)
			(layer "B.Fab")
		)
		(fp_line
			(start -0.8 5.05)
			(end -1.200001 4.65)
			(stroke
				(width 0.15)
				(type solid)
			)
			(layer "B.Fab")
		)
		(fp_line
			(start -1.200001 4.65)
			(end -1.2 2.04)
			(stroke
				(width 0.15)
				(type solid)
			)
			(layer "B.Fab")
		)
		(fp_circle
			(center -0.001001 -1.25)
			(end -0.001 2.25)
			(stroke
				(width 0.15)
				(type solid)
			)
			(fill no)
			(layer "B.Fab")
		)
		(fp_text user "${REFERENCE}"
			(at -3.501 -11.8 45)
			(layer "B.Fab")
			(effects
				(font
					(size 0.7 0.7)
					(thickness 0.15)
				)
				(justify left bottom mirror)
			)
		)
		(fp_text user "COPPER KEEPOUT"
			(at -0.2 3.14 135)
			(unlocked yes)
			(layer "B.Fab")
			(effects
				(font
					(size 0.4 0.4)
					(thickness 0.1)
				)
				(justify left bottom mirror)
			)
		)
		(fp_text user "License: Apache-2.0"
			(at -3.501 -8.2 45)
			(layer "B.Fab")
			(effects
				(font
					(size 0.7 0.7)
					(thickness 0.15)
				)
				(justify left bottom mirror)
			)
		)
		(fp_text user "Author: Antmicro"
			(at -3.501 -9.4 45)
			(layer "B.Fab")
			(effects
				(font
					(size 0.7 0.7)
					(thickness 0.15)
				)
				(justify left bottom mirror)
			)
		)
		(pad "1" smd rect
			(at -0.750001 4.05 315)
			(size 1.8 0.75)
			(layers "B.Cu" "B.Mask" "B.Paste")
			(net 502 "Net-(BT801-+)")
			(pinfunction "+")
			(pintype "passive")
		)
		(pad "2" smd rect
			(at 0.750001 4.05 315)
			(size 1.8 0.75)
			(layers "B.Cu" "B.Mask" "B.Paste")
			(net 3 "GND")
			(pinfunction "-")
			(pintype "passive")
		)
		(zone
			(net 0)
			(net_name "")
			(layers "B.Cu" "B.CrtYd")
			(hatch edge 0.508)
			(connect_pads
				(clearance 0)
			)
			(min_thickness 0.254)
			(filled_areas_thickness no)
			(keepout
				(tracks allowed)
				(vias not_allowed)
				(pads not_allowed)
				(copperpour not_allowed)
				(footprints allowed)
			)
			(placement
				(enabled no)
				(sheetname "")
			)
			(fill
				(thermal_gap 0.508)
				(thermal_bridge_width 0.508)
			)
			(polygon
				(pts
					(xy 133.188011 175.547523) (xy 129.199929 171.559441) (xy 127.559441 173.199929) (xy 131.547523 177.188011)
				)
			)
		)
	)
	(gr_arc
		(start 140.917962 157.3915)
		(mid 141.035119 157.108657)
		(end 141.317962 156.9915)
		(stroke
			(width 0.12)
			(type solid)
		)
		(layer "Edge.Cuts")
	)
	(gr_arc
		(start 141.317962 169.9415)
		(mid 141.035119 169.824343)
		(end 140.917962 169.5415)
		(stroke
			(width 0.12)
			(type solid)
		)
		(layer "Edge.Cuts")
	)
	(gr_arc
		(start 143.917962 156.5915)
		(mid 143.800805 156.874343)
		(end 143.517962 156.9915)
		(stroke
			(width 0.12)
			(type solid)
		)
		(layer "Edge.Cuts")
	)
	(gr_line
		(start 36.917962 111.7165)
		(end 143.917962 111.7165)
		(stroke
			(width 0.12)
			(type solid)
		)
		(layer "Edge.Cuts")
	)
	(gr_line
		(start 143.917962 179.7165)
		(end 36.917962 179.7165)
		(stroke
			(width 0.12)
			(type solid)
		)
		(layer "Edge.Cuts")
	)
	(gr_line
		(start 140.917962 157.3915)
		(end 140.917962 169.5415)
		(stroke
			(width 0.12)
			(type solid)
		)
		(layer "Edge.Cuts")
	)
	(gr_arc
		(start 143.517962 169.9415)
		(mid 143.800805 170.058657)
		(end 143.917962 170.3415)
		(stroke
			(width 0.12)
			(type solid)
		)
		(layer "Edge.Cuts")
	)
	(gr_line
		(start 143.917962 179.7165)
		(end 143.917962 170.3415)
		(stroke
			(width 0.12)
			(type solid)
		)
		(layer "Edge.Cuts")
	)
	(gr_line
		(start 36.917962 179.7165)
		(end 36.917962 111.7165)
		(stroke
			(width 0.12)
			(type solid)
		)
		(layer "Edge.Cuts")
	)
	(gr_line
		(start 141.317962 156.9915)
		(end 143.517962 156.9915)
		(stroke
			(width 0.12)
			(type solid)
		)
		(layer "Edge.Cuts")
	)
	(gr_line
		(start 141.317962 169.9415)
		(end 143.517962 169.9415)
		(stroke
			(width 0.12)
			(type solid)
		)
		(layer "Edge.Cuts")
	)
	(gr_line
		(start 143.917962 111.7165)
		(end 143.917962 156.5915)
		(stroke
			(width 0.12)
			(type solid)
		)
		(layer "Edge.Cuts")
	)
	(gr_text "CM4 Baseboard"
		(at 131.039798 175.082514 90)
		(layer "F.Cu")
		(effects
			(font
				(size 0.7 0.7)
				(thickness 0.175)
			)
		)
	)
	(gr_text "Rev. ${REVISION} 01/2026"
		(at 132.245798 173.831014 90)
		(layer "F.Cu")
		(effects
			(font
				(size 0.7 0.7)
				(thickness 0.175)
			)
		)
	)
	(segment
		(start 49.436962 134.9915)
		(end 49.417962 134.9915)
		(width 0.5)
		(layer "F.Cu")
		(net 1)
	)
	(segment
		(start 53.052962 135.8165)
		(end 49.442962 135.8165)
		(width 0.2)
		(layer "F.Cu")
		(net 1)
	)
	(segment
		(start 49.177462 135.251)
		(end 48.989962 135.4385)
		(width 0.5)
		(layer "F.Cu")
		(net 1)
	)
	(segment
		(start 49.417962 135.0105)
		(end 49.177462 135.251)
		(width 0.5)
		(layer "F.Cu")
		(net 1)
	)
	(segment
		(start 49.439962 134.9885)
		(end 49.436962 134.9915)
		(width 0.5)
		(layer "F.Cu")
		(net 1)
	)
	(segment
		(start 49.261962 135.1665)
		(end 49.177462 135.251)
		(width 0.254)
		(layer "F.Cu")
		(net 1)
	)
	(segment
		(start 48.892962 135.5165)
		(end 48.892962 135.5355)
		(width 0.5)
		(layer "F.Cu")
		(net 1)
	)
	(segment
		(start 57.292962 137.5065)
		(end 57.292962 135.8265)
		(width 0.2)
		(layer "F.Cu")
		(net 1)
	)
	(segment
		(start 49.417962 134.9915)
		(end 49.417962 135.0105)
		(width 0.5)
		(layer "F.Cu")
		(net 1)
	)
	(segment
		(start 49.442962 135.8165)
		(end 49.367962 135.8165)
		(width 0.2)
		(layer "F.Cu")
		(net 1)
	)
	(segment
		(start 49.439962 134.9885)
		(end 49.911962 134.5165)
		(width 0.254)
		(layer "F.Cu")
		(net 1)
	)
	(segment
		(start 49.261962 134.8105)
		(end 49.439962 134.9885)
		(width 0.254)
		(layer "F.Cu")
		(net 1)
	)
	(segment
		(start 48.611962 135.8165)
		(end 48.314962 136.1135)
		(width 0.2)
		(layer "F.Cu")
		(net 1)
	)
	(segment
		(start 49.367962 135.8165)
		(end 48.989962 135.4385)
		(width 0.2)
		(layer "F.Cu")
		(net 1)
	)
	(segment
		(start 48.989962 135.4385)
		(end 48.911962 135.5165)
		(width 0.5)
		(layer "F.Cu")
		(net 1)
	)
	(segment
		(start 49.261962 134.8105)
		(end 49.261962 135.1665)
		(width 0.254)
		(layer "F.Cu")
		(net 1)
	)
	(segment
		(start 48.314962 136.1135)
		(end 44.711962 139.7165)
		(width 0.5)
		(layer "F.Cu")
		(net 1)
	)
	(segment
		(start 48.911962 135.5165)
		(end 48.892962 135.5165)
		(width 0.5)
		(layer "F.Cu")
		(net 1)
	)
	(segment
		(start 57.402962 135.7415)
		(end 58.442962 135.7415)
		(width 0.2)
		(layer "F.Cu")
		(net 1)
	)
	(segment
		(start 48.892962 135.5355)
		(end 48.314962 136.1135)
		(width 0.5)
		(layer "F.Cu")
		(net 1)
	)
	(segment
		(start 49.911962 134.5165)
		(end 49.911962 133.7415)
		(width 0.254)
		(layer "F.Cu")
		(net 1)
	)
	(segment
		(start 49.261962 133.7415)
		(end 49.261962 134.8105)
		(width 0.254)
		(layer "F.Cu")
		(net 1)
	)
	(via
		(at 46.927962 149.4415)
		(size 0.45)
		(drill 0.1)
		(layers "F.Cu" "B.Cu")
		(net 1)
	)
	(via
		(at 60.597962 146.8565)
		(size 0.45)
		(drill 0.1)
		(layers "F.Cu" "B.Cu")
		(net 1)
	)
	(via
		(at 45.552962 146.8815)
		(size 0.45)
		(drill 0.1)
		(layers "F.Cu" "B.Cu")
		(net 1)
	)
	(via
		(at 55.582962 149.4415)
		(size 0.45)
		(drill 0.1)
		(layers "F.Cu" "B.Cu")
		(net 1)
	)
	(via
		(at 49.632962 146.8565)
		(size 0.45)
		(drill 0.1)
		(layers "F.Cu" "B.Cu")
		(net 1)
	)
	(via
		(at 59.712962 149.4415)
		(size 0.45)
		(drill 0.1)
		(layers "F.Cu" "B.Cu")
		(net 1)
	)
	(via
		(at 62.417962 146.8565)
		(size 0.45)
		(drill 0.1)
		(layers "F.Cu" "B.Cu")
		(net 1)
	)
	(via
		(at 62.442962 149.4415)
		(size 0.45)
		(drill 0.1)
		(layers "F.Cu" "B.Cu")
		(net 1)
	)
	(via
		(at 61.507962 146.8565)
		(size 0.45)
		(drill 0.1)
		(layers "F.Cu" "B.Cu")
		(net 1)
	)
	(via
		(at 48.314962 136.1135)
		(size 0.45)
		(drill 0.1)
		(layers "F.Cu" "B.Cu")
		(net 1)
	)
	(via
		(at 46.902962 146.8565)
		(size 0.45)
		(drill 0.1)
		(layers "F.Cu" "B.Cu")
		(net 1)
	)
	(via
		(at 58.777962 146.8565)
		(size 0.45)
		(drill 0.1)
		(layers "F.Cu" "B.Cu")
		(net 1)
	)
	(via
		(at 42.822962 146.8815)
		(size 0.45)
		(drill 0.1)
		(layers "F.Cu" "B.Cu")
		(net 1)
	)
	(via
		(at 48.892962 135.5165)
		(size 0.45)
		(drill 0.1)
		(layers "F.Cu" "B.Cu")
		(net 1)
	)
	(via
		(at 43.757962 149.4665)
		(size 0.45)
		(drill 0.1)
		(layers "F.Cu" "B.Cu")
		(net 1)
	)
	(via
		(at 55.557962 146.8565)
		(size 0.45)
		(drill 0.1)
		(layers "F.Cu" "B.Cu")
		(net 1)
	)
	(via
		(at 57.292962 137.5065)
		(size 0.5)
		(drill 0.15)
		(layers "F.Cu" "B.Cu")
		(net 1)
	)
	(via
		(at 41.002962 146.8815)
		(size 0.45)
		(drill 0.1)
		(layers "F.Cu" "B.Cu")
		(net 1)
	)
	(via
		(at 44.667962 149.4665)
		(size 0.45)
		(drill 0.1)
		(layers "F.Cu" "B.Cu")
		(net 1)
	)
	(via
		(at 48.227962 134.0065)
		(size 0.45)
		(drill 0.1)
		(layers "F.Cu" "B.Cu")
		(free yes)
		(net 1)
	)
	(via
		(at 47.417962 134.4465)
		(size 0.45)
		(drill 0.1)
		(layers "F.Cu" "B.Cu")
		(free yes)
		(net 1)
	)
	(via
		(at 47.837962 149.4415)
		(size 0.45)
		(drill 0.1)
		(layers "F.Cu" "B.Cu")
		(net 1)
	)
	(via
		(at 54.672962 149.4415)
		(size 0.45)
		(drill 0.1)
		(layers "F.Cu" "B.Cu")
		(net 1)
	)
	(via
		(at 41.937962 149.4665)
		(size 0.45)
		(drill 0.1)
		(layers "F.Cu" "B.Cu")
		(net 1)
	)
	(via
		(at 57.402962 149.4415)
		(size 0.45)
		(drill 0.1)
		(layers "F.Cu" "B.Cu")
		(net 1)
	)
	(via
		(at 52.852962 149.4415)
		(size 0.45)
		(drill 0.1)
		(layers "F.Cu" "B.Cu")
		(net 1)
	)
	(via
		(at 63.327962 146.8565)
		(size 0.45)
		(drill 0.1)
		(layers "F.Cu" "B.Cu")
		(net 1)
	)
	(via
		(at 43.732962 146.8815)
		(size 0.45)
		(drill 0.1)
		(layers "F.Cu" "B.Cu")
		(net 1)
	)
	(via
		(at 50.542962 146.8565)
		(size 0.45)
		(drill 0.1)
		(layers "F.Cu" "B.Cu")
		(net 1)
	)
	(via
		(at 41.912962 146.8815)
		(size 0.45)
		(drill 0.1)
		(layers "F.Cu" "B.Cu")
		(net 1)
	)
	(via
		(at 49.417962 134.9915)
		(size 0.45)
		(drill 0.1)
		(layers "F.Cu" "B.Cu")
		(net 1)
	)
	(via
		(at 45.577962 149.4665)
		(size 0.45)
		(drill 0.1)
		(layers "F.Cu" "B.Cu")
		(net 1)
	)
	(via
		(at 58.802962 149.4415)
		(size 0.45)
		(drill 0.1)
		(layers "F.Cu" "B.Cu")
		(net 1)
	)
	(via
		(at 48.747962 149.4415)
		(size 0.45)
		(drill 0.1)
		(layers "F.Cu" "B.Cu")
		(net 1)
	)
	(via
		(at 44.642962 146.8815)
		(size 0.45)
		(drill 0.1)
		(layers "F.Cu" "B.Cu")
		(net 1)
	)
	(via
		(at 60.622962 149.4415)
		(size 0.45)
		(drill 0.1)
		(layers "F.Cu" "B.Cu")
		(net 1)
	)
	(via
		(at 41.027962 149.4665)
		(size 0.45)
		(drill 0.1)
		(layers "F.Cu" "B.Cu")
		(net 1)
	)
	(via
		(at 61.532962 149.4415)
		(size 0.45)
		(drill 0.1)
		(layers "F.Cu" "B.Cu")
		(net 1)
	)
	(via
		(at 56.467962 146.8565)
		(size 0.45)
		(drill 0.1)
		(layers "F.Cu" "B.Cu")
		(net 1)
	)
	(via
		(at 56.492962 149.4415)
		(size 0.45)
		(drill 0.1)
		(layers "F.Cu" "B.Cu")
		(net 1)
	)
	(via
		(at 47.812962 146.8565)
		(size 0.45)
		(drill 0.1)
		(layers "F.Cu" "B.Cu")
		(net 1)
	)
	(via
		(at 53.762962 149.4415)
		(size 0.45)
		(drill 0.1)
		(layers "F.Cu" "B.Cu")
		(net 1)
	)
	(via
		(at 57.377962 146.8565)
		(size 0.45)
		(drill 0.1)
		(layers "F.Cu" "B.Cu")
		(net 1)
	)
	(via
		(at 49.657962 149.4415)
		(size 0.45)
		(drill 0.1)
		(layers "F.Cu" "B.Cu")
		(net 1)
	)
	(via
		(at 54.647962 146.8565)
		(size 0.45)
		(drill 0.1)
		(layers "F.Cu" "B.Cu")
		(net 1)
	)
	(via
		(at 53.737962 146.8565)
		(size 0.45)
		(drill 0.1)
		(layers "F.Cu" "B.Cu")
		(net 1)
	)
	(via
		(at 42.847962 149.4665)
		(size 0.45)
		(drill 0.1)
		(layers "F.Cu" "B.Cu")
		(net 1)
	)
	(via
		(at 59.687962 146.8565)
		(size 0.45)
		(drill 0.1)
		(layers "F.Cu" "B.Cu")
		(net 1)
	)
	(via
		(at 50.567962 149.4415)
		(size 0.45)
		(drill 0.1)
		(layers "F.Cu" "B.Cu")
		(net 1)
	)
	(via
		(at 52.827962 146.8565)
		(size 0.45)
		(drill 0.1)
		(layers "F.Cu" "B.Cu")
		(net 1)
	)
	(via
		(at 51.477962 149.4415)
		(size 0.45)
		(drill 0.1)
		(layers "F.Cu" "B.Cu")
		(net 1)
	)
	(via
		(at 63.352962 149.4415)
		(size 0.45)
		(drill 0.1)
		(layers "F.Cu" "B.Cu")
		(net 1)
	)
	(via
		(at 51.452962 146.8565)
		(size 0.45)
		(drill 0.1)
		(layers "F.Cu" "B.Cu")
		(net 1)
	)
	(via
		(at 48.722962 146.8565)
		(size 0.45)
		(drill 0.1)
		(layers "F.Cu" "B.Cu")
		(net 1)
	)
	(via
		(at 48.267962 134.7865)
		(size 0.45)
		(drill 0.1)
		(layers "F.Cu" "B.Cu")
		(free yes)
		(net 1)
	)
	(segment
		(start 48.314962 136.1135)
		(end 48.342962 136.1415)
		(width 0.2)
		(layer "B.Cu")
		(net 1)
	)
	(segment
		(start 48.342962 136.1415)
		(end 51.032962 136.1415)
		(width 0.2)
		(layer "B.Cu")
		(net 1)
	)
	(segment
		(start 97.855388 178.6965)
		(end 88.103816 178.6965)
		(width 0.127)
		(layer "F.Cu")
		(net 2)
	)
	(segment
		(start 134.007962 136.982882)
		(end 132.268962 138.721882)
		(width 0.127)
		(layer "F.Cu")
		(net 2)
	)
	(segment
		(start 129.927962 158.760166)
		(end 129.927962 160.832914)
		(width 0.127)
		(layer "F.Cu")
		(net 2)
	)
	(segment
		(start 135.215962 124.7665)
		(end 134.007962 124.7665)
		(width 0.127)
		(layer "F.Cu")
		(net 2)
	)
	(segment
		(start 99.694036 178.883)
		(end 98.041888 178.883)
		(width 0.127)
		(layer "F.Cu")
		(net 2)
	)
	(segment
		(start 80.442962 171.035646)
		(end 80.442962 170.3415)
		(width 0.127)
		(layer "F.Cu")
		(net 2)
	)
	(segment
		(start 84.816962 175.409646)
		(end 80.442962 171.035646)
		(width 0.127)
		(layer "F.Cu")
		(net 2)
	)
	(segment
		(start 129.926962 158.759166)
		(end 129.927962 158.760166)
		(width 0.127)
		(layer "F.Cu")
		(net 2)
	)
	(segment
		(start 99.880536 178.6965)
		(end 99.694036 178.883)
		(width 0.127)
		(layer "F.Cu")
		(net 2)
	)
	(segment
		(start 122.163296 161.5945)
		(end 105.070296 178.6875)
		(width 0.127)
		(layer "F.Cu")
		(net 2)
	)
	(segment
		(start 129.926962 158.756962)
		(end 129.926962 158.759166)
		(width 0.127)
		(layer "F.Cu")
		(net 2)
	)
	(segment
		(start 134.007962 125.3765)
		(end 134.007962 136.982882)
		(width 0.127)
		(layer "F.Cu")
		(net 2)
	)
	(segment
		(start 133.827962 124.7415)
		(end 133.827962 123.8175)
		(width 0.254)
		(layer "F.Cu")
		(net 2)
	)
	(segment
		(start 88.094816 178.6875)
		(end 88.093402 178.6875)
		(width 0.127)
		(layer "F.Cu")
		(net 2)
	)
	(segment
		(start 129.793 156.044796)
		(end 129.793 158.623)
		(width 0.127)
		(layer "F.Cu")
		(net 2)
	)
	(segment
		(start 133.827962 124.7415)
		(end 135.240962 124.7415)
		(width 0.254)
		(layer "F.Cu")
		(net 2)
	)
	(segment
		(start 98.041888 178.883)
		(end 97.855388 178.6965)
		(width 0.127)
		(layer "F.Cu")
		(net 2)
	)
	(segment
		(start 132.268962 138.721882)
		(end 132.268962 153.568834)
		(width 0.127)
		(layer "F.Cu")
		(net 2)
	)
	(segment
		(start 105.0125 178.6875)
		(end 105.0035 178.6965)
		(width 0.127)
		(layer "F.Cu")
		(net 2)
	)
	(segment
		(start 129.793 158.623)
		(end 129.926962 158.756962)
		(width 0.127)
		(layer "F.Cu")
		(net 2)
	)
	(segment
		(start 135.240962 124.7415)
		(end 135.240962 120.6435)
		(width 0.254)
		(layer "F.Cu")
		(net 2)
	)
	(segment
		(start 132.268962 153.568834)
		(end 129.793 156.044796)
		(width 0.127)
		(layer "F.Cu")
		(net 2)
	)
	(segment
		(start 105.070296 178.6875)
		(end 105.0125 178.6875)
		(width 0.127)
		(layer "F.Cu")
		(net 2)
	)
	(segment
		(start 105.0035 178.6965)
		(end 99.880536 178.6965)
		(width 0.127)
		(layer "F.Cu")
		(net 2)
	)
	(segment
		(start 88.103816 178.6965)
		(end 88.094816 178.6875)
		(width 0.127)
		(layer "F.Cu")
		(net 2)
	)
	(segment
		(start 133.827962 125.1965)
		(end 134.007962 125.3765)
		(width 0.127)
		(layer "F.Cu")
		(net 2)
	)
	(segment
		(start 129.166376 161.5945)
		(end 122.163296 161.5945)
		(width 0.127)
		(layer "F.Cu")
		(net 2)
	)
	(segment
		(start 84.816962 175.41106)
		(end 84.816962 175.409646)
		(width 0.127)
		(layer "F.Cu")
		(net 2)
	)
	(segment
		(start 88.093402 178.6875)
		(end 84.816962 175.41106)
		(width 0.127)
		(layer "F.Cu")
		(net 2)
	)
	(segment
		(start 129.927962 160.832914)
		(end 129.166376 161.5945)
		(width 0.127)
		(layer "F.Cu")
		(net 2)
	)
	(segment
		(start 133.827962 124.7415)
		(end 133.827962 125.1965)
		(width 0.127)
		(layer "F.Cu")
		(net 2)
	)
	(segment
		(start 93.742462 145.2005)
		(end 93.117962 145.2005)
		(width 0.2)
		(layer "F.Cu")
		(net 3)
	)
	(segment
		(start 82.367962 136.359236)
		(end 83.329962 136.359236)
		(width 0.2)
		(layer "F.Cu")
		(net 3)
	)
	(segment
		(start 135.118962 112.8905)
		(end 133.941962 112.8905)
		(width 0.254)
		(layer "F.Cu")
		(net 3)
	)
	(segment
		(start 82.242962 154.728999)
		(end 82.242962 153.104001)
		(width 0.15)
		(layer "F.Cu")
		(net 3)
	)
	(segment
		(start 140.372962 126.4615)
		(end 140.367962 126.4565)
		(width 0.15)
		(layer "F.Cu")
		(net 3)
	)
	(segment
		(start 91.047962 147.1165)
		(end 91.692962 147.7615)
		(width 0.2)
		(layer "F.Cu")
		(net 3)
	)
	(segment
		(start 88.108962 143.907236)
		(end 88.108962 144.4255)
		(width 0.15)
		(layer "F.Cu")
		(net 3)
	)
	(segment
		(start 83.530962 138.791368)
		(end 83.083962 139.238368)
		(width 0.254)
		(layer "F.Cu")
		(net 3)
	)
	(segment
		(start 113.267462 155.716)
		(end 113.267962 155.7165)
		(width 0.15)
		(layer "F.Cu")
		(net 3)
	)
	(segment
		(start 140.092962 135.979)
		(end 140.092962 135.204)
		(width 0.127)
		(layer "F.Cu")
		(net 3)
	)
	(segment
		(start 115.554961 162.916)
		(end 116.317462 162.916)
		(width 0.15)
		(layer "F.Cu")
		(net 3)
	)
	(segment
		(start 96.483962 126.74783)
		(end 96.483962 124.8165)
		(width 0.2)
		(layer "F.Cu")
		(net 3)
	)
	(segment
		(start 83.642962 119.9665)
		(end 82.992962 119.9665)
		(width 0.4)
		(layer "F.Cu")
		(net 3)
	)
	(segment
		(start 140.192962 159.6915)
		(end 139.517962 159.0165)
		(width 0.254)
		(layer "F.Cu")
		(net 3)
	)
	(segment
		(start 86.158962 144.2325)
		(end 86.167962 144.2415)
		(width 0.15)
		(layer "F.Cu")
		(net 3)
	)
	(segment
		(start 67.492962 175.5665)
		(end 68.167962 174.8915)
		(width 0.254)
		(layer "F.Cu")
		(net 3)
	)
	(segment
		(start 141.905462 150.3415)
		(end 142.680462 150.3415)
		(width 0.127)
		(layer "F.Cu")
		(net 3)
	)
	(segment
		(start 92.737752 149.66129)
		(end 92.737752 149.04671)
		(width 0.254)
		(layer "F.Cu")
		(net 3)
	)
	(segment
		(start 75.503962 177.2025)
		(end 76.142962 177.8415)
		(width 0.2)
		(layer "F.Cu")
		(net 3)
	)
	(segment
		(start 113.187962 159.316)
		(end 112.473961 159.316)
		(width 0.15)
		(layer "F.Cu")
		(net 3)
	)
	(segment
		(start 141.905462 144.3915)
		(end 142.680462 144.3915)
		(width 0.127)
		(layer "F.Cu")
		(net 3)
	)
	(segment
		(start 83.083962 140.307236)
		(end 83.083962 139.332236)
		(width 0.254)
		(layer "F.Cu")
		(net 3)
	)
	(segment
		(start 135.192962 142.3665)
		(end 135.292962 142.4665)
		(width 0.2)
		(layer "F.Cu")
		(net 3)
	)
	(segment
		(start 93.917962 149.9415)
		(end 93.917962 151.4915)
		(width 0.15)
		(layer "F.Cu")
		(net 3)
	)
	(segment
		(start 76.677962 147.1165)
		(end 77.467462 147.1165)
		(width 0.15)
		(layer "F.Cu")
		(net 3)
	)
	(segment
		(start 141.342962 144.4665)
		(end 141.417962 144.3915)
		(width 0.127)
		(layer "F.Cu")
		(net 3)
	)
	(segment
		(start 77.067962 158.52037)
		(end 77.491092 158.9435)
		(width 0.15)
		(layer "F.Cu")
		(net 3)
	)
	(segment
		(start 61.117962 177.2075)
		(end 60.585962 177.2075)
		(width 0.254)
		(layer "F.Cu")
		(net 3)
	)
	(segment
		(start 97.567962 130.5395)
		(end 96.765962 130.5395)
		(width 0.18)
		(layer "F.Cu")
		(net 3)
	)
	(segment
		(start 88.693962 148.3655)
		(end 88.693962 149.3175)
		(width 0.2)
		(layer "F.Cu")
		(net 3)
	)
	(segment
		(start 96.381962 121.2285)
		(end 96.381962 121.2125)
		(width 0.254)
		(layer "F.Cu")
		(net 3)
	)
	(segment
		(start 125.618962 112.8905)
		(end 124.573962 112.8905)
		(width 0.254)
		(layer "F.Cu")
		(net 3)
	)
	(segment
		(start 93.117962 145.2005)
		(end 92.717962 144.8005)
		(width 0.2)
		(layer "F.Cu")
		(net 3)
	)
	(segment
		(start 91.342962 157.1935)
		(end 90.407962 156.2585)
		(width 0.15)
		(layer "F.Cu")
		(net 3)
	)
	(segment
		(start 72.317962 167.4815)
		(end 72.387962 167.4115)
		(width 0.2)
		(layer "F.Cu")
		(net 3)
	)
	(segment
		(start 96.219962 119.1165)
		(end 96.219962 120.5665)
		(width 0.254)
		(layer "F.Cu")
		(net 3)
	)
	(segment
		(start 128.783962 118.6665)
		(end 128.017962 118.6665)
		(width 0.254)
		(layer "F.Cu")
		(net 3)
	)
	(segment
		(start 113.280962 164.424001)
		(end 112.973961 164.117)
		(width 0.15)
		(layer "F.Cu")
		(net 3)
	)
	(segment
		(start 135.709962 159.6545)
		(end 135.732962 159.6775)
		(width 0.3)
		(layer "F.Cu")
		(net 3)
	)
	(segment
		(start 124.573962 112.8905)
		(end 124.557962 112.9065)
		(width 0.254)
		(layer "F.Cu")
		(net 3)
	)
	(segment
		(start 136.030462 161.454)
		(end 135.692962 161.1165)
		(width 0.35)
		(layer "F.Cu")
		(net 3)
	)
	(segment
		(start 64.499962 176.1845)
		(end 65.092962 176.1845)
		(width 0.254)
		(layer "F.Cu")
		(net 3)
	)
	(segment
		(start 124.317962 117.7665)
		(end 123.987962 118.0965)
		(width 0.15)
		(layer "F.Cu")
		(net 3)
	)
	(segment
		(start 62.808962 176.2095)
		(end 62.817962 176.2005)
		(width 0.254)
		(layer "F.Cu")
		(net 3)
	)
	(segment
		(start 96.467962 145.5165)
		(end 96.717962 145.2665)
		(width 0.2)
		(layer "F.Cu")
		(net 3)
	)
	(segment
		(start 85.317962 138.707236)
		(end 84.367962 138.707236)
		(width 0.15)
		(layer "F.Cu")
		(net 3)
	)
	(segment
		(start 75.503962 177.2025)
		(end 76.015962 177.2025)
		(width 0.2)
		(layer "F.Cu")
		(net 3)
	)
	(segment
		(start 77.467462 147.1165)
		(end 77.667962 147.317)
		(width 0.15)
		(layer "F.Cu")
		(net 3)
	)
	(segment
		(start 115.554961 148.517)
		(end 116.317462 148.517)
		(width 0.127)
		(layer "F.Cu")
		(net 3)
	)
	(segment
		(start 67.192962 176.6415)
		(end 67.192962 176.1665)
		(width 0.254)
		(layer "F.Cu")
		(net 3)
	)
	(segment
		(start 135.099063 125.9465)
		(end 135.319016 125.726547)
		(width 0.2)
		(layer "F.Cu")
		(net 3)
	)
	(segment
		(start 106.112462 125.736867)
		(end 106.112462 126.352)
		(width 0.15)
		(layer "F.Cu")
		(net 3)
	)
	(segment
		(start 106.112462 124.961867)
		(end 106.112462 125.736867)
		(width 0.15)
		(layer "F.Cu")
		(net 3)
	)
	(segment
		(start 133.680462 147.1665)
		(end 133.042961 147.1665)
		(width 0.127)
		(layer "F.Cu")
		(net 3)
	)
	(segment
		(start 83.088073 152.171389)
		(end 83.567962 151.6915)
		(width 0.15)
		(layer "F.Cu")
		(net 3)
	)
	(segment
		(start 116.692962 140.3415)
		(end 116.317962 140.7165)
		(width 0.2)
		(layer "F.Cu")
		(net 3)
	)
	(segment
		(start 109.112462 126.347)
		(end 109.112462 124.954)
		(width 0.15)
		(layer "F.Cu")
		(net 3)
	)
	(segment
		(start 85.395823 132.922639)
		(end 85.726962 132.5915)
		(width 0.2)
		(layer "F.Cu")
		(net 3)
	)
	(segment
		(start 137.313962 157.3155)
		(end 137.313962 158.1925)
		(width 0.4)
		(layer "F.Cu")
		(net 3)
	)
	(segment
		(start 133.680462 150.1285)
		(end 133.392962 150.1285)
		(width 0.127)
		(layer "F.Cu")
		(net 3)
	)
	(segment
		(start 137.617962 158.4965)
		(end 138.427962 158.4965)
		(width 0.4)
		(layer "F.Cu")
		(net 3)
	)
	(segment
		(start 113.342448 162.916)
		(end 113.342948 162.9165)
		(width 0.15)
		(layer "F.Cu")
		(net 3)
	)
	(segment
		(start 83.530962 138.729236)
		(end 84.345962 138.729236)
		(width 0.254)
		(layer "F.Cu")
		(net 3)
	)
	(segment
		(start 84.142962 146.6165)
		(end 84.717962 146.6165)
		(width 0.127)
		(layer "F.Cu")
		(net 3)
	)
	(segment
		(start 80.942462 148.917)
		(end 81.554961 148.917)
		(width 0.15)
		(layer "F.Cu")
		(net 3)
	)
	(segment
		(start 117.627962 140.3415)
		(end 116.692962 140.3415)
		(width 0.2)
		(layer "F.Cu")
		(net 3)
	)
	(segment
		(start 141.905462 147.3665)
		(end 142.680462 147.3665)
		(width 0.127)
		(layer "F.Cu")
		(net 3)
	)
	(segment
		(start 116.104961 164.117)
		(end 115.554961 164.117)
		(width 0.15)
		(layer "F.Cu")
		(net 3)
	)
	(segment
		(start 82.982962 119.9565)
		(end 82.992962 119.9665)
		(width 0.4)
		(layer "F.Cu")
		(net 3)
	)
	(segment
		(start 77.667962 147.317)
		(end 78.473961 147.317)
		(width 0.15)
		(layer "F.Cu")
		(net 3)
	)
	(segment
		(start 76.117962 167.6665)
		(end 76.142962 167.6915)
		(width 0.2)
		(layer "F.Cu")
		(net 3)
	)
	(segment
		(start 82.054961 152.916)
		(end 81.554961 152.916)
		(width 0.15)
		(layer "F.Cu")
		(net 3)
	)
	(segment
		(start 115.554961 160.516)
		(end 116.317462 160.516)
		(width 0.15)
		(layer "F.Cu")
		(net 3)
	)
	(segment
		(start 133.692962 150.1415)
		(end 134.467962 150.1415)
		(width 0.127)
		(layer "F.Cu")
		(net 3)
	)
	(segment
		(start 50.737962 121.0175)
		(end 50.737962 117.3865)
		(width 1)
		(layer "F.Cu")
		(net 3)
	)
	(segment
		(start 113.157962 158.116)
		(end 112.473961 158.116)
		(width 0.15)
		(layer "F.Cu")
		(net 3)
	)
	(segment
		(start 98.197962 143.1865)
		(end 97.967962 143.4165)
		(width 0.2)
		(layer "F.Cu")
		(net 3)
	)
	(segment
		(start 132.937962 161.9765)
		(end 133.460462 161.454)
		(width 0.2)
		(layer "F.Cu")
		(net 3)
	)
	(segment
		(start 102.177962 125.3065)
		(end 103.327962 125.3065)
		(width 0.254)
		(layer "F.Cu")
		(net 3)
	)
	(segment
		(start 133.692962 147.1665)
		(end 134.467962 147.1665)
		(width 0.127)
		(layer "F.Cu")
		(net 3)
	)
	(segment
		(start 75.367962 158.4915)
		(end 75.367962 157.615029)
		(width 0.2)
		(layer "F.Cu")
		(net 3)
	)
	(segment
		(start 102.177962 126.7565)
		(end 103.327962 126.7565)
		(width 0.254)
		(layer "F.Cu")
		(net 3)
	)
	(segment
		(start 94.367962 126.7665)
		(end 95.157292 126.7665)
		(width 0.2)
		(layer "F.Cu")
		(net 3)
	)
	(segment
		(start 116.592962 145.5665)
		(end 116.592962 145.5165)
		(width 0.15)
		(layer "F.Cu")
		(net 3)
	)
	(segment
		(start 105.357962 124.1365)
		(end 105.357962 122.5705)
		(width 0.2)
		(layer "F.Cu")
		(net 3)
	)
	(segment
		(start 95.157292 126.7665)
		(end 95.411292 127.0205)
		(width 0.2)
		(layer "F.Cu")
		(net 3)
	)
	(segment
		(start 112.473961 162.916)
		(end 113.342448 162.916)
		(width 0.15)
		(layer "F.Cu")
		(net 3)
	)
	(segment
		(start 90.467962 142.657236)
		(end 90.467962 140.9165)
		(width 0.15)
		(layer "F.Cu")
		(net 3)
	)
	(segment
		(start 75.367962 157.615029)
		(end 75.442962 157.540029)
		(width 0.2)
		(layer "F.Cu")
		(net 3)
	)
	(segment
		(start 132.913962 158.1325)
		(end 132.913962 157.3155)
		(width 0.4)
		(layer "F.Cu")
		(net 3)
	)
	(segment
		(start 38.678962 121.4865)
		(end 39.118962 121.0465)
		(width 0.35)
		(layer "F.Cu")
		(net 3)
	)
	(segment
		(start 139.192962 148.1415)
		(end 139.516962 148.4655)
		(width 0.2)
		(layer "F.Cu")
		(net 3)
	)
	(segment
		(start 133.817962 116.6165)
		(end 133.817962 115.5165)
		(width 0.254)
		(layer "F.Cu")
		(net 3)
	)
	(segment
		(start 109.867962 120.9265)
		(end 109.847962 120.9065)
		(width 0.2)
		(layer "F.Cu")
		(net 3)
	)
	(segment
		(start 90.492962 146.0655)
		(end 91.391962 146.0655)
		(width 0.2)
		(layer "F.Cu")
		(net 3)
	)
	(segment
		(start 140.292962 159.6915)
		(end 140.192962 159.6915)
		(width 0.254)
		(layer "F.Cu")
		(net 3)
	)
	(segment
		(start 140.372962 127.4315)
		(end 141.229962 127.4315)
		(width 0.15)
		(layer "F.Cu")
		(net 3)
	)
	(segment
		(start 112.473961 146.117)
		(end 111.666957 146.117)
		(width 0.15)
		(layer "F.Cu")
		(net 3)
	)
	(segment
		(start 132.342962 120.012567)
		(end 132.342962 119.329)
		(width 0.15)
		(layer "F.Cu")
		(net 3)
	)
	(segment
		(start 76.580962 119.102)
		(end 76.034962 119.102)
		(width 0.15)
		(layer "F.Cu")
		(net 3)
	)
	(segment
		(start 99.367962 122.275)
		(end 99.367962 122.7965)
		(width 0.15)
		(layer "F.Cu")
		(net 3)
	)
	(segment
		(start 80.465962 169.3435)
		(end 80.982962 168.8265)
		(width 0.2)
		(layer "F.Cu")
		(net 3)
	)
	(segment
		(start 67.192962 175.1915)
		(end 67.492962 175.4915)
		(width 0.254)
		(layer "F.Cu")
		(net 3)
	)
	(segment
		(start 78.473961 156.517)
		(end 77.69347 156.517)
		(width 0.15)
		(layer "F.Cu")
		(net 3)
	)
	(segment
		(start 67.192962 175.8665)
		(end 67.492962 175.5665)
		(width 0.254)
		(layer "F.Cu")
		(net 3)
	)
	(segment
		(start 66.092962 176.1845)
		(end 65.092962 176.1845)
		(width 0.254)
		(layer "F.Cu")
		(net 3)
	)
	(segment
		(start 86.167962 144.5365)
		(end 85.687962 145.0165)
		(width 0.15)
		(layer "F.Cu")
		(net 3)
	)
	(segment
		(start 66.092962 177.2165)
		(end 66.617962 177.2165)
		(width 0.254)
		(layer "F.Cu")
		(net 3)
	)
	(segment
		(start 96.381962 121.7165)
		(end 96.381962 121.2285)
		(width 0.254)
		(layer "F.Cu")
		(net 3)
	)
	(segment
		(start 112.473961 147.317)
		(end 113.192466 147.317)
		(width 0.15)
		(layer "F.Cu")
		(net 3)
	)
	(segment
		(start 94.017962 135.507236)
		(end 94.592962 135.507236)
		(width 0.15)
		(layer "F.Cu")
		(net 3)
	)
	(segment
		(start 84.140724 149.104262)
		(end 83.577962 148.5415)
		(width 0.15)
		(layer "F.Cu")
		(net 3)
	)
	(segment
		(start 90.467962 142.657236)
		(end 90.467962 143.2665)
		(width 0.15)
		(layer "F.Cu")
		(net 3)
	)
	(segment
		(start 113.165462 150.919)
		(end 113.167962 150.9165)
		(width 0.15)
		(layer "F.Cu")
		(net 3)
	)
	(segment
		(start 115.554961 158.116)
		(end 116.317462 158.116)
		(width 0.15)
		(layer "F.Cu")
		(net 3)
	)
	(segment
		(start 95.411292 127.0205)
		(end 96.211292 127.0205)
		(width 0.2)
		(layer "F.Cu")
		(net 3)
	)
	(segment
		(start 86.762962 152.2465)
		(end 86.767962 152.2415)
		(width 0.15)
		(layer "F.Cu")
		(net 3)
	)
	(segment
		(start 80.092962 149.7665)
		(end 79.642462 149.316)
		(width 0.15)
		(layer "F.Cu")
		(net 3)
	)
	(segment
		(start 116.317462 158.116)
		(end 116.317962 158.1165)
		(width 0.15)
		(layer "F.Cu")
		(net 3)
	)
	(segment
		(start 113.147962 156.917)
		(end 112.473961 156.917)
		(width 0.15)
		(layer "F.Cu")
		(net 3)
	)
	(segment
		(start 113.280962 164.534)
		(end 113.280962 164.424001)
		(width 0.15)
		(layer "F.Cu")
		(net 3)
	)
	(segment
		(start 86.826962 152.2415)
		(end 87.367962 152.7825)
		(width 0.15)
		(layer "F.Cu")
		(net 3)
	)
	(segment
		(start 68.592962 174.0665)
		(end 68.592962 174.4415)
		(width 0.254)
		(layer "F.Cu")
		(net 3)
	)
	(segment
		(start 115.554961 147.317)
		(end 116.317462 147.317)
		(width 0.15)
		(layer "F.Cu")
		(net 3)
	)
	(segment
		(start 81.547962 144.4915)
		(end 81.547962 144.909001)
		(width 0.15)
		(layer "F.Cu")
		(net 3)
	)
	(segment
		(start 103.327962 126.7565)
		(end 103.327962 126.063)
		(width 0.254)
		(layer "F.Cu")
		(net 3)
	)
	(segment
		(start 82.054961 154.917)
		(end 82.242962 154.728999)
		(width 0.15)
		(layer "F.Cu")
		(net 3)
	)
	(segment
		(start 142.680462 147.3665)
		(end 143.242962 147.3665)
		(width 0.127)
		(layer "F.Cu")
		(net 3)
	)
	(segment
		(start 69.817962 168.8415)
		(end 69.817962 170.0415)
		(width 0.2)
		(layer "F.Cu")
		(net 3)
	)
	(segment
		(start 83.088073 152.202611)
		(end 83.542962 152.6575)
		(width 0.15)
		(layer "F.Cu")
		(net 3)
	)
	(segment
		(start 96.076962 138.782236)
		(end 96.733698 138.782236)
		(width 0.15)
		(layer "F.Cu")
		(net 3)
	)
	(segment
		(start 96.492962 124.2165)
		(end 96.483962 124.2255)
		(width 0.2)
		(layer "F.Cu")
		(net 3)
	)
	(segment
		(start 92.767962 121.696929)
		(end 92.767962 122.239108)
		(width 0.15)
		(layer "F.Cu")
		(net 3)
	)
	(segment
		(start 77.817962 144.7165)
		(end 78.017462 144.916)
		(width 0.15)
		(layer "F.Cu")
		(net 3)
	)
	(segment
		(start 96.381962 122.6565)
		(end 96.381962 121.7165)
		(width 0.2)
		(layer "F.Cu")
		(net 3)
	)
	(segment
		(start 80.842962 164.328999)
		(end 80.842962 164.5665)
		(width 0.15)
		(layer "F.Cu")
		(net 3)
	)
	(segment
		(start 66.092962 176.1845)
		(end 66.092962 177.2165)
		(width 0.254)
		(layer "F.Cu")
		(net 3)
	)
	(segment
		(start 116.255962 164.268001)
		(end 116.104961 164.117)
		(width 0.15)
		(layer "F.Cu")
		(net 3)
	)
	(segment
		(start 135.692962 161.1165)
		(end 135.692962 160.7415)
		(width 0.35)
		(layer "F.Cu")
		(net 3)
	)
	(segment
		(start 80.833684 156.517)
		(end 81.554961 156.517)
		(width 0.15)
		(layer "F.Cu")
		(net 3)
	)
	(segment
		(start 91.867962 131.948236)
		(end 91.867962 131.2165)
		(width 0.2)
		(layer "F.Cu")
		(net 3)
	)
	(segment
		(start 80.693058 157.716)
		(end 80.548302 157.571244)
		(width 0.15)
		(layer "F.Cu")
		(net 3)
	)
	(segment
		(start 97.092962 122.8915)
		(end 97.067962 122.8915)
		(width 0.2)
		(layer "F.Cu")
		(net 3)
	)
	(segment
		(start 74.172962 124.6315)
		(end 74.872962 124.6315)
		(width 0.4)
		(layer "F.Cu")
		(net 3)
	)
	(segment
		(start 106.866962 120.9055)
		(end 106.847962 120.8865)
		(width 0.2)
		(layer "F.Cu")
		(net 3)
	)
	(segment
		(start 124.317962 117.8915)
		(end 124.617962 118.1915)
		(width 0.254)
		(layer "F.Cu")
		(net 3)
	)
	(segment
		(start 67.492962 175.4915)
		(end 67.492962 175.5665)
		(width 0.254)
		(layer "F.Cu")
		(net 3)
	)
	(segment
		(start 133.967962 158.5165)
		(end 133.297962 158.5165)
		(width 0.4)
		(layer "F.Cu")
		(net 3)
	)
	(segment
		(start 140.292962 158.2665)
		(end 140.217962 158.2665)
		(width 0.254)
		(layer "F.Cu")
		(net 3)
	)
	(segment
		(start 82.506462 138.609736)
		(end 82.958962 138.157236)
		(width 0.254)
		(layer "F.Cu")
		(net 3)
	)
	(segment
		(start 77.844832 158.9435)
		(end 77.871332 158.917)
		(width 0.15)
		(layer "F.Cu")
		(net 3)
	)
	(segment
		(start 112.473961 161.715)
		(end 113.266462 161.715)
		(width 0.15)
		(layer "F.Cu")
		(net 3)
	)
	(segment
		(start 134.533962 159.0825)
		(end 133.967962 158.5165)
		(width 0.4)
		(layer "F.Cu")
		(net 3)
	)
	(segment
		(start 85.920962 145.9635)
		(end 85.920962 145.2495)
		(width 0.127)
		(layer "F.Cu")
		(net 3)
	)
	(segment
		(start 140.092962 135.9665)
		(end 140.092962 136.6415)
		(width 0.127)
		(layer "F.Cu")
		(net 3)
	)
	(segment
		(start 116.6 156.9165)
		(end 116.5995 156.917)
		(width 0.15)
		(layer "F.Cu")
		(net 3)
	)
	(segment
		(start 82.506462 138.7665)
		(end 82.518226 138.7665)
		(width 0.254)
		(layer "F.Cu")
		(net 3)
	)
	(segment
		(start 90.407962 156.2585)
		(end 90.407962 154.9365)
		(width 0.15)
		(layer "F.Cu")
		(net 3)
	)
	(segment
		(start 133.941962 112.8905)
		(end 133.897962 112.8465)
		(width 0.254)
		(layer "F.Cu")
		(net 3)
	)
	(segment
		(start 135.392962 161.454)
		(end 135.692962 161.154)
		(width 0.35)
		(layer "F.Cu")
		(net 3)
	)
	(segment
		(start 99.569462 148.5915)
		(end 100.592226 148.5915)
		(width 0.2)
		(layer "F.Cu")
		(net 3)
	)
	(segment
		(start 79.530962 121.754)
		(end 79.530962 122.537455)
		(width 0.127)
		(layer "F.Cu")
		(net 3)
	)
	(segment
		(start 132.937962 155.3715)
		(end 132.937962 156.0165)
		(width 0.254)
		(layer "F.Cu")
		(net 3)
	)
	(segment
		(start 116.69513 153.318)
		(end 115.554961 153.318)
		(width 0.15)
		(layer "F.Cu")
		(net 3)
	)
	(segment
		(start 90.492962 147.1165)
		(end 91.047962 147.1165)
		(width 0.2)
		(layer "F.Cu")
		(net 3)
	)
	(segment
		(start 112.473961 152.116)
		(end 111.718462 152.116)
		(width 0.15)
		(layer "F.Cu")
		(net 3)
	)
	(segment
		(start 96.467962 146.7655)
		(end 95.868962 146.7655)
		(width 0.2)
		(layer "F.Cu")
		(net 3)
	)
	(segment
		(start 85.517962 146.5665)
		(end 85.567962 146.6165)
		(width 0.127)
		(layer "F.Cu")
		(net 3)
	)
	(segment
		(start 81.554961 150.919)
		(end 80.940462 150.919)
		(width 0.15)
		(layer "F.Cu")
		(net 3)
	)
	(segment
		(start 85.517962 145.1865)
		(end 85.687962 145.0165)
		(width 0.127)
		(layer "F.Cu")
		(net 3)
	)
	(segment
		(start 116.5995 156.917)
		(end 115.554961 156.917)
		(width 0.15)
		(layer "F.Cu")
		(net 3)
	)
	(segment
		(start 84.367962 138.707236)
		(end 83.833962 138.707236)
		(width 0.2)
		(layer "F.Cu")
		(net 3)
	)
	(segment
		(start 133.817962 116.6165)
		(end 133.817962 117.6165)
		(width 0.15)
		(layer "F.Cu")
		(net 3)
	)
	(segment
		(start 80.675573 156.358889)
		(end 80.833684 156.517)
		(width 0.15)
		(layer "F.Cu")
		(net 3)
	)
	(segment
		(start 81.554961 157.716)
		(end 80.693058 157.716)
		(width 0.15)
		(layer "F.Cu")
		(net 3)
	)
	(segment
		(start 101.267962 150.1145)
		(end 101.267962 150.6915)
		(width 0.127)
		(layer "F.Cu")
		(net 3)
	)
	(segment
		(start 85.920962 146.9195)
		(end 85.617962 146.6165)
		(width 0.127)
		(layer "F.Cu")
		(net 3)
	)
	(segment
		(start 93.183962 147.4165)
		(end 93.608962 147.8415)
		(width 0.15)
		(layer "F.Cu")
		(net 3)
	)
	(segment
		(start 114.668462 146.117)
		(end 114.217962 145.6665)
		(width 0.15)
		(layer "F.Cu")
		(net 3)
	)
	(segment
		(start 80.092962 149.7665)
		(end 80.942462 148.917)
		(width 0.15)
		(layer "F.Cu")
		(net 3)
	)
	(segment
		(start 77.95124 151.318)
		(end 78.473961 151.318)
		(width 0.127)
		(layer "F.Cu")
		(net 3)
	)
	(segment
		(start 103.327962 125.3065)
		(end 103.327962 126.063)
		(width 0.254)
		(layer "F.Cu")
		(net 3)
	)
	(segment
		(start 80.851462 146.117)
		(end 81.554961 146.117)
		(width 0.15)
		(layer "F.Cu")
		(net 3)
	)
	(segment
		(start 142.680462 144.3915)
		(end 143.242962 144.3915)
		(width 0.127)
		(layer "F.Cu")
		(net 3)
	)
	(segment
		(start 89.817962 120.0915)
		(end 89.817962 120.9165)
		(width 0.254)
		(layer "F.Cu")
		(net 3)
	)
	(segment
		(start 77.832782 144.60168)
		(end 77.817962 144.6165)
		(width 0.15)
		(layer "F.Cu")
		(net 3)
	)
	(segment
		(start 65.62 169.78)
		(end 65.9835 169.4165)
		(width 0.254)
		(layer "F.Cu")
		(net 3)
	)
	(segment
		(start 79.530962 120.979)
		(end 79.530962 120.5045)
		(width 0.127)
		(layer "F.Cu")
		(net 3)
	)
	(segment
		(start 76.580962 118.580962)
		(end 76.25 118.25)
		(width 0.15)
		(layer "F.Cu")
		(net 3)
	)
	(segment
		(start 116.042462 146.117)
		(end 116.592962 145.5665)
		(width 0.15)
		(layer "F.Cu")
		(net 3)
	)
	(segment
		(start 103.327962 126.063)
		(end 103.327962 127.6365)
		(width 0.254)
		(layer "F.Cu")
		(net 3)
	)
	(segment
		(start 112.867962 120.9165)
		(end 112.842962 120.8915)
		(width 0.2)
		(layer "F.Cu")
		(net 3)
	)
	(segment
		(start 85.567962 146.6165)
		(end 84.717962 146.6165)
		(width 0.127)
		(layer "F.Cu")
		(net 3)
	)
	(segment
		(start 116.317462 159.316)
		(end 116.317962 159.3165)
		(width 0.15)
		(layer "F.Cu")
		(net 3)
	)
	(segment
		(start 96.806962 120.6165)
		(end 96.806962 119.9775)
		(width 0.254)
		(layer "F.Cu")
		(net 3)
	)
	(segment
		(start 82.317962 147.4065)
		(end 82.228462 147.317)
		(width 0.15)
		(layer "F.Cu")
		(net 3)
	)
	(segment
		(start 68.592962 174.4665)
		(end 68.592962 174.4415)
		(width 0.254)
		(layer "F.Cu")
		(net 3)
	)
	(segment
		(start 76.567962 119.9665)
		(end 75.942962 119.9665)
		(width 0.4)
		(layer "F.Cu")
		(net 3)
	)
	(segment
		(start 140.067962 140.4165)
		(end 140.067962 140.9665)
		(width 0.2)
		(layer "F.Cu")
		(net 3)
	)
	(segment
		(start 82.982962 119.102)
		(end 82.982962 119.9565)
		(width 0.4)
		(layer "F.Cu")
		(net 3)
	)
	(segment
		(start 89.187962 131.4765)
		(end 88.734962 131.0235)
		(width 0.2)
		(layer "F.Cu")
		(net 3)
	)
	(segment
		(start 75.442962 157.042971)
		(end 74.521491 156.1215)
		(width 0.2)
		(layer "F.Cu")
		(net 3)
	)
	(segment
		(start 97.055347 121.952914)
		(end 96.818933 121.7165)
		(width 0.2)
		(layer "F.Cu")
		(net 3)
	)
	(segment
		(start 112.867962 122.5605)
		(end 112.867962 124.2415)
		(width 0.2)
		(layer "F.Cu")
		(net 3)
	)
	(segment
		(start 141.905462 141.4165)
		(end 142.680462 141.4165)
		(width 0.127)
		(layer "F.Cu")
		(net 3)
	)
	(segment
		(start 133.055961 150.1285)
		(end 133.042961 150.1415)
		(width 0.127)
		(layer "F.Cu")
		(net 3)
	)
	(segment
		(start 122.987962 119.820296)
		(end 122.948732 119.859526)
		(width 0.15)
		(layer "F.Cu")
		(net 3)
	)
	(segment
		(start 133.202245 155.215019)
		(end 133.094443 155.215019)
		(width 0.254)
		(layer "F.Cu")
		(net 3)
	)
	(segment
		(start 86.167962 144.2415)
		(end 86.167962 144.5365)
		(width 0.15)
		(layer "F.Cu")
		(net 3)
	)
	(segment
		(start 81.554961 164.117)
		(end 81.054961 164.117)
		(width 0.15)
		(layer "F.Cu")
		(net 3)
	)
	(segment
		(start 68.790962 175.130476)
		(end 68.506938 175.130476)
		(width 0.254)
		(layer "F.Cu")
		(net 3)
	)
	(segment
		(start 75.101962 177.6045)
		(end 75.503962 177.2025)
		(width 0.2)
		(layer "F.Cu")
		(net 3)
	)
	(segment
		(start 89.187962 132.442236)
		(end 89.187962 131.4765)
		(width 0.2)
		(layer "F.Cu")
		(net 3)
	)
	(segment
		(start 142.680462 141.4165)
		(end 143.242962 141.4165)
		(width 0.127)
		(layer "F.Cu")
		(net 3)
	)
	(segment
		(start 85.242962 159.5415)
		(end 82.417962 159.5415)
		(width 0.15)
		(layer "F.Cu")
		(net 3)
	)
	(segment
		(start 116.683861 154.5195)
		(end 116.680361 154.516)
		(width 0.15)
		(layer "F.Cu")
		(net 3)
	)
	(segment
		(start 77.692962 146.117)
		(end 78.473961 146.117)
		(width 0.15)
		(layer "F.Cu")
		(net 3)
	)
	(segment
		(start 75.367962 158.4915)
		(end 75.362962 158.4865)
		(width 0.2)
		(layer "F.Cu")
		(net 3)
	)
	(segment
		(start 62.117962 177.2075)
		(end 62.117962 176.2095)
		(width 0.254)
		(layer "F.Cu")
		(net 3)
	)
	(segment
		(start 77.76861 157.716)
		(end 77.691558 157.793052)
		(width 0.15)
		(layer "F.Cu")
		(net 3)
	)
	(segment
		(start 79.530962 120.979)
		(end 79.530962 121.754)
		(width 0.127)
		(layer "F.Cu")
		(net 3)
	)
	(segment
		(start 67.174962 176.1845)
		(end 67.192962 176.1665)
		(width 0.254)
		(layer "F.Cu")
		(net 3)
	)
	(segment
		(start 108.358962 124.144958)
		(end 108.358962 122.5685)
		(width 0.2)
		(layer "F.Cu")
		(net 3)
	)
	(segment
		(start 113.187962 160.516)
		(end 112.473961 160.516)
		(width 0.15)
		(layer "F.Cu")
		(net 3)
	)
	(segment
		(start 106.866962 122.5605)
		(end 106.866962 120.9055)
		(width 0.2)
		(layer "F.Cu")
		(net 3)
	)
	(segment
		(start 71.742962 177.6915)
		(end 71.742962 177.0005)
		(width 0.254)
		(layer "F.Cu")
		(net 3)
	)
	(segment
		(start 109.867962 122.5605)
		(end 109.867962 120.9265)
		(width 0.2)
		(layer "F.Cu")
		(net 3)
	)
	(segment
		(start 70.737962 167.0165)
		(end 70.877962 167.0165)
		(width 0.127)
		(layer "F.Cu")
		(net 3)
	)
	(segment
		(start 74.387962 155.0465)
		(end 74.412962 155.0715)
		(width 0.2)
		(layer "F.Cu")
		(net 3)
	)
	(segment
		(start 95.117962 135.223236)
		(end 94.833962 135.507236)
		(width 0.2)
		(layer "F.Cu")
		(net 3)
	)
	(segment
		(start 87.392962 151.8005)
		(end 87.392962 152.7575)
		(width 0.254)
		(layer "F.Cu")
		(net 3)
	)
	(segment
		(start 108.366962 120.9155)
		(end 108.347962 120.8965)
		(width 0.2)
		(layer "F.Cu")
		(net 3)
	)
	(segment
		(start 132.342962 118.554)
		(end 132.342962 117.9665)
		(width 0.15)
		(layer "F.Cu")
		(net 3)
	)
	(segment
		(start 83.567962 151.6755)
		(end 83.567962 152.6325)
		(width 0.254)
		(layer "F.Cu")
		(net 3)
	)
	(segment
		(start 99.442962 148.718)
		(end 99.569462 148.5915)
		(width 0.2)
		(layer "F.Cu")
		(net 3)
	)
	(segment
		(start 115.554961 161.715)
		(end 116.316462 161.715)
		(width 0.15)
		(layer "F.Cu")
		(net 3)
	)
	(segment
		(start 76.617962 177.1005)
		(end 76.117962 177.1005)
		(width 0.2)
		(layer "F.Cu")
		(net 3)
	)
	(segment
		(start 135.732962 159.6775)
		(end 135.732962 160.7015)
		(width 0.3)
		(layer "F.Cu")
		(net 3)
	)
	(segment
		(start 142.680462 150.3415)
		(end 143.242962 150.3415)
		(width 0.127)
		(layer "F.Cu")
		(net 3)
	)
	(segment
		(start 139.367962 164.4165)
		(end 140.256464 164.4165)
		(width 0.2)
		(layer "F.Cu")
		(net 3)
	)
	(segment
		(start 89.817962 120.0915)
		(end 89.142962 120.0915)
		(width 0.254)
		(layer "F.Cu")
		(net 3)
	)
	(segment
		(start 74.521491 156.1215)
		(end 74.462962 156.1215)
		(width 0.2)
		(layer "F.Cu")
		(net 3)
	)
	(segment
		(start 74.172962 123.8565)
		(end 74.847962 123.8565)
		(width 0.4)
		(layer "F.Cu")
		(net 3)
	)
	(segment
		(start 122.987962 119.284)
		(end 122.987962 119.820296)
		(width 0.15)
		(layer "F.Cu")
		(net 3)
	)
	(segment
		(start 96.483962 124.2255)
		(end 96.483962 124.8165)
		(width 0.2)
		(layer "F.Cu")
		(net 3)
	)
	(segment
		(start 72.717962 177.6165)
		(end 72.717962 177.1505)
		(width 0.254)
		(layer "F.Cu")
		(net 3)
	)
	(segment
		(start 78.017462 144.916)
		(end 78.473961 144.916)
		(width 0.15)
		(layer "F.Cu")
		(net 3)
	)
	(segment
		(start 73.792962 175.566502)
		(end 73.792962 175.7915)
		(width 0.2)
		(layer "F.Cu")
		(net 3)
	)
	(segment
		(start 132.857962 124.7415)
		(end 132.857962 123.8155)
		(width 0.254)
		(layer "F.Cu")
		(net 3)
	)
	(segment
		(start 94.967962 128.9915)
		(end 94.967962 128.8665)
		(width 0.2)
		(layer "F.Cu")
		(net 3)
	)
	(segment
		(start 133.392962 150.1285)
		(end 133.055961 150.1285)
		(width 0.127)
		(layer "F.Cu")
		(net 3)
	)
	(segment
		(start 116.317462 162.916)
		(end 116.317962 162.9165)
		(width 0.15)
		(layer "F.Cu")
		(net 3)
	)
	(segment
		(start 135.692962 161.154)
		(end 135.692962 160.7415)
		(width 0.35)
		(layer "F.Cu")
		(net 3)
	)
	(segment
		(start 93.917962 149.1005)
		(end 93.608962 148.7915)
		(width 0.2)
		(layer "F.Cu")
		(net 3)
	)
	(segment
		(start 53.296962 175.0245)
		(end 51.919962 175.0245)
		(width 0.254)
		(layer "F.Cu")
		(net 3)
	)
	(segment
		(start 124.317962 116.7665)
		(end 124.317962 117.7665)
		(width 0.15)
		(layer "F.Cu")
		(net 3)
	)
	(segment
		(start 76.034962 119.102)
		(end 75.460962 118.528)
		(width 0.15)
		(layer "F.Cu")
		(net 3)
	)
	(segment
		(start 75.942962 119.9665)
		(end 75.527962 119.9665)
		(width 0.4)
		(layer "F.Cu")
		(net 3)
	)
	(segment
		(start 70.877962 167.0165)
		(end 71.317962 166.5765)
		(width 0.127)
		(layer "F.Cu")
		(net 3)
	)
	(segment
		(start 99.367962 122.7965)
		(end 99.027962 123.1365)
		(width 0.15)
		(layer "F.Cu")
		(net 3)
	)
	(segment
		(start 135.709962 159.6545)
		(end 135.709962 159.665552)
		(width 0.35)
		(layer "F.Cu")
		(net 3)
	)
	(segment
		(start 75.552962 167.6665)
		(end 76.117962 167.6665)
		(width 0.2)
		(layer "F.Cu")
		(net 3)
	)
	(segment
		(start 138.938962 159.0075)
		(end 139.517962 159.0075)
		(width 0.4)
		(layer "F.Cu")
		(net 3)
	)
	(segment
		(start 95.117962 135.223236)
		(end 95.861226 135.223236)
		(width 0.2)
		(layer "F.Cu")
		(net 3)
	)
	(segment
		(start 92.992962 148.7915)
		(end 93.608962 148.7915)
		(width 0.254)
		(layer "F.Cu")
		(net 3)
	)
	(segment
		(start 140.092962 135.204)
		(end 140.092962 134.5665)
		(width 0.127)
		(layer "F.Cu")
		(net 3)
	)
	(segment
		(start 60.585962 177.2075)
		(end 60.542962 177.2505)
		(width 0.254)
		(layer "F.Cu")
		(net 3)
	)
	(segment
		(start 130.593962 112.8905)
		(end 130.627962 112.8565)
		(width 0.254)
		(layer "F.Cu")
		(net 3)
	)
	(segment
		(start 95.092962 133.322236)
		(end 96.012226 133.322236)
		(width 0.2)
		(layer "F.Cu")
		(net 3)
	)
	(segment
		(start 116.316462 161.715)
		(end 116.317962 161.7165)
		(width 0.15)
		(layer "F.Cu")
		(net 3)
	)
	(segment
		(start 90.392962 152.3165)
		(end 90.567962 152.1415)
		(width 0.15)
		(layer "F.Cu")
		(net 3)
	)
	(segment
		(start 85.517962 145.9635)
		(end 85.517962 145.1865)
		(width 0.127)
		(layer "F.Cu")
		(net 3)
	)
	(segment
		(start 100.592226 148.5915)
		(end 101.817962 147.365764)
		(width 0.2)
		(layer "F.Cu")
		(net 3)
	)
	(segment
		(start 134.987573 150.1285)
		(end 133.392962 150.1285)
		(width 0.127)
		(layer "F.Cu")
		(net 3)
	)
	(segment
		(start 77.491092 158.9435)
		(end 77.844832 158.9435)
		(width 0.15)
		(layer "F.Cu")
		(net 3)
	)
	(segment
		(start 91.391962 146.0655)
		(end 91.392962 146.0665)
		(width 0.2)
		(layer "F.Cu")
		(net 3)
	)
	(segment
		(start 120.019962 112.8905)
		(end 121.001962 112.8905)
		(width 0.254)
		(layer "F.Cu")
		(net 3)
	)
	(segment
		(start 98.197962 142.7165)
		(end 98.197962 143.1865)
		(width 0.2)
		(layer "F.Cu")
		(net 3)
	)
	(segment
		(start 88.108962 144.4255)
		(end 87.867962 144.6665)
		(width 0.15)
		(layer "F.Cu")
		(net 3)
	)
	(segment
		(start 79.642462 149.316)
		(end 78.473961 149.316)
		(width 0.15)
		(layer "F.Cu")
		(net 3)
	)
	(segment
		(start 82.192462 159.316)
		(end 82.417962 159.5415)
		(width 0.15)
		(layer "F.Cu")
		(net 3)
	)
	(segment
		(start 134.688962 125.9465)
		(end 135.099063 125.9465)
		(width 0.2)
		(layer "F.Cu")
		(net 3)
	)
	(segment
		(start 83.508962 138.707236)
		(end 83.833962 138.707236)
		(width 0.2)
		(layer "F.Cu")
		(net 3)
	)
	(segment
		(start 88.693962 149.3175)
		(end 88.742962 149.3665)
		(width 0.2)
		(layer "F.Cu")
		(net 3)
	)
	(segment
		(start 135.004962 144.1785)
		(end 135.017962 144.1915)
		(width 0.127)
		(layer "F.Cu")
		(net 3)
	)
	(segment
		(start 109.858962 124.154958)
		(end 109.858962 122.5695)
		(width 0.2)
		(layer "F.Cu")
		(net 3)
	)
	(segment
		(start 76.015962 177.2025)
		(end 76.117962 177.1005)
		(width 0.2)
		(layer "F.Cu")
		(net 3)
	)
	(segment
		(start 96.467962 146.7655)
		(end 96.467962 145.5165)
		(width 0.2)
		(layer "F.Cu")
		(net 3)
	)
	(segment
		(start 90.567962 151.784111)
		(end 90.554526 151.770675)
		(width 0.15)
		(layer "F.Cu")
		(net 3)
	)
	(segment
		(start 83.833962 138.707236)
		(end 83.667962 138.707236)
		(width 0.2)
		(layer "F.Cu")
		(net 3)
	)
	(segment
		(start 106.858962 124.134958)
		(end 106.858962 122.5685)
		(width 0.2)
		(layer "F.Cu")
		(net 3)
	)
	(segment
		(start 135.079462 150.036611)
		(end 134.987573 150.1285)
		(width 0.127)
		(layer "F.Cu")
		(net 3)
	)
	(segment
		(start 77.963035 155.316)
		(end 78.473961 155.316)
		(width 0.127)
		(layer "F.Cu")
		(net 3)
	)
	(segment
		(start 85.517962 147.2665)
		(end 85.517962 147.7465)
		(width 0.127)
		(layer "F.Cu")
		(net 3)
	)
	(segment
		(start 66.617962 177.2165)
		(end 67.192962 176.6415)
		(width 0.254)
		(layer "F.Cu")
		(net 3)
	)
	(segment
		(start 137.862962 161.722764)
		(end 137.609226 161.9765)
		(width 0.2)
		(layer "F.Cu")
		(net 3)
	)
	(segment
		(start 112.473961 146.117)
		(end 113.418462 146.117)
		(width 0.15)
		(layer "F.Cu")
		(net 3)
	)
	(segment
		(start 101.817962 147.365764)
		(end 101.817962 146.7645)
		(width 0.2)
		(layer "F.Cu")
		(net 3)
	)
	(segment
		(start 112.473961 150.919)
		(end 113.165462 150.919)
		(width 0.15)
		(layer "F.Cu")
		(net 3)
	)
	(segment
		(start 96.219962 120.5665)
		(end 96.219962 121.0665)
		(width 0.254)
		(layer "F.Cu")
		(net 3)
	)
	(segment
		(start 116.317462 148.517)
		(end 116.317962 148.5165)
		(width 0.127)
		(layer "F.Cu")
		(net 3)
	)
	(segment
		(start 75.362962 158.4865)
		(end 74.467962 158.4865)
		(width 0.2)
		(layer "F.Cu")
		(net 3)
	)
	(segment
		(start 80.982962 168.8265)
		(end 81.017962 168.8265)
		(width 0.2)
		(layer "F.Cu")
		(net 3)
	)
	(segment
		(start 91.417962 145.5165)
		(end 91.042962 145.1415)
		(width 0.254)
		(layer "F.Cu")
		(net 3)
	)
	(segment
		(start 61.117962 176.2095)
		(end 61.117962 177.2075)
		(width 0.254)
		(layer "F.Cu")
		(net 3)
	)
	(segment
		(start 90.567962 152.1415)
		(end 90.567962 151.784111)
		(width 0.15)
		(layer "F.Cu")
		(net 3)
	)
	(segment
		(start 81.554961 154.917)
		(end 82.054961 154.917)
		(width 0.15)
		(layer "F.Cu")
		(net 3)
	)
	(segment
		(start 86.951962 152.2415)
		(end 87.392962 151.8005)
		(width 0.15)
		(layer "F.Cu")
		(net 3)
	)
	(segment
		(start 82.228462 147.317)
		(end 81.554961 147.317)
		(width 0.15)
		(layer "F.Cu")
		(net 3)
	)
	(segment
		(start 87.215962 157.2665)
		(end 87.215962 157.5685)
		(width 0.15)
		(layer "F.Cu")
		(net 3)
	)
	(segment
		(start 132.857962 124.7415)
		(end 132.867962 125.4665)
		(width 0.254)
		(layer "F.Cu")
		(net 3)
	)
	(segment
		(start 69.817962 177.3005)
		(end 69.817962 178.0665)
		(width 0.254)
		(layer "F.Cu")
		(net 3)
	)
	(segment
		(start 62.117962 176.2095)
		(end 62.808962 176.2095)
		(width 0.254)
		(layer "F.Cu")
		(net 3)
	)
	(segment
		(start 82.506462 138.7665)
		(end 82.506462 138.609736)
		(width 0.254)
		(layer "F.Cu")
		(net 3)
	)
	(segment
		(start 116.597 155.716)
		(end 115.554961 155.716)
		(width 0.15)
		(layer "F.Cu")
		(net 3)
	)
	(segment
		(start 129.519962 112.8905)
		(end 130.593962 112.8905)
		(width 0.254)
		(layer "F.Cu")
		(net 3)
	)
	(segment
		(start 137.167962 156.0165)
		(end 136.567962 155.4165)
		(width 0.254)
		(layer "F.Cu")
		(net 3)
	)
	(segment
		(start 116.317462 160.516)
		(end 116.317962 160.5165)
		(width 0.15)
		(layer "F.Cu")
		(net 3)
	)
	(segment
		(start 136.442962 149.4655)
		(end 137.543962 149.4655)
		(width 0.2)
		(layer "F.Cu")
		(net 3)
	)
	(segment
		(start 131.937962 161.9815)
		(end 132.937962 161.9815)
		(width 0.2)
		(layer "F.Cu")
		(net 3)
	)
	(segment
		(start 73.792962 175.7915)
		(end 74.230962 176.2295)
		(width 0.2)
		(layer "F.Cu")
		(net 3)
	)
	(segment
		(start 85.317962 138.707236)
		(end 89.267962 138.707236)
		(width 0.15)
		(layer "F.Cu")
		(net 3)
	)
	(segment
		(start 96.817962 119.9665)
		(end 96.217962 119.9665)
		(width 0.254)
		(layer "F.Cu")
		(net 3)
	)
	(segment
		(start 135.709962 159.6545)
		(end 135.137962 159.0825)
		(width 0.35)
		(layer "F.Cu")
		(net 3)
	)
	(segment
		(start 75.717962 178.8165)
		(end 75.117962 178.2165)
		(width 0.2)
		(layer "F.Cu")
		(net 3)
	)
	(segment
		(start 122.987962 117.9865)
		(end 122.967962 117.9665)
		(width 0.15)
		(layer "F.Cu")
		(net 3)
	)
	(segment
		(start 62.135962 177.2255)
		(end 62.817962 177.2255)
		(width 0.254)
		(layer "F.Cu")
		(net 3)
	)
	(segment
		(start 140.283962 159.0075)
		(end 139.517962 159.0075)
		(width 0.254)
		(layer "F.Cu")
		(net 3)
	)
	(segment
		(start 139.217962 144.4665)
		(end 140.393962 144.4665)
		(width 0.2)
		(layer "F.Cu")
		(net 3)
	)
	(segment
		(start 65.658962 171.6165)
		(end 64.892962 171.6165)
		(width 0.254)
		(layer "F.Cu")
		(net 3)
	)
	(segment
		(start 64.517962 177.2165)
		(end 64.342962 177.0415)
		(width 0.254)
		(layer "F.Cu")
		(net 3)
	)
	(segment
		(start 95.861226 135.223236)
		(end 95.867962 135.2165)
		(width 0.2)
		(layer "F.Cu")
		(net 3)
	)
	(segment
		(start 96.012226 133.322236)
		(end 96.017962 133.3165)
		(width 0.2)
		(layer "F.Cu")
		(net 3)
	)
	(segment
		(start 115.554961 149.717)
		(end 116.317964 149.717)
		(width 0.15)
		(layer "F.Cu")
		(net 3)
	)
	(segment
		(start 112.473961 148.517)
		(end 113.167966 148.517)
		(width 0.15)
		(layer "F.Cu")
		(net 3)
	)
	(segment
		(start 68.267962 174.8915)
		(end 68.167962 174.8915)
		(width 0.254)
		(layer "F.Cu")
		(net 3)
	)
	(segment
		(start 51.919962 175.0245)
		(end 51.917962 175.0265)
		(width 0.254)
		(layer "F.Cu")
		(net 3)
	)
	(segment
		(start 87.211617 131.324807)
		(end 87.211617 131.588845)
		(width 0.2)
		(layer "F.Cu")
		(net 3)
	)
	(segment
		(start 89.817962 119.1165)
		(end 89.817962 120.0915)
		(width 0.254)
		(layer "F.Cu")
		(net 3)
	)
	(segment
		(start 77.642962 151.626278)
		(end 77.95124 151.318)
		(width 0.127)
		(layer "F.Cu")
		(net 3)
	)
	(segment
		(start 121.001962 112.8905)
		(end 121.027962 112.9165)
		(width 0.254)
		(layer "F.Cu")
		(net 3)
	)
	(segment
		(start 96.818933 121.7165)
		(end 96.381962 121.7165)
		(width 0.2)
		(layer "F.Cu")
		(net 3)
	)
	(segment
		(start 86.167962 152.2465)
		(end 86.762962 152.2465)
		(width 0.15)
		(layer "F.Cu")
		(net 3)
	)
	(segment
		(start 102.267962 133.8915)
		(end 102.517962 134.1415)
		(width 0.2)
		(layer "F.Cu")
		(net 3)
	)
	(segment
		(start 90.492962 146.0655)
		(end 90.492962 147.1165)
		(width 0.2)
		(layer "F.Cu")
		(net 3)
	)
	(segment
		(start 76.617962 177.6915)
		(end 76.617962 177.1505)
		(width 0.2)
		(layer "F.Cu")
		(net 3)
	)
	(segment
		(start 74.412962 155.0715)
		(end 74.412962 156.1215)
		(width 0.2)
		(layer "F.Cu")
		(net 3)
	)
	(segment
		(start 86.158962 143.557236)
		(end 86.158962 144.2325)
		(width 0.15)
		(layer "F.Cu")
		(net 3)
	)
	(segment
		(start 140.393962 144.4665)
		(end 141.342962 144.4665)
		(width 0.127)
		(layer "F.Cu")
		(net 3)
	)
	(segment
		(start 77.442962 174.3665)
		(end 76.726962 174.3665)
		(width 0.2)
		(layer "F.Cu")
		(net 3)
	)
	(segment
		(start 64.342962 176.3415)
		(end 64.499962 176.1845)
		(width 0.254)
		(layer "F.Cu")
		(net 3)
	)
	(segment
		(start 85.617962 146.6165)
		(end 85.567962 146.6165)
		(width 0.127)
		(layer "F.Cu")
		(net 3)
	)
	(segment
		(start 135.400372 145.9645)
		(end 136.442962 145.9645)
		(width 0.254)
		(layer "F.Cu")
		(net 3)
	)
	(segment
		(start 77.69347 156.517)
		(end 77.667962 156.491492)
		(width 0.15)
		(layer "F.Cu")
		(net 3)
	)
	(segment
		(start 81.554961 159.316)
		(end 82.192462 159.316)
		(width 0.15)
		(layer "F.Cu")
		(net 3)
	)
	(segment
		(start 93.608962 148.7915)
		(end 93.608962 147.8415)
		(width 0.254)
		(layer "F.Cu")
		(net 3)
	)
	(segment
		(start 81.054961 164.117)
		(end 80.842962 164.328999)
		(width 0.15)
		(layer "F.Cu")
		(net 3)
	)
	(segment
		(start 76.580962 119.102)
		(end 76.580962 118.580962)
		(width 0.15)
		(layer "F.Cu")
		(net 3)
	)
	(segment
		(start 88.692962 147.2665)
		(end 88.167962 147.2665)
		(width 0.2)
		(layer "F.Cu")
		(net 3)
	)
	(segment
		(start 132.314029 120.0415)
		(end 132.342962 120.012567)
		(width 0.15)
		(layer "F.Cu")
		(net 3)
	)
	(segment
		(start 67.192962 175.9915)
		(end 67.192962 175.8665)
		(width 0.254)
		(layer "F.Cu")
		(net 3)
	)
	(segment
		(start 77.642962 151.7025)
		(end 77.642962 151.626278)
		(width 0.127)
		(layer "F.Cu")
		(net 3)
	)
	(segment
		(start 82.958962 138.157236)
		(end 83.530962 138.729236)
		(width 0.254)
		(layer "F.Cu")
		(net 3)
	)
	(segment
		(start 112.473961 155.716)
		(end 113.267462 155.716)
		(width 0.15)
		(layer "F.Cu")
		(net 3)
	)
	(segment
		(start 111.666957 146.117)
		(end 111.554957 146.229)
		(width 0.15)
		(layer "F.Cu")
		(net 3)
	)
	(segment
		(start 96.806962 119.9775)
		(end 96.817962 119.9665)
		(width 0.254)
		(layer "F.Cu")
		(net 3)
	)
	(segment
		(start 85.517962 146.6665)
		(end 85.567962 146.6165)
		(width 0.127)
		(layer "F.Cu")
		(net 3)
	)
	(segment
		(start 137.287962 156.0165)
		(end 137.287962 157.2895)
		(width 0.254)
		(layer "F.Cu")
		(net 3)
	)
	(segment
		(start 82.518226 138.7665)
		(end 83.083962 139.332236)
		(width 0.254)
		(layer "F.Cu")
		(net 3)
	)
	(segment
		(start 85.920962 147.2665)
		(end 85.920962 148.1495)
		(width 0.127)
		(layer "F.Cu")
		(net 3)
	)
	(segment
		(start 75.527962 119.9665)
		(end 74.338962 121.1555)
		(width 0.4)
		(layer "F.Cu")
		(net 3)
	)
	(segment
		(start 106.112462 126.352)
		(end 106.107962 126.3565)
		(width 0.15)
		(layer "F.Cu")
		(net 3)
	)
	(segment
		(start 85.317962 135.507236)
		(end 86.867962 135.507236)
		(width 0.15)
		(layer "F.Cu")
		(net 3)
	)
	(segment
		(start 140.217962 158.2665)
		(end 139.517962 158.9665)
		(width 0.254)
		(layer "F.Cu")
		(net 3)
	)
	(segment
		(start 112.473961 149.717)
		(end 113.167462 149.717)
		(width 0.15)
		(layer "F.Cu")
		(net 3)
	)
	(segment
		(start 88.734962 131.0235)
		(end 88.734962 130.7365)
		(width 0.2)
		(layer "F.Cu")
		(net 3)
	)
	(segment
		(start 137.543962 149.4655)
		(end 137.567962 149.4415)
		(width 0.2)
		(layer "F.Cu")
		(net 3)
	)
	(segment
		(start 112.473961 150.919)
		(end 111.720462 150.919)
		(width 0.15)
		(layer "F.Cu")
		(net 3)
	)
	(segment
		(start 85.920962 146.3135)
		(end 85.617962 146.6165)
		(width 0.127)
		(layer "F.Cu")
		(net 3)
	)
	(segment
		(start 105.367962 122.5605)
		(end 105.367962 120.909042)
		(width 0.2)
		(layer "F.Cu")
		(net 3)
	)
	(segment
		(start 75.442962 157.540029)
		(end 75.442962 157.042971)
		(width 0.2)
		(layer "F.Cu")
		(net 3)
	)
	(segment
		(start 135.313872 146.051)
		(end 135.400372 145.9645)
		(width 0.254)
		(layer "F.Cu")
		(net 3)
	)
	(segment
		(start 116.317462 147.317)
		(end 116.317962 147.3165)
		(width 0.15)
		(layer "F.Cu")
		(net 3)
	)
	(segment
		(start 116.328062 150.9045)
		(end 116.313562 150.919)
		(width 0.15)
		(layer "F.Cu")
		(net 3)
	)
	(segment
		(start 77.817962 144.6165)
		(end 77.817962 144.7165)
		(width 0.15)
		(layer "F.Cu")
		(net 3)
	)
	(segment
		(start 112.473961 152.116)
		(end 113.167462 152.116)
		(width 0.15)
		(layer "F.Cu")
		(net 3)
	)
	(segment
		(start 135.137962 159.0825)
		(end 134.533962 159.0825)
		(width 0.4)
		(layer "F.Cu")
		(net 3)
	)
	(segment
		(start 96.269962 120.6165)
		(end 96.219962 120.5665)
		(width 0.254)
		(layer "F.Cu")
		(net 3)
	)
	(segment
		(start 69.317962 174.0665)
		(end 71.567962 171.8165)
		(width 0.2)
		(layer "F.Cu")
		(net 3)
	)
	(segment
		(start 139.516962 148.4655)
		(end 140.393962 148.4655)
		(width 0.2)
		(layer "F.Cu")
		(net 3)
	)
	(segment
		(start 83.088073 152.171389)
		(end 83.088073 152.202611)
		(width 0.15)
		(layer "F.Cu")
		(net 3)
	)
	(segment
		(start 94.833962 135.507236)
		(end 94.592962 135.507236)
		(width 0.2)
		(layer "F.Cu")
		(net 3)
	)
	(segment
		(start 116.705736 153.307394)
		(end 116.69513 153.318)
		(width 0.15)
		(layer "F.Cu")
		(net 3)
	)
	(segment
		(start 100.267962 150.1015)
		(end 100.267962 150.6415)
		(width 0.127)
		(layer "F.Cu")
		(net 3)
	)
	(segment
		(start 77.892962 155.386073)
		(end 77.963035 155.316)
		(width 0.127)
		(layer "F.Cu")
		(net 3)
	)
	(segment
		(start 109.067962 126.3915)
		(end 109.112462 126.347)
		(width 0.15)
		(layer "F.Cu")
		(net 3)
	)
	(segment
		(start 87.211617 131.588845)
		(end 86.742962 132.0575)
		(width 0.2)
		(layer "F.Cu")
		(net 3)
	)
	(segment
		(start 75.310662 177.2025)
		(end 74.337662 176.2295)
		(width 0.2)
		(layer "F.Cu")
		(net 3)
	)
	(segment
		(start 91.042962 145.1415)
		(end 91.042962 144.766236)
		(width 0.254)
		(layer "F.Cu")
		(net 3)
	)
	(segment
		(start 135.292962 142.4665)
		(end 136.442962 142.4665)
		(width 0.2)
		(layer "F.Cu")
		(net 3)
	)
	(segment
		(start 92.767962 121.696929)
		(end 92.767962 120.921929)
		(width 0.15)
		(layer "F.Cu")
		(net 3)
	)
	(segment
		(start 116.255962 164.5265)
		(end 116.255962 164.268001)
		(width 0.15)
		(layer "F.Cu")
		(net 3)
	)
	(segment
		(start 133.817962 117.7415)
		(end 134.117962 118.0415)
		(width 0.254)
		(layer "F.Cu")
		(net 3)
	)
	(segment
		(start 137.609226 161.9765)
		(end 137.192962 161.9765)
		(width 0.2)
		(layer "F.Cu")
		(net 3)
	)
	(segment
		(start 96.832962 122.6565)
		(end 96.381962 122.6565)
		(width 0.2)
		(layer "F.Cu")
		(net 3)
	)
	(segment
		(start 80.842962 146.1255)
		(end 80.851462 146.117)
		(width 0.15)
		(layer "F.Cu")
		(net 3)
	)
	(segment
		(start 135.732962 160.7015)
		(end 135.709962 160.7245)
		(width 0.3)
		(layer "F.Cu")
		(net 3)
	)
	(segment
		(start 38.528962 120.4565)
		(end 39.118962 121.0465)
		(width 0.35)
		(layer "F.Cu")
		(net 3)
	)
	(segment
		(start 116.6 155.719)
		(end 116.597 155.716)
		(width 0.15)
		(layer "F.Cu")
		(net 3)
	)
	(segment
		(start 65.633962 172.7415)
		(end 64.892962 172.7415)
		(width 0.254)
		(layer "F.Cu")
		(net 3)
	)
	(segment
		(start 96.806962 120.6165)
		(end 96.269962 120.6165)
		(width 0.254)
		(layer "F.Cu")
		(net 3)
	)
	(segment
		(start 101.567962 144.6165)
		(end 101.587962 144.6165)
		(width 0.127)
		(layer "F.Cu")
		(net 3)
	)
	(segment
		(start 96.733698 138.782236)
		(end 96.742962 138.7915)
		(width 0.15)
		(layer "F.Cu")
		(net 3)
	)
	(segment
		(start 79.530962 120.5045)
		(end 79.517962 120.4915)
		(width 0.127)
		(layer "F.Cu")
		(net 3)
	)
	(segment
		(start 76.867962 177.9415)
		(end 76.617962 177.6915)
		(width 0.2)
		(layer "F.Cu")
		(net 3)
	)
	(segment
		(start 133.460462 161.454)
		(end 135.392962 161.454)
		(width 0.2)
		(layer "F.Cu")
		(net 3)
	)
	(segment
		(start 132.342962 119.329)
		(end 132.342962 118.554)
		(width 0.15)
		(layer "F.Cu")
		(net 3)
	)
	(segment
		(start 103.327962 127.6365)
		(end 103.307962 127.6565)
		(width 0.254)
		(layer "F.Cu")
		(net 3)
	)
	(segment
		(start 113.418462 146.117)
		(end 113.567962 146.2665)
		(width 0.15)
		(layer "F.Cu")
		(net 3)
	)
	(segment
		(start 96.806962 120.7875)
		(end 96.806962 120.6165)
		(width 0.254)
		(layer "F.Cu")
		(net 3)
	)
	(segment
		(start 113.167462 152.116)
		(end 113.167962 152.1165)
		(width 0.15)
		(layer "F.Cu")
		(net 3)
	)
	(segment
		(start 78.473961 157.716)
		(end 77.76861 157.716)
		(width 0.15)
		(layer "F.Cu")
		(net 3)
	)
	(segment
		(start 98.467962 141.6165)
		(end 98.567962 141.6165)
		(width 0.127)
		(layer "F.Cu")
		(net 3)
	)
	(segment
		(start 132.718962 126.3915)
		(end 133.342962 126.3915)
		(width 0.254)
		(layer "F.Cu")
		(net 3)
	)
	(segment
		(start 123.987962 119.284)
		(end 123.987962 118.509)
		(width 0.15)
		(layer "F.Cu")
		(net 3)
	)
	(segment
		(start 83.133962 138.332236)
		(end 83.508962 138.707236)
		(width 0.2)
		(layer "F.Cu")
		(net 3)
	)
	(segment
		(start 105.367962 120.909042)
		(end 105.346962 120.888042)
		(width 0.2)
		(layer "F.Cu")
		(net 3)
	)
	(segment
		(start 91.392962 146.0665)
		(end 91.417962 146.0415)
		(width 0.254)
		(layer "F.Cu")
		(net 3)
	)
	(segment
		(start 124.317962 116.7665)
		(end 124.317962 117.8915)
		(width 0.254)
		(layer "F.Cu")
		(net 3)
	)
	(segment
		(start 135.709962 160.7245)
		(end 135.692962 160.7415)
		(width 0.254)
		(layer "F.Cu")
		(net 3)
	)
	(segment
		(start 80.817462 152.916)
		(end 80.617962 152.7165)
		(width 0.15)
		(layer "F.Cu")
		(net 3)
	)
	(segment
		(start 96.765962 130.5395)
		(end 96.692962 130.4665)
		(width 0.18)
		(layer "F.Cu")
		(net 3)
	)
	(segment
		(start 115.554961 159.316)
		(end 116.317462 159.316)
		(width 0.15)
		(layer "F.Cu")
		(net 3)
	)
	(segment
		(start 65.092962 176.1845)
		(end 65.092962 177.2165)
		(width 0.254)
		(layer "F.Cu")
		(net 3)
	)
	(segment
		(start 67.192962 176.1665)
		(end 67.192962 175.9915)
		(width 0.254)
		(layer "F.Cu")
		(net 3)
	)
	(segment
		(start 93.917962 149.9415)
		(end 93.917962 149.1005)
		(width 0.2)
		(layer "F.Cu")
		(net 3)
	)
	(segment
		(start 61.117962 177.2075)
		(end 62.117962 177.2075)
		(width 0.254)
		(layer "F.Cu")
		(net 3)
	)
	(segment
		(start 133.692962 144.1915)
		(end 134.467962 144.1915)
		(width 0.127)
		(layer "F.Cu")
		(net 3)
	)
	(segment
		(start 137.313962 158.1925)
		(end 137.617962 158.4965)
		(width 0.4)
		(layer "F.Cu")
		(net 3)
	)
	(segment
		(start 112.973961 164.117)
		(end 112.473961 164.117)
		(width 0.15)
		(layer "F.Cu")
		(net 3)
	)
	(segment
		(start 116.680361 154.516)
		(end 115.554961 154.516)
		(width 0.15)
		(layer "F.Cu")
		(net 3)
	)
	(segment
		(start 92.467962 147.4165)
		(end 93.183962 147.4165)
		(width 0.15)
		(layer "F.Cu")
		(net 3)
	)
	(segment
		(start 133.817962 117.6665)
		(end 133.342962 118.1415)
		(width 0.15)
		(layer "F.Cu")
		(net 3)
	)
	(segment
		(start 79.530962 122.537455)
		(end 79.5148 122.553617)
		(width 0.127)
		(layer "F.Cu")
		(net 3)
	)
	(segment
		(start 77.892962 155.386073)
		(end 77.393787 155.386073)
		(width 0.127)
		(layer "F.Cu")
		(net 3)
	)
	(segment
		(start 101.267962 150.6915)
		(end 101.092962 150.8665)
		(width 0.127)
		(layer "F.Cu")
		(net 3)
	)
	(segment
		(start 85.920962 145.9635)
		(end 85.920962 146.3135)
		(width 0.127)
		(layer "F.Cu")
		(net 3)
	)
	(segment
		(start 78.867962 124.4665)
		(end 78.867962 123.7165)
		(width 0.2)
		(layer "F.Cu")
		(net 3)
	)
	(segment
		(start 132.937962 156.0165)
		(end 132.937962 157.2915)
		(width 0.254)
		(layer "F.Cu")
		(net 3)
	)
	(segment
		(start 115.554961 152.116)
		(end 116.317962 152.116)
		(width 0.15)
		(layer "F.Cu")
		(net 3)
	)
	(segment
		(start 133.817962 116.7665)
		(end 133.817962 117.6665)
		(width 0.15)
		(layer "F.Cu")
		(net 3)
	)
	(segment
		(start 66.092962 176.1845)
		(end 67.174962 176.1845)
		(width 0.254)
		(layer "F.Cu")
		(net 3)
	)
	(segment
		(start 86.767962 152.2415)
		(end 86.826962 152.2415)
		(width 0.15)
		(layer "F.Cu")
		(net 3)
	)
	(segment
		(start 76.580962 119.102)
		(end 76.580962 119.9535)
		(width 0.4)
		(layer "F.Cu")
		(net 3)
	)
	(segment
		(start 138.427962 158.4965)
		(end 138.938962 159.0075)
		(width 0.4)
		(layer "F.Cu")
		(net 3)
	)
	(segment
		(start 122.987962 118.509)
		(end 122.987962 117.9865)
		(width 0.15)
		(layer "F.Cu")
		(net 3)
	)
	(segment
		(start 101.092962 150.8665)
		(end 100.792962 150.8665)
		(width 0.127)
		(layer "F.Cu")
		(net 3)
	)
	(segment
		(start 113.266462 161.715)
		(end 113.267962 161.7165)
		(width 0.15)
		(layer "F.Cu")
		(net 3)
	)
	(segment
		(start 95.387962 142.7165)
		(end 95.387962 143.3365)
		(width 0.2)
		(layer "F.Cu")
		(net 3)
	)
	(segment
		(start 111.720462 150.919)
		(end 111.717962 150.9165)
		(width 0.15)
		(layer "F.Cu")
		(net 3)
	)
	(segment
		(start 133.094443 155.215019)
		(end 132.937962 155.3715)
		(width 0.254)
		(layer "F.Cu")
		(net 3)
	)
	(segment
		(start 61.117962 176.2095)
		(end 60.558962 176.2095)
		(width 0.254)
		(layer "F.Cu")
		(net 3)
	)
	(segment
		(start 77.067962 158.2165)
		(end 77.067962 158.52037)
		(width 0.15)
		(layer "F.Cu")
		(net 3)
	)
	(segment
		(start 91.417962 146.0415)
		(end 91.417962 145.5165)
		(width 0.254)
		(layer "F.Cu")
		(net 3)
	)
	(segment
		(start 94.017962 135.507236)
		(end 92.477226 135.507236)
		(width 0.15)
		(layer "F.Cu")
		(net 3)
	)
	(segment
		(start 95.192962 129.2165)
		(end 94.967962 128.9915)
		(width 0.2)
		(layer "F.Cu")
		(net 3)
	)
	(segment
		(start 91.692962 147.7575)
		(end 92.126962 147.7575)
		(width 0.15)
		(layer "F.Cu")
		(net 3)
	)
	(segment
		(start 53.296962 178.6255)
		(end 51.936962 178.6255)
		(width 0.254)
		(layer "F.Cu")
		(net 3)
	)
	(segment
		(start 133.342962 118.1415)
		(end 133.342962 118.554)
		(width 0.15)
		(layer "F.Cu")
		(net 3)
	)
	(segment
		(start 75.367962 160.0265)
		(end 75.367962 158.4915)
		(width 0.2)
		(layer "F.Cu")
		(net 3)
	)
	(segment
		(start 74.517962 160.8765)
		(end 75.367962 160.0265)
		(width 0.2)
		(layer "F.Cu")
		(net 3)
	)
	(segment
		(start 68.506938 175.130476)
		(end 68.267962 174.8915)
		(width 0.254)
		(layer "F.Cu")
		(net 3)
	)
	(segment
		(start 65.092962 177.2165)
		(end 66.092962 177.2165)
		(width 0.254)
		(layer "F.Cu")
		(net 3)
	)
	(segment
		(start 140.717962 140.4165)
		(end 140.717962 140.9295)
		(width 0.2)
		(layer "F.Cu")
		(net 3)
	)
	(segment
		(start 68.167962 174.8915)
		(end 68.592962 174.4665)
		(width 0.254)
		(layer "F.Cu")
		(net 3)
	)
	(segment
		(start 140.292962 159.0165)
		(end 140.283962 159.0075)
		(width 0.254)
		(layer "F.Cu")
		(net 3)
	)
	(segment
		(start 92.717962 144.8005)
		(end 92.142962 144.8005)
		(width 0.2)
		(layer "F.Cu")
		(net 3)
	)
	(segment
		(start 85.920962 147.2665)
		(end 85.920962 146.9195)
		(width 0.127)
		(layer "F.Cu")
		(net 3)
	)
	(segment
		(start 140.372962 127.4315)
		(end 140.372962 126.4615)
		(width 0.15)
		(layer "F.Cu")
		(net 3)
	)
	(segment
		(start 96.381962 121.2285)
		(end 96.219962 121.0665)
		(width 0.254)
		(layer "F.Cu")
		(net 3)
	)
	(segment
		(start 108.366962 122.5605)
		(end 108.366962 120.9155)
		(width 0.2)
		(layer "F.Cu")
		(net 3)
	)
	(segment
		(start 112.867962 122.5605)
		(end 112.867962 120.9165)
		(width 0.2)
		(layer "F.Cu")
		(net 3)
	)
	(segment
		(start 86.767962 152.2415)
		(end 86.951962 152.2415)
		(width 0.15)
		(layer "F.Cu")
		(net 3)
	)
	(segment
		(start 133.342962 119.329)
		(end 133.342962 118.554)
		(width 0.15)
		(layer "F.Cu")
		(net 3)
	)
	(segment
		(start 66.433962 170.4165)
		(end 65.66 170.4165)
		(width 0.254)
		(layer "F.Cu")
		(net 3)
	)
	(segment
		(start 134.467462 144.1785)
		(end 135.004962 144.1785)
		(width 0.127)
		(layer "F.Cu")
		(net 3)
	)
	(segment
		(start 66.092962 176.1845)
		(end 66.810962 176.1845)
		(width 0.254)
		(layer "F.Cu")
		(net 3)
	)
	(segment
		(start 115.554961 146.117)
		(end 114.668462 146.117)
		(width 0.15)
		(layer "F.Cu")
		(net 3)
	)
	(segment
		(start 65.9835 169.4165)
		(end 66.433962 169.4165)
		(width 0.254)
		(layer "F.Cu")
		(net 3)
	)
	(segment
		(start 103.327962 126.063)
		(end 103.327962 124.4465)
		(width 0.254)
		(layer "F.Cu")
		(net 3)
	)
	(segment
		(start 89.992962 152.3165)
		(end 90.392962 152.3165)
		(width 0.15)
		(layer "F.Cu")
		(net 3)
	)
	(segment
		(start 100.492962 150.8665)
		(end 100.792962 150.8665)
		(width 0.127)
		(layer "F.Cu")
		(net 3)
	)
	(segment
		(start 75.101962 178.2415)
		(end 75.101962 177.6045)
		(width 0.2)
		(layer "F.Cu")
		(net 3)
	)
	(segment
		(start 92.737752 149.04671)
		(end 92.992962 148.7915)
		(width 0.254)
		(layer "F.Cu")
		(net 3)
	)
	(segment
		(start 85.395823 133.238639)
		(end 85.395823 132.922639)
		(width 0.2)
		(layer "F.Cu")
		(net 3)
	)
	(segment
		(start 77.871332 158.917)
		(end 78.473961 158.917)
		(width 0.15)
		(layer "F.Cu")
		(net 3)
	)
	(segment
		(start 95.632962 129.2165)
		(end 95.192962 129.2165)
		(width 0.2)
		(layer "F.Cu")
		(net 3)
	)
	(segment
		(start 96.219962 119.1165)
		(end 96.219962 119.9645)
		(width 0.254)
		(layer "F.Cu")
		(net 3)
	)
	(segment
		(start 85.517962 147.7465)
		(end 85.987962 148.2165)
		(width 0.127)
		(layer "F.Cu")
		(net 3)
	)
	(segment
		(start 96.076962 141.1165)
		(end 96.817962 141.1165)
		(width 0.15)
		(layer "F.Cu")
		(net 3)
	)
	(segment
		(start 85.517962 147.2665)
		(end 85.517962 146.6665)
		(width 0.127)
		(layer "F.Cu")
		(net 3)
	)
	(segment
		(start 81.917231 136.517231)
		(end 82.209967 136.517231)
		(width 0.2)
		(layer "F.Cu")
		(net 3)
	)
	(segment
		(start 80.940462 150.919)
		(end 80.617962 151.2415)
		(width 0.15)
		(layer "F.Cu")
		(net 3)
	)
	(segment
		(start 95.868962 146.7655)
		(end 95.867962 146.7665)
		(width 0.2)
		(layer "F.Cu")
		(net 3)
	)
	(segment
		(start 51.936962 178.6255)
		(end 51.927962 178.6165)
		(width 0.254)
		(layer "F.Cu")
		(net 3)
	)
	(segment
		(start 96.211292 127.0205)
		(end 96.483962 126.74783)
		(width 0.2)
		(layer "F.Cu")
		(net 3)
	)
	(segment
		(start 82.242962 153.104001)
		(end 82.054961 152.916)
		(width 0.15)
		(layer "F.Cu")
		(net 3)
	)
	(segment
		(start 115.554961 146.117)
		(end 116.042462 146.117)
		(width 0.15)
		(layer "F.Cu")
		(net 3)
	)
	(segment
		(start 141.417962 144.3915)
		(end 141.905462 144.3915)
		(width 0.127)
		(layer "F.Cu")
		(net 3)
	)
	(segment
		(start 72.317962 168.8415)
		(end 72.317962 171.0665)
		(width 0.2)
		(layer "F.Cu")
		(net 3)
	)
	(segment
		(start 68.592962 174.0665)
		(end 69.317962 174.0665)
		(width 0.2)
		(layer "F.Cu")
		(net 3)
	)
	(segment
		(start 122.987962 119.284)
		(end 122.987962 118.509)
		(width 0.15)
		(layer "F.Cu")
		(net 3)
	)
	(segment
		(start 76.142962 177.8415)
		(end 76.167962 177.8415)
		(width 0.2)
		(layer "F.Cu")
		(net 3)
	)
	(segment
		(start 81.554961 152.916)
		(end 80.817462 152.916)
		(width 0.15)
		(layer "F.Cu")
		(net 3)
	)
	(segment
		(start 140.256464 164.4165)
		(end 140.281464 164.3915)
		(width 0.2)
		(layer "F.Cu")
		(net 3)
	)
	(segment
		(start 85.517962 145.9635)
		(end 85.517962 146.5665)
		(width 0.127)
		(layer "F.Cu")
		(net 3)
	)
	(segment
		(start 113.167462 149.717)
		(end 113.167962 149.7165)
		(width 0.15)
		(layer "F.Cu")
		(net 3)
	)
	(segment
		(start 128.782962 119.6165)
		(end 128.782962 118.6675)
		(width 0.254)
		(layer "F.Cu")
		(net 3)
	)
	(segment
		(start 72.317962 168.8415)
		(end 72.317962 167.4815)
		(width 0.2)
		(layer "F.Cu")
		(net 3)
	)
	(segment
		(start 60.558962 176.2095)
		(end 60.542962 176.2255)
		(width 0.254)
		(layer "F.Cu")
		(net 3)
	)
	(segment
		(start 101.652962 133.8915)
		(end 102.267962 133.8915)
		(width 0.2)
		(layer "F.Cu")
		(net 3)
	)
	(segment
		(start 104.757962 127.6765)
		(end 104.757962 128.3865)
		(width 0.2)
		(layer "F.Cu")
		(net 3)
	)
	(segment
		(start 37.977962 120.4565)
		(end 38.528962 120.4565)
		(width 0.35)
		(layer "F.Cu")
		(net 3)
	)
	(segment
		(start 83.530962 138.729236)
		(end 83.530962 138.791368)
		(width 0.254)
		(layer "F.Cu")
		(net 3)
	)
	(segment
		(start 97.067962 122.8915)
		(end 96.832962 122.6565)
		(width 0.2)
		(layer "F.Cu")
		(net 3)
	)
	(segment
		(start 88.693962 148.3655)
		(end 88.693962 147.2675)
		(width 0.2)
		(layer "F.Cu")
		(net 3)
	)
	(segment
		(start 92.126962 147.7575)
		(end 92.467962 147.4165)
		(width 0.15)
		(layer "F.Cu")
		(net 3)
	)
	(segment
		(start 87.947962 147.0465)
		(end 88.167962 147.2665)
		(width 0.2)
		(layer "F.Cu")
		(net 3)
	)
	(segment
		(start 100.267962 150.6415)
		(end 100.492962 150.8665)
		(width 0.127)
		(layer "F.Cu")
		(net 3)
	)
	(segment
		(start 87.215962 157.5685)
		(end 85.242962 159.5415)
		(width 0.15)
		(layer "F.Cu")
		(net 3)
	)
	(segment
		(start 66.810962 176.1845)
		(end 66.817962 176.1915)
		(width 0.254)
		(layer "F.Cu")
		(net 3)
	)
	(segment
		(start 96.219962 119.9645)
		(end 96.217962 119.9665)
		(width 0.254)
		(layer "F.Cu")
		(net 3)
	)
	(segment
		(start 90.467962 143.2665)
		(end 90.467962 146.0405)
		(width 0.2)
		(layer "F.Cu")
		(net 3)
	)
	(segment
		(start 85.920962 148.1495)
		(end 85.987962 148.2165)
		(width 0.127)
		(layer "F.Cu")
		(net 3)
	)
	(segment
		(start 114.918462 147.317)
		(end 115.554961 147.317)
		(width 0.15)
		(layer "F.Cu")
		(net 3)
	)
	(segment
		(start 98.567962 141.6165)
		(end 101.567962 144.6165)
		(width 0.127)
		(layer "F.Cu")
		(net 3)
	)
	(segment
		(start 82.209967 136.517231)
		(end 82.367962 136.359236)
		(width 0.2)
		(layer "F.Cu")
		(net 3)
	)
	(segment
		(start 93.817962 145.276)
		(end 93.742462 145.2005)
		(width 0.2)
		(layer "F.Cu")
		(net 3)
	)
	(segment
		(start 95.387962 143.3365)
		(end 95.517962 143.4665)
		(width 0.2)
		(layer "F.Cu")
		(net 3)
	)
	(segment
		(start 76.580962 119.9535)
		(end 76.567962 119.9665)
		(width 0.4)
		(layer "F.Cu")
		(net 3)
	)
	(segment
		(start 62.117962 176.2095)
		(end 61.117962 176.2095)
		(width 0.254)
		(layer "F.Cu")
		(net 3)
	)
	(segment
		(start 85.920962 145.2495)
		(end 85.687962 145.0165)
		(width 0.127)
		(layer "F.Cu")
		(net 3)
	)
	(segment
		(start 72.467962 177.8665)
		(end 72.717962 177.6165)
		(width 0.254)
		(layer "F.Cu")
		(net 3)
	)
	(segment
		(start 139.501962 163.4165)
		(end 140.279464 163.4165)
		(width 0.254)
		(layer "F.Cu")
		(net 3)
	)
	(segment
		(start 94.342962 127.2665)
		(end 95.165292 127.2665)
		(width 0.2)
		(layer "F.Cu")
		(net 3)
	)
	(segment
		(start 87.467962 147.0465)
		(end 87.947962 147.0465)
		(width 0.2)
		(layer "F.Cu")
		(net 3)
	)
	(segment
		(start 137.862962 161.1665)
		(end 137.862962 161.722764)
		(width 0.2)
		(layer "F.Cu")
		(net 3)
	)
	(segment
		(start 65.092962 177.2165)
		(end 64.517962 177.2165)
		(width 0.254)
		(layer "F.Cu")
		(net 3)
	)
	(segment
		(start 116.313562 150.919)
		(end 115.554961 150.919)
		(width 0.15)
		(layer "F.Cu")
		(net 3)
	)
	(segment
		(start 133.297962 158.5165)
		(end 132.913962 158.1325)
		(width 0.4)
		(layer "F.Cu")
		(net 3)
	)
	(segment
		(start 133.817962 116.6165)
		(end 133.817962 117.7415)
		(width 0.254)
		(layer "F.Cu")
		(net 3)
	)
	(segment
		(start 124.317962 116.7665)
		(end 124.317962 115.5165)
		(width 0.254)
		(layer "F.Cu")
		(net 3)
	)
	(segment
		(start 84.140724 149.241164)
		(end 84.140724 149.104262)
		(width 0.15)
		(layer "F.Cu")
		(net 3)
	)
	(segment
		(start 111.718462 152.116)
		(end 111.717962 152.1165)
		(width 0.15)
		(layer "F.Cu")
		(net 3)
	)
	(segment
		(start 37.967962 121.4865)
		(end 38.678962 121.4865)
		(width 0.35)
		(layer "F.Cu")
		(net 3)
	)
	(segment
		(start 88.693962 147.2675)
		(end 88.692962 147.2665)
		(width 0.2)
		(layer "F.Cu")
		(net 3)
	)
	(segment
		(start 123.987962 118.0965)
		(end 123.987962 118.509)
		(width 0.15)
		(layer "F.Cu")
		(net 3)
	)
	(via
		(at 96.017962 133.3165)
		(size 0.45)
		(drill 0.1)
		(layers "F.Cu" "B.Cu")
		(net 3)
	)
	(via
		(at 92.737752 149.66129)
		(size 0.45)
		(drill 0.1)
		(layers "F.Cu" "B.Cu")
		(net 3)
	)
	(via
		(at 140.292962 158.2665)
		(size 0.45)
		(drill 0.1)
		(layers "F.Cu" "B.Cu")
		(net 3)
	)
	(via
		(at 109.067962 126.3915)
		(size 0.45)
		(drill 0.1)
		(layers "F.Cu" "B.Cu")
		(free yes)
		(net 3)
	)
	(via
		(at 41.55 167.2)
		(size 0.45)
		(drill 0.1)
		(layers "F.Cu" "B.Cu")
		(free yes)
		(net 3)
	)
	(via
		(at 58.457962 162.5665)
		(size 0.45)
		(drill 0.1)
		(layers "F.Cu" "B.Cu")
		(free yes)
		(net 3)
	)
	(via
		(at 77.832782 144.60168)
		(size 0.45)
		(drill 0.1)
		(layers "F.Cu" "B.Cu")
		(free yes)
		(net 3)
	)
	(via
		(at 46.607962 169.3165)
		(size 0.45)
		(drill 0.1)
		(layers "F.Cu" "B.Cu")
		(net 3)
	)
	(via
		(at 86.967962 127.8915)
		(size 0.45)
		(drill 0.1)
		(layers "F.Cu" "B.Cu")
		(net 3)
	)
	(via
		(at 40.687962 136.0365)
		(size 0.45)
		(drill 0.1)
		(layers "F.Cu" "B.Cu")
		(free yes)
		(net 3)
	)
	(via
		(at 71.877962 115.3265)
		(size 0.45)
		(drill 0.1)
		(layers "F.Cu" "B.Cu")
		(net 3)
	)
	(via
		(at 50.392962 117.9665)
		(size 0.45)
		(drill 0.1)
		(layers "F.Cu" "B.Cu")
		(net 3)
	)
	(via
		(at 65.4 160.325)
		(size 0.45)
		(drill 0.1)
		(layers "F.Cu" "B.Cu")
		(free yes)
		(net 3)
	)
	(via
		(at 132.342962 117.9665)
		(size 0.45)
		(drill 0.1)
		(layers "F.Cu" "B.Cu")
		(net 3)
	)
	(via
		(at 93.817962 152.7915)
		(size 0.45)
		(drill 0.1)
		(layers "F.Cu" "B.Cu")
		(net 3)
	)
	(via
		(at 102.177962 125.3065)
		(size 0.45)
		(drill 0.1)
		(layers "F.Cu" "B.Cu")
		(net 3)
	)
	(via
		(at 46.377962 172.5965)
		(size 0.45)
		(drill 0.1)
		(layers "F.Cu" "B.Cu")
		(net 3)
	)
	(via
		(at 44.767962 178.7965)
		(size 0.45)
		(drill 0.1)
		(layers "F.Cu" "B.Cu")
		(net 3)
	)
	(via
		(at 60.197962 162.6565)
		(size 0.45)
		(drill 0.1)
		(layers "F.Cu" "B.Cu")
		(free yes)
		(net 3)
	)
	(via
		(at 77.691558 157.793052)
		(size 0.45)
		(drill 0.1)
		(layers "F.Cu" "B.Cu")
		(net 3)
	)
	(via
		(at 121.1 152.2)
		(size 0.45)
		(drill 0.1)
		(layers "F.Cu" "B.Cu")
		(net 3)
	)
	(via
		(at 79.067962 133.1665)
		(size 0.45)
		(drill 0.1)
		(layers "F.Cu" "B.Cu")
		(free yes)
		(net 3)
	)
	(via
		(at 82.506462 138.7665)
		(size 0.45)
		(drill 0.1)
		(layers "F.Cu" "B.Cu")
		(net 3)
	)
	(via
		(at 126.867962 115.5165)
		(size 0.45)
		(drill 0.1)
		(layers "F.Cu" "B.Cu")
		(net 3)
	)
	(via
		(at 133.817962 115.5165)
		(size 0.45)
		(drill 0.1)
		(layers "F.Cu" "B.Cu")
		(net 3)
	)
	(via
		(at 49.707962 121.7165)
		(size 0.45)
		(drill 0.1)
		(layers "F.Cu" "B.Cu")
		(net 3)
	)
	(via
		(at 44.187962 165.3665)
		(size 0.45)
		(drill 0.1)
		(layers "F.Cu" "B.Cu")
		(free yes)
		(net 3)
	)
	(via
		(at 49.707962 121.0165)
		(size 0.45)
		(drill 0.1)
		(layers "F.Cu" "B.Cu")
		(net 3)
	)
	(via
		(at 59.067962 153.8915)
		(size 0.45)
		(drill 0.1)
		(layers "F.Cu" "B.Cu")
		(free yes)
		(net 3)
	)
	(via
		(at 98.492962 175.349499)
		(size 0.45)
		(drill 0.1)
		(layers "F.Cu" "B.Cu")
		(net 3)
	)
	(via
		(at 82.992962 119.9665)
		(size 0.45)
		(drill 0.1)
		(layers "F.Cu" "B.Cu")
		(net 3)
	)
	(via
		(at 77.642962 151.7025)
		(size 0.45)
		(drill 0.1)
		(layers "F.Cu" "B.Cu")
		(net 3)
	)
	(via
		(at 49.687962 117.9665)
		(size 0.45)
		(drill 0.1)
		(layers "F.Cu" "B.Cu")
		(net 3)
	)
	(via
		(at 94.342962 126.7665)
		(size 0.45)
		(drill 0.1)
		(layers "F.Cu" "B.Cu")
		(net 3)
	)
	(via
		(at 120.827962 134.5665)
		(size 0.45)
		(drill 0.1)
		(layers "F.Cu" "B.Cu")
		(free yes)
		(net 3)
	)
	(via
		(at 73.417962 146.9165)
		(size 0.45)
		(drill 0.1)
		(layers "F.Cu" "B.Cu")
		(net 3)
	)
	(via
		(at 87.117962 140.8665)
		(size 0.45)
		(drill 0.1)
		(layers "F.Cu" "B.Cu")
		(net 3)
	)
	(via
		(at 109.917962 149.9415)
		(size 0.45)
		(drill 0.1)
		(layers "F.Cu" "B.Cu")
		(net 3)
	)
	(via
		(at 128.997962 151.2965)
		(size 0.45)
		(drill 0.1)
		(layers "F.Cu" "B.Cu")
		(net 3)
	)
	(via
		(at 77.442962 174.3665)
		(size 0.45)
		(drill 0.1)
		(layers "F.Cu" "B.Cu")
		(net 3)
	)
	(via
		(at 113.147962 156.917)
		(size 0.45)
		(drill 0.1)
		(layers "F.Cu" "B.Cu")
		(free yes)
		(net 3)
	)
	(via
		(at 91.867962 131.2165)
		(size 0.45)
		(drill 0.1)
		(layers "F.Cu" "B.Cu")
		(net 3)
	)
	(via
		(at 68.727962 157.0065)
		(size 0.45)
		(drill 0.1)
		(layers "F.Cu" "B.Cu")
		(net 3)
	)
	(via
		(at 104.737962 177.7765)
		(size 0.45)
		(drill 0.1)
		(layers "F.Cu" "B.Cu")
		(net 3)
	)
	(via
		(at 105.346962 120.888042)
		(size 0.45)
		(drill 0.1)
		(layers "F.Cu" "B.Cu")
		(free yes)
		(net 3)
	)
	(via
		(at 102.127962 179.2565)
		(size 0.45)
		(drill 0.1)
		(layers "F.Cu" "B.Cu")
		(net 3)
	)
	(via
		(at 67.192962 175.1915)
		(size 0.45)
		(drill 0.1)
		(layers "F.Cu" "B.Cu")
		(net 3)
	)
	(via
		(at 114.918462 147.317)
		(size 0.45)
		(drill 0.1)
		(layers "F.Cu" "B.Cu")
		(net 3)
	)
	(via
		(at 68.142962 161.3165)
		(size 0.45)
		(drill 0.1)
		(layers "F.Cu" "B.Cu")
		(free yes)
		(net 3)
	)
	(via
		(at 130.5 127.25)
		(size 0.5)
		(drill 0.15)
		(layers "F.Cu" "B.Cu")
		(free yes)
		(net 3)
	)
	(via
		(at 52.727962 156.9565)
		(size 0.45)
		(drill 0.1)
		(layers "F.Cu" "B.Cu")
		(free yes)
		(net 3)
	)
	(via
		(at 99.027962 123.1365)
		(size 0.45)
		(drill 0.1)
		(layers "F.Cu" "B.Cu")
		(net 3)
	)
	(via
		(at 93.377962 178.0065)
		(size 0.45)
		(drill 0.1)
		(layers "F.Cu" "B.Cu")
		(net 3)
	)
	(via
		(at 143.107962 156.3465)
		(size 0.45)
		(drill 0.1)
		(layers "F.Cu" "B.Cu")
		(net 3)
	)
	(via
		(at 73.207962 163.4865)
		(size 0.45)
		(drill 0.1)
		(layers "F.Cu" "B.Cu")
		(net 3)
	)
	(via
		(at 85.717962 125.3865)
		(size 0.45)
		(drill 0.1)
		(layers "F.Cu" "B.Cu")
		(net 3)
	)
	(via
		(at 88.817962 140.8665)
		(size 0.45)
		(drill 0.1)
		(layers "F.Cu" "B.Cu")
		(net 3)
	)
	(via
		(at 51.087962 117.2165)
		(size 0.45)
		(drill 0.1)
		(layers "F.Cu" "B.Cu")
		(net 3)
	)
	(via
		(at 88.817962 139.1665)
		(size 0.45)
		(drill 0.1)
		(layers "F.Cu" "B.Cu")
		(net 3)
	)
	(via
		(at 77.667962 147.317)
		(size 0.45)
		(drill 0.1)
		(layers "F.Cu" "B.Cu")
		(free yes)
		(net 3)
	)
	(via
		(at 133.202245 155.215019)
		(size 0.45)
		(drill 0.1)
		(layers "F.Cu" "B.Cu")
		(net 3)
	)
	(via
		(at 90.554526 151.770675)
		(size 0.45)
		(drill 0.1)
		(layers "F.Cu" "B.Cu")
		(net 3)
	)
	(via
		(at 142.877962 129.7065)
		(size 0.45)
		(drill 0.1)
		(layers "F.Cu" "B.Cu")
		(net 3)
	)
	(via
		(at 110.767962 138.7165)
		(size 0.45)
		(drill 0.1)
		(layers "F.Cu" "B.Cu")
		(free yes)
		(net 3)
	)
	(via
		(at 60.417962 171.9665)
		(size 0.45)
		(drill 0.1)
		(layers "F.Cu" "B.Cu")
		(free yes)
		(net 3)
	)
	(via
		(at 96.617962 151.3915)
		(size 0.45)
		(drill 0.1)
		(layers "F.Cu" "B.Cu")
		(net 3)
	)
	(via
		(at 89.507962 166.3065)
		(size 0.45)
		(drill 0.1)
		(layers "F.Cu" "B.Cu")
		(net 3)
	)
	(via
		(at 140.292962 159.6915)
		(size 0.45)
		(drill 0.1)
		(layers "F.Cu" "B.Cu")
		(net 3)
	)
	(via
		(at 76.867962 177.9415)
		(size 0.45)
		(drill 0.1)
		(layers "F.Cu" "B.Cu")
		(net 3)
	)
	(via
		(at 95.517962 143.4665)
		(size 0.45)
		(drill 0.1)
		(layers "F.Cu" "B.Cu")
		(net 3)
	)
	(via
		(at 93.817962 145.276)
		(size 0.45)
		(drill 0.1)
		(layers "F.Cu" "B.Cu")
		(net 3)
	)
	(via
		(at 50.727962 158.5265)
		(size 0.45)
		(drill 0.1)
		(layers "F.Cu" "B.Cu")
		(net 3)
	)
	(via
		(at 50.392962 118.6665)
		(size 0.45)
		(drill 0.1)
		(layers "F.Cu" "B.Cu")
		(net 3)
	)
	(via
		(at 56.727962 173.4565)
		(size 0.45)
		(drill 0.1)
		(layers "F.Cu" "B.Cu")
		(free yes)
		(net 3)
	)
	(via
		(at 122.967962 117.9665)
		(size 0.45)
		(drill 0.1)
		(layers "F.Cu" "B.Cu")
		(net 3)
	)
	(via
		(at 116.592962 145.5165)
		(size 0.45)
		(drill 0.1)
		(layers "F.Cu" "B.Cu")
		(net 3)
	)
	(via
		(at 90.517962 137.4665)
		(size 0.45)
		(drill 0.1)
		(layers "F.Cu" "B.Cu")
		(net 3)
	)
	(via
		(at 77.067962 158.2165)
		(size 0.45)
		(drill 0.1)
		(layers "F.Cu" "B.Cu")
		(net 3)
	)
	(via
		(at 51.317962 162.5765)
		(size 0.45)
		(drill 0.1)
		(layers "F.Cu" "B.Cu")
		(free yes)
		(net 3)
	)
	(via
		(at 116.317962 158.1165)
		(size 0.45)
		(drill 0.1)
		(layers "F.Cu" "B.Cu")
		(net 3)
	)
	(via
		(at 59.677962 130.2965)
		(size 0.45)
		(drill 0.1)
		(layers "F.Cu" "B.Cu")
		(free yes)
		(net 3)
	)
	(via
		(at 92.217962 140.8665)
		(size 0.45)
		(drill 0.1)
		(layers "F.Cu" "B.Cu")
		(net 3)
	)
	(via
		(at 106.858962 124.134958)
		(size 0.45)
		(drill 0.1)
		(layers "F.Cu" "B.Cu")
		(free yes)
		(net 3)
	)
	(via
		(at 97.667962 164.3415)
		(size 0.45)
		(drill 0.1)
		(layers "F.Cu" "B.Cu")
		(free yes)
		(net 3)
	)
	(via
		(at 92.217962 139.1665)
		(size 0.45)
		(drill 0.1)
		(layers "F.Cu" "B.Cu")
		(net 3)
	)
	(via
		(at 111.092962 153.4035)
		(size 0.45)
		(drill 0.1)
		(layers "F.Cu" "B.Cu")
		(free yes)
		(net 3)
	)
	(via
		(at 51.092962 118.6665)
		(size 0.45)
		(drill 0.1)
		(layers "F.Cu" "B.Cu")
		(net 3)
	)
	(via
		(at 105.6855 157.491252)
		(size 0.45)
		(drill 0.1)
		(layers "F.Cu" "B.Cu")
		(free yes)
		(net 3)
	)
	(via
		(at 63.992962 136.1165)
		(size 0.45)
		(drill 0.1)
		(layers "F.Cu" "B.Cu")
		(net 3)
	)
	(via
		(at 123.3 122.8)
		(size 0.5)
		(drill 0.15)
		(layers "F.Cu" "B.Cu")
		(free yes)
		(net 3)
	)
	(via
		(at 84.697962 129.2865)
		(size 0.45)
		(drill 0.1)
		(layers "F.Cu" "B.Cu")
		(net 3)
	)
	(via
		(at 104.042962 171.0915)
		(size 0.45)
		(drill 0.1)
		(layers "F.Cu" "B.Cu")
		(free yes)
		(net 3)
	)
	(via
		(at 64.867962 130.3165)
		(size 0.45)
		(drill 0.1)
		(layers "F.Cu" "B.Cu")
		(free yes)
		(net 3)
	)
	(via
		(at 74.067962 179.0165)
		(size 0.45)
		(drill 0.1)
		(layers "F.Cu" "B.Cu")
		(net 3)
	)
	(via
		(at 108.347962 120.8965)
		(size 0.45)
		(drill 0.1)
		(layers "F.Cu" "B.Cu")
		(free yes)
		(net 3)
	)
	(via
		(at 129.417962 129.0165)
		(size 0.5)
		(drill 0.15)
		(layers "F.Cu" "B.Cu")
		(net 3)
	)
	(via
		(at 135.567962 153.3065)
		(size 0.45)
		(drill 0.1)
		(layers "F.Cu" "B.Cu")
		(net 3)
	)
	(via
		(at 55.487962 156.4265)
		(size 0.45)
		(drill 0.1)
		(layers "F.Cu" "B.Cu")
		(free yes)
		(net 3)
	)
	(via
		(at 79.5148 122.553617)
		(size 0.45)
		(drill 0.1)
		(layers "F.Cu" "B.Cu")
		(net 3)
	)
	(via
		(at 71.742962 177.6915)
		(size 0.45)
		(drill 0.1)
		(layers "F.Cu" "B.Cu")
		(net 3)
	)
	(via
		(at 129.417962 116.0165)
		(size 0.45)
		(drill 0.1)
		(layers "F.Cu" "B.Cu")
		(net 3)
	)
	(via
		(at 140.279464 163.4165)
		(size 0.45)
		(drill 0.1)
		(layers "F.Cu" "B.Cu")
		(net 3)
	)
	(via
		(at 109.437962 112.6665)
		(size 0.45)
		(drill 0.1)
		(layers "F.Cu" "B.Cu")
		(net 3)
	)
	(via
		(at 88.817962 135.7665)
		(size 0.45)
		(drill 0.1)
		(layers "F.Cu" "B.Cu")
		(net 3)
	)
	(via
		(at 80.675573 156.358889)
		(size 0.45)
		(drill 0.1)
		(layers "F.Cu" "B.Cu")
		(net 3)
	)
	(via
		(at 72.117962 162.6765)
		(size 0.45)
		(drill 0.1)
		(layers "F.Cu" "B.Cu")
		(net 3)
	)
	(via
		(at 79.517962 120.4915)
		(size 0.45)
		(drill 0.1)
		(layers "F.Cu" "B.Cu")
		(net 3)
	)
	(via
		(at 57.767962 156.7765)
		(size 0.45)
		(drill 0.1)
		(layers "F.Cu" "B.Cu")
		(free yes)
		(net 3)
	)
	(via
		(at 40.517962 158.5265)
		(size 0.45)
		(drill 0.1)
		(layers "F.Cu" "B.Cu")
		(free yes)
		(net 3)
	)
	(via
		(at 102.050862 169.8785)
		(size 0.45)
		(drill 0.1)
		(layers "F.Cu" "B.Cu")
		(net 3)
	)
	(via
		(at 116.317962 152.116)
		(size 0.45)
		(drill 0.1)
		(layers "F.Cu" "B.Cu")
		(net 3)
	)
	(via
		(at 105.775 155.825)
		(size 0.45)
		(drill 0.1)
		(layers "F.Cu" "B.Cu")
		(free yes)
		(net 3)
	)
	(via
		(at 129.417962 130.5165)
		(size 0.45)
		(drill 0.1)
		(layers "F.Cu" "B.Cu")
		(net 3)
	)
	(via
		(at 113.167962 149.7165)
		(size 0.45)
		(drill 0.1)
		(layers "F.Cu" "B.Cu")
		(net 3)
	)
	(via
		(at 87.117962 139.1665)
		(size 0.45)
		(drill 0.1)
		(layers "F.Cu" "B.Cu")
		(net 3)
	)
	(via
		(at 132.867962 125.4665)
		(size 0.45)
		(drill 0.1)
		(layers "F.Cu" "B.Cu")
		(net 3)
	)
	(via
		(at 143.242962 147.3665)
		(size 0.45)
		(drill 0.1)
		(layers "F.Cu" "B.Cu")
		(net 3)
	)
	(via
		(at 109.225 158.1245)
		(size 0.45)
		(drill 0.1)
		(layers "F.Cu" "B.Cu")
		(free yes)
		(net 3)
	)
	(via
		(at 116.317962 147.3165)
		(size 0.45)
		(drill 0.1)
		(layers "F.Cu" "B.Cu")
		(net 3)
	)
	(via
		(at 96.492962 124.2165)
		(size 0.45)
		(drill 0.1)
		(layers "F.Cu" "B.Cu")
		(net 3)
	)
	(via
		(at 134.657962 168.9565)
		(size 0.45)
		(drill 0.1)
		(layers "F.Cu" "B.Cu")
		(net 3)
	)
	(via
		(at 80.548302 157.571244)
		(size 0.45)
		(drill 0.1)
		(layers "F.Cu" "B.Cu")
		(net 3)
	)
	(via
		(at 121.33 148.75)
		(size 0.45)
		(drill 0.1)
		(layers "F.Cu" "B.Cu")
		(net 3)
	)
	(via
		(at 124.617962 118.1915)
		(size 0.45)
		(drill 0.1)
		(layers "F.Cu" "B.Cu")
		(net 3)
	)
	(via
		(at 37.857962 165.8165)
		(size 0.45)
		(drill 0.1)
		(layers "F.Cu" "B.Cu")
		(net 3)
	)
	(via
		(at 113.187962 159.316)
		(size 0.45)
		(drill 0.1)
		(layers "F.Cu" "B.Cu")
		(free yes)
		(net 3)
	)
	(via
		(at 130.627962 112.8565)
		(size 0.45)
		(drill 0.1)
		(layers "F.Cu" "B.Cu")
		(net 3)
	)
	(via
		(at 107.577962 126.3565)
		(size 0.45)
		(drill 0.1)
		(layers "F.Cu" "B.Cu")
		(free yes)
		(net 3)
	)
	(via
		(at 80.617962 152.7165)
		(size 0.45)
		(drill 0.1)
		(layers "F.Cu" "B.Cu")
		(net 3)
	)
	(via
		(at 142.757962 170.7965)
		(size 0.45)
		(drill 0.1)
		(layers "F.Cu" "B.Cu")
		(net 3)
	)
	(via
		(at 83.317962 144.2165)
		(size 0.45)
		(drill 0.1)
		(layers "F.Cu" "B.Cu")
		(free yes)
		(net 3)
	)
	(via
		(at 52.967962 162.6165)
		(size 0.45)
		(drill 0.1)
		(layers "F.Cu" "B.Cu")
		(free yes)
		(net 3)
	)
	(via
		(at 104.617962 126.3565)
		(size 0.45)
		(drill 0.1)
		(layers "F.Cu" "B.Cu")
		(free yes)
		(net 3)
	)
	(via
		(at 139.44486 126.092489)
		(size 0.45)
		(drill 0.1)
		(layers "F.Cu" "B.Cu")
		(free yes)
		(net 3)
	)
	(via
		(at 140.717962 140.4165)
		(size 0.45)
		(drill 0.1)
		(layers "F.Cu" "B.Cu")
		(free yes)
		(net 3)
	)
	(via
		(at 62.817962 176.2005)
		(size 0.45)
		(drill 0.1)
		(layers "F.Cu" "B.Cu")
		(net 3)
	)
	(via
		(at 66.757962 157.9565)
		(size 0.45)
		(drill 0.1)
		(layers "F.Cu" "B.Cu")
		(net 3)
	)
	(via
		(at 94.967962 128.8665)
		(size 0.45)
		(drill 0.1)
		(layers "F.Cu" "B.Cu")
		(net 3)
	)
	(via
		(at 54.207962 159.1065)
		(size 0.45)
		(drill 0.1)
		(layers "F.Cu" "B.Cu")
		(free yes)
		(net 3)
	)
	(via
		(at 67.017962 179.1665)
		(size 0.45)
		(drill 0.1)
		(layers "F.Cu" "B.Cu")
		(net 3)
	)
	(via
		(at 103.327962 124.4465)
		(size 0.45)
		(drill 0.1)
		(layers "F.Cu" "B.Cu")
		(net 3)
	)
	(via
		(at 73.847962 112.7165)
		(size 0.45)
		(drill 0.1)
		(layers "F.Cu" "B.Cu")
		(net 3)
	)
	(via
		(at 51.377962 156.3565)
		(size 0.45)
		(drill 0.1)
		(layers "F.Cu" "B.Cu")
		(free yes)
		(net 3)
	)
	(via
		(at 83.573574 125.169294)
		(size 0.45)
		(drill 0.1)
		(layers "F.Cu" "B.Cu")
		(net 3)
	)
	(via
		(at 71.592962 171.8165)
		(size 0.45)
		(drill 0.1)
		(layers "F.Cu" "B.Cu")
		(net 3)
	)
	(via
		(at 93.337962 171.1465)
		(size 0.45)
		(drill 0.1)
		(layers "F.Cu" "B.Cu")
		(net 3)
	)
	(via
		(at 49.707962 120.3165)
		(size 0.45)
		(drill 0.1)
		(layers "F.Cu" "B.Cu")
		(net 3)
	)
	(via
		(at 96.497962 117.0565)
		(size 0.45)
		(drill 0.1)
		(layers "F.Cu" "B.Cu")
		(net 3)
	)
	(via
		(at 119.1 173.8)
		(size 0.45)
		(drill 0.1)
		(layers "F.Cu" "B.Cu")
		(net 3)
	)
	(via
		(at 57.667962 156.0665)
		(size 0.45)
		(drill 0.1)
		(layers "F.Cu" "B.Cu")
		(free yes)
		(net 3)
	)
	(via
		(at 76.567962 138.8665)
		(size 0.45)
		(drill 0.1)
		(layers "F.Cu" "B.Cu")
		(net 3)
	)
	(via
		(at 131.107962 170.6665)
		(size 0.45)
		(drill 0.1)
		(layers "F.Cu" "B.Cu")
		(net 3)
	)
	(via
		(at 95.692962 169.1915)
		(size 0.45)
		(drill 0.1)
		(layers "F.Cu" "B.Cu")
		(net 3)
	)
	(via
		(at 88.242962 127.8915)
		(size 0.45)
		(drill 0.1)
		(layers "F.Cu" "B.Cu")
		(net 3)
	)
	(via
		(at 64.892962 172.7415)
		(size 0.45)
		(drill 0.1)
		(layers "F.Cu" "B.Cu")
		(net 3)
	)
	(via
		(at 77.692962 146.117)
		(size 0.45)
		(drill 0.1)
		(layers "F.Cu" "B.Cu")
		(free yes)
		(net 3)
	)
	(via
		(at 116.317962 161.7165)
		(size 0.45)
		(drill 0.1)
		(layers "F.Cu" "B.Cu")
		(net 3)
	)
	(via
		(at 101.867962 175.1415)
		(size 0.45)
		(drill 0.1)
		(layers "F.Cu" "B.Cu")
		(net 3)
	)
	(via
		(at 113.267962 161.7165)
		(size 0.45)
		(drill 0.1)
		(layers "F.Cu" "B.Cu")
		(free yes)
		(net 3)
	)
	(via
		(at 108.358962 124.144958)
		(size 0.45)
		(drill 0.1)
		(layers "F.Cu" "B.Cu")
		(free yes)
		(net 3)
	)
	(via
		(at 135.017962 144.1915)
		(size 0.45)
		(drill 0.1)
		(layers "F.Cu" "B.Cu")
		(net 3)
	)
	(via
		(at 96.692962 130.4665)
		(size 0.45)
		(drill 0.1)
		(layers "F.Cu" "B.Cu")
		(net 3)
	)
	(via
		(at 64.627962 157.8665)
		(size 0.45)
		(drill 0.1)
		(layers "F.Cu" "B.Cu")
		(net 3)
	)
	(via
		(at 89.957962 179.11)
		(size 0.45)
		(drill 0.1)
		(layers "F.Cu" "B.Cu")
		(net 3)
	)
	(via
		(at 46.267962 119.6665)
		(size 0.45)
		(drill 0.1)
		(layers "F.Cu" "B.Cu")
		(net 3)
	)
	(via
		(at 49.687962 117.2165)
		(size 0.45)
		(drill 0.1)
		(layers "F.Cu" "B.Cu")
		(net 3)
	)
	(via
		(at 112.552962 134.5465)
		(size 0.45)
		(drill 0.1)
		(layers "F.Cu" "B.Cu")
		(net 3)
	)
	(via
		(at 56.727962 154.3665)
		(size 0.45)
		(drill 0.1)
		(layers "F.Cu" "B.Cu")
		(free yes)
		(net 3)
	)
	(via
		(at 64.342962 176.3415)
		(size 0.45)
		(drill 0.1)
		(layers "F.Cu" "B.Cu")
		(net 3)
	)
	(via
		(at 69.892962 170.1165)
		(size 0.45)
		(drill 0.1)
		(layers "F.Cu" "B.Cu")
		(net 3)
	)
	(via
		(at 50.387962 117.2165)
		(size 0.45)
		(drill 0.1)
		(layers "F.Cu" "B.Cu")
		(net 3)
	)
	(via
		(at 135.313872 146.051)
		(size 0.45)
		(drill 0.1)
		(layers "F.Cu" "B.Cu")
		(free yes)
		(net 3)
	)
	(via
		(at 68.117962 164.7165)
		(size 0.45)
		(drill 0.1)
		(layers "F.Cu" "B.Cu")
		(free yes)
		(net 3)
	)
	(via
		(at 140.387962 167.6665)
		(size 0.45)
		(drill 0.1)
		(layers "F.Cu" "B.Cu")
		(net 3)
	)
	(via
		(at 51.377962 165.4365)
		(size 0.45)
		(drill 0.1)
		(layers "F.Cu" "B.Cu")
		(free yes)
		(net 3)
	)
	(via
		(at 139.317962 129.2265)
		(size 0.45)
		(drill 0.1)
		(layers "F.Cu" "B.Cu")
		(free yes)
		(net 3)
	)
	(via
		(at 135.319016 125.726547)
		(size 0.45)
		(drill 0.1)
		(layers "F.Cu" "B.Cu")
		(free yes)
		(net 3)
	)
	(via
		(at 136.542962 137.9665)
		(size 0.45)
		(drill 0.1)
		(layers "F.Cu" "B.Cu")
		(net 3)
	)
	(via
		(at 119.09 153.3)
		(size 0.45)
		(drill 0.1)
		(layers "F.Cu" "B.Cu")
		(net 3)
	)
	(via
		(at 72.467962 177.8665)
		(size 0.45)
		(drill 0.1)
		(layers "F.Cu" "B.Cu")
		(net 3)
	)
	(via
		(at 63.417962 153.9265)
		(size 0.45)
		(drill 0.1)
		(layers "F.Cu" "B.Cu")
		(free yes)
		(net 3)
	)
	(via
		(at 143.467962 120.4865)
		(size 0.45)
		(drill 0.1)
		(layers "F.Cu" "B.Cu")
		(net 3)
	)
	(via
		(at 90.467962 170.6915)
		(size 0.45)
		(drill 0.1)
		(layers "F.Cu" "B.Cu")
		(net 3)
	)
	(via
		(at 60.542962 176.2255)
		(size 0.45)
		(drill 0.1)
		(layers "F.Cu" "B.Cu")
		(net 3)
	)
	(via
		(at 51.917962 175.0265)
		(size 0.45)
		(drill 0.1)
		(layers "F.Cu" "B.Cu")
		(net 3)
	)
	(via
		(at 71.897962 130.8765)
		(size 0.45)
		(drill 0.1)
		(layers "F.Cu" "B.Cu")
		(net 3)
	)
	(via
		(at 133.042961 150.1415)
		(size 0.45)
		(drill 0.1)
		(layers "F.Cu" "B.Cu")
		(net 3)
	)
	(via
		(at 112.542962 118.3415)
		(size 0.45)
		(drill 0.1)
		(layers "F.Cu" "B.Cu")
		(net 3)
	)
	(via
		(at 99.417962 178.2165)
		(size 0.45)
		(drill 0.1)
		(layers "F.Cu" "B.Cu")
		(net 3)
	)
	(via
		(at 64.357962 139.0065)
		(size 0.45)
		(drill 0.1)
		(layers "F.Cu" "B.Cu")
		(net 3)
	)
	(via
		(at 46.267962 117.8665)
		(size 0.45)
		(drill 0.1)
		(layers "F.Cu" "B.Cu")
		(net 3)
	)
	(via
		(at 118.025384 161.797207)
		(size 0.45)
		(drill 0.1)
		(layers "F.Cu" "B.Cu")
		(net 3)
	)
	(via
		(at 135.307738 127.716498)
		(size 0.45)
		(drill 0.1)
		(layers "F.Cu" "B.Cu")
		(free yes)
		(net 3)
	)
	(via
		(at 117.242962 133.623677)
		(size 0.45)
		(drill 0.1)
		(layers "F.Cu" "B.Cu")
		(net 3)
	)
	(via
		(at 113.167962 150.9165)
		(size 0.45)
		(drill 0.1)
		(layers "F.Cu" "B.Cu")
		(net 3)
	)
	(via
		(at 40.167962 153.2065)
		(size 0.45)
		(drill 0.1)
		(layers "F.Cu" "B.Cu")
		(free yes)
		(net 3)
	)
	(via
		(at 62.442962 161.1415)
		(size 0.45)
		(drill 0.1)
		(layers "F.Cu" "B.Cu")
		(free yes)
		(net 3)
	)
	(via
		(at 45.827962 162.5565)
		(size 0.45)
		(drill 0.1)
		(layers "F.Cu" "B.Cu")
		(free yes)
		(net 3)
	)
	(via
		(at 89.817962 120.0915)
		(size 0.45)
		(drill 0.1)
		(layers "F.Cu" "B.Cu")
		(net 3)
	)
	(via
		(at 62.817962 177.2255)
		(size 0.45)
		(drill 0.1)
		(layers "F.Cu" "B.Cu")
		(net 3)
	)
	(via
		(at 67.109962 166.05)
		(size 0.45)
		(drill 0.1)
		(layers "F.Cu" "B.Cu")
		(net 3)
	)
	(via
		(at 127.067962 126.0165)
		(size 0.5)
		(drill 0.15)
		(layers "F.Cu" "B.Cu")
		(net 3)
	)
	(via
		(at 90.467962 169.1915)
		(size 0.45)
		(drill 0.1)
		(layers "F.Cu" "B.Cu")
		(net 3)
	)
	(via
		(at 99.442962 148.718)
		(size 0.45)
		(drill 0.1)
		(layers "F.Cu" "B.Cu")
		(net 3)
	)
	(via
		(at 121.5 158.13)
		(size 0.45)
		(drill 0.1)
		(layers "F.Cu" "B.Cu")
		(net 3)
	)
	(via
		(at 80.842962 146.1255)
		(size 0.45)
		(drill 0.1)
		(layers "F.Cu" "B.Cu")
		(free yes)
		(net 3)
	)
	(via
		(at 133.042961 147.1665)
		(size 0.45)
		(drill 0.1)
		(layers "F.Cu" "B.Cu")
		(net 3)
	)
	(via
		(at 90.489564 164.490298)
		(size 0.45)
		(drill 0.1)
		(layers "F.Cu" "B.Cu")
		(net 3)
	)
	(via
		(at 70.942962 149.1915)
		(size 0.45)
		(drill 0.1)
		(layers "F.Cu" "B.Cu")
		(net 3)
	)
	(via
		(at 80.992962 166.5915)
		(size 0.45)
		(drill 0.1)
		(layers "F.Cu" "B.Cu")
		(net 3)
	)
	(via
		(at 86.167962 144.2415)
		(size 0.45)
		(drill 0.1)
		(layers "F.Cu" "B.Cu")
		(net 3)
	)
	(via
		(at 73.233483 121.330979)
		(size 0.45)
		(drill 0.1)
		(layers "F.Cu" "B.Cu")
		(net 3)
	)
	(via
		(at 100.792962 150.8665)
		(size 0.45)
		(drill 0.1)
		(layers "F.Cu" "B.Cu")
		(net 3)
	)
	(via
		(at 86.767962 152.2415)
		(size 0.45)
		(drill 0.1)
		(layers "F.Cu" "B.Cu")
		(net 3)
	)
	(via
		(at 113.667962 134.5615)
		(size 0.45)
		(drill 0.1)
		(layers "F.Cu" "B.Cu")
		(net 3)
	)
	(via
		(at 71.592962 173.5165)
		(size 0.45)
		(drill 0.1)
		(layers "F.Cu" "B.Cu")
		(net 3)
	)
	(via
		(at 127.067962 121.5165)
		(size 0.45)
		(drill 0.1)
		(layers "F.Cu" "B.Cu")
		(net 3)
	)
	(via
		(at 139.192962 148.1415)
		(size 0.45)
		(drill 0.1)
		(layers "F.Cu" "B.Cu")
		(free yes)
		(net 3)
	)
	(via
		(at 113.342948 162.9165)
		(size 0.45)
		(drill 0.1)
		(layers "F.Cu" "B.Cu")
		(free yes)
		(net 3)
	)
	(via
		(at 48.187962 165.4365)
		(size 0.45)
		(drill 0.1)
		(layers "F.Cu" "B.Cu")
		(free yes)
		(net 3)
	)
	(via
		(at 51.927962 178.6165)
		(size 0.45)
		(drill 0.1)
		(layers "F.Cu" "B.Cu")
		(net 3)
	)
	(via
		(at 136.517885 136.446423)
		(size 0.45)
		(drill 0.1)
		(layers "F.Cu" "B.Cu")
		(net 3)
	)
	(via
		(at 113.157962 158.116)
		(size 0.45)
		(drill 0.1)
		(layers "F.Cu" "B.Cu")
		(free yes)
		(net 3)
	)
	(via
		(at 63.507962 168.3165)
		(size 0.45)
		(drill 0.1)
		(layers "F.Cu" "B.Cu")
		(net 3)
	)
	(via
		(at 140.281464 164.3915)
		(size 0.45)
		(drill 0.1)
		(layers "F.Cu" "B.Cu")
		(net 3)
	)
	(via
		(at 125.667962 162.5915)
		(size 0.45)
		(drill 0.1)
		(layers "F.Cu" "B.Cu")
		(free yes)
		(net 3)
	)
	(via
		(at 109.275 156.925)
		(size 0.45)
		(drill 0.1)
		(layers "F.Cu" "B.Cu")
		(free yes)
		(net 3)
	)
	(via
		(at 104.757962 127.6765)
		(size 0.45)
		(drill 0.1)
		(layers "F.Cu" "B.Cu")
		(net 3)
	)
	(via
		(at 142.757962 178.7765)
		(size 0.45)
		(drill 0.1)
		(layers "F.Cu" "B.Cu")
		(net 3)
	)
	(via
		(at 43.817962 134.2565)
		(size 0.45)
		(drill 0.1)
		(layers "F.Cu" "B.Cu")
		(free yes)
		(net 3)
	)
	(via
		(at 111.367962 135.9665)
		(size 0.45)
		(drill 0.1)
		(layers "F.Cu" "B.Cu")
		(net 3)
	)
	(via
		(at 114.727962 134.5465)
		(size 0.45)
		(drill 0.1)
		(layers "F.Cu" "B.Cu")
		(net 3)
	)
	(via
		(at 83.99 122.72)
		(size 0.45)
		(drill 0.1)
		(layers "F.Cu" "B.Cu")
		(net 3)
	)
	(via
		(at 122.660284 120.785284)
		(size 0.5)
		(drill 0.15)
		(layers "F.Cu" "B.Cu")
		(free yes)
		(net 3)
	)
	(via
		(at 114.217962 145.6665)
		(size 0.45)
		(drill 0.1)
		(layers "F.Cu" "B.Cu")
		(net 3)
	)
	(via
		(at 106.897962 138.2265)
		(size 0.45)
		(drill 0.1)
		(layers "F.Cu" "B.Cu")
		(net 3)
	)
	(via
		(at 81.017962 168.8265)
		(size 0.45)
		(drill 0.1)
		(layers "F.Cu" "B.Cu")
		(net 3)
	)
	(via
		(at 73.292962 171.8165)
		(size 0.45)
		(drill 0.1)
		(layers "F.Cu" "B.Cu")
		(net 3)
	)
	(via
		(at 65.66 170.4165)
		(size 0.45)
		(drill 0.1)
		(layers "F.Cu" "B.Cu")
		(net 3)
	)
	(via
		(at 76.142962 167.6915)
		(size 0.45)
		(drill 0.1)
		(layers "F.Cu" "B.Cu")
		(net 3)
	)
	(via
		(at 116.6 156.9165)
		(size 0.45)
		(drill 0.1)
		(layers "F.Cu" "B.Cu")
		(net 3)
	)
	(via
		(at 54.397962 152.5965)
		(size 0.45)
		(drill 0.1)
		(layers "F.Cu" "B.Cu")
		(free yes)
		(net 3)
	)
	(via
		(at 37.967962 121.4865)
		(size 0.45)
		(drill 0.1)
		(layers "F.Cu" "B.Cu")
		(net 3)
	)
	(via
		(at 86.96 117.7)
		(size 0.45)
		(drill 0.1)
		(layers "F.Cu" "B.Cu")
		(net 3)
	)
	(via
		(at 97.967962 143.4165)
		(size 0.45)
		(drill 0.1)
		(layers "F.Cu" "B.Cu")
		(net 3)
	)
	(via
		(at 88.742962 149.3665)
		(size 0.45)
		(drill 0.1)
		(layers "F.Cu" "B.Cu")
		(net 3)
	)
	(via
		(at 125.042962 166.9915)
		(size 0.45)
		(drill 0.1)
		(layers "F.Cu" "B.Cu")
		(net 3)
	)
	(via
		(at 55.567962 157.1665)
		(size 0.45)
		(drill 0.1)
		(layers "F.Cu" "B.Cu")
		(free yes)
		(net 3)
	)
	(via
		(at 110.092962 115.7165)
		(size 0.45)
		(drill 0.1)
		(layers "F.Cu" "B.Cu")
		(net 3)
	)
	(via
		(at 64.637962 157.0065)
		(size 0.45)
		(drill 0.1)
		(layers "F.Cu" "B.Cu")
		(net 3)
	)
	(via
		(at 113.267962 155.7165)
		(size 0.45)
		(drill 0.1)
		(layers "F.Cu" "B.Cu")
		(free yes)
		(net 3)
	)
	(via
		(at 129.417962 116.8415)
		(size 0.45)
		(drill 0.1)
		(layers "F.Cu" "B.Cu")
		(net 3)
	)
	(via
		(at 126.867962 116.5415)
		(size 0.45)
		(drill 0.1)
		(layers "F.Cu" "B.Cu")
		(net 3)
	)
	(via
		(at 51.907962 120.3365)
		(size 0.45)
		(drill 0.1)
		(layers "F.Cu" "B.Cu")
		(net 3)
	)
	(via
		(at 69.817962 178.0665)
		(size 0.45)
		(drill 0.1)
		(layers "F.Cu" "B.Cu")
		(net 3)
	)
	(via
		(at 116.317962 160.5165)
		(size 0.45)
		(drill 0.1)
		(layers "F.Cu" "B.Cu")
		(net 3)
	)
	(via
		(at 96.717962 145.2665)
		(size 0.45)
		(drill 0.1)
		(layers "F.Cu" "B.Cu")
		(net 3)
	)
	(via
		(at 102.092962 172.6665)
		(size 0.45)
		(drill 0.1)
		(layers "F.Cu" "B.Cu")
		(net 3)
	)
	(via
		(at 123.3 124.73)
		(size 0.5)
		(drill 0.15)
		(layers "F.Cu" "B.Cu")
		(free yes)
		(net 3)
	)
	(via
		(at 127.067962 124.5165)
		(size 0.5)
		(drill 0.15)
		(layers "F.Cu" "B.Cu")
		(net 3)
	)
	(via
		(at 37.887962 112.9665)
		(size 0.45)
		(drill 0.1)
		(layers "F.Cu" "B.Cu")
		(free yes)
		(net 3)
	)
	(via
		(at 95.717962 173.6915)
		(size 0.45)
		(drill 0.1)
		(layers "F.Cu" "B.Cu")
		(net 3)
	)
	(via
		(at 95.717962 176.6915)
		(size 0.45)
		(drill 0.1)
		(layers "F.Cu" "B.Cu")
		(net 3)
	)
	(via
		(at 50.392962 119.3665)
		(size 0.45)
		(drill 0.1)
		(layers "F.Cu" "B.Cu")
		(net 3)
	)
	(via
		(at 113.567962 146.2665)
		(size 0.45)
		(drill 0.1)
		(layers "F.Cu" "B.Cu")
		(net 3)
	)
	(via
		(at 51.907962 121.0365)
		(size 0.45)
		(drill 0.1)
		(layers "F.Cu" "B.Cu")
		(net 3)
	)
	(via
		(at 121.5 154.45)
		(size 0.45)
		(drill 0.1)
		(layers "F.Cu" "B.Cu")
		(net 3)
	)
	(via
		(at 108.917962 139.2665)
		(size 0.45)
		(drill 0.1)
		(layers "F.Cu" "B.Cu")
		(free yes)
		(net 3)
	)
	(via
		(at 132.314029 120.0415)
		(size 0.45)
		(drill 0.1)
		(layers "F.Cu" "B.Cu")
		(net 3)
	)
	(via
		(at 106.95 156.975)
		(size 0.45)
		(drill 0.1)
		(layers "F.Cu" "B.Cu")
		(free yes)
		(net 3)
	)
	(via
		(at 143.242962 150.3415)
		(size 0.45)
		(drill 0.1)
		(layers "F.Cu" "B.Cu")
		(net 3)
	)
	(via
		(at 106.847962 120.8865)
		(size 0.45)
		(drill 0.1)
		(layers "F.Cu" "B.Cu")
		(free yes)
		(net 3)
	)
	(via
		(at 130.2 131.325)
		(size 0.5)
		(drill 0.15)
		(layers "F.Cu" "B.Cu")
		(free yes)
		(net 3)
	)
	(via
		(at 46.267962 112.4665)
		(size 0.45)
		(drill 0.1)
		(layers "F.Cu" "B.Cu")
		(net 3)
	)
	(via
		(at 126.017962 121.5165)
		(size 0.5)
		(drill 0.15)
		(layers "F.Cu" "B.Cu")
		(free yes)
		(net 3)
	)
	(via
		(at 129.067962 155.4415)
		(size 0.45)
		(drill 0.1)
		(layers "F.Cu" "B.Cu")
		(net 3)
	)
	(via
		(at 49.687962 118.6665)
		(size 0.45)
		(drill 0.1)
		(layers "F.Cu" "B.Cu")
		(net 3)
	)
	(via
		(at 102.177962 126.7565)
		(size 0.45)
		(drill 0.1)
		(layers "F.Cu" "B.Cu")
		(net 3)
	)
	(via
		(at 110.667962 136.5915)
		(size 0.45)
		(drill 0.1)
		(layers "F.Cu" "B.Cu")
		(free yes)
		(net 3)
	)
	(via
		(at 74.172962 124.6315)
		(size 0.45)
		(drill 0.1)
		(layers "F.Cu" "B.Cu")
		(net 3)
	)
	(via
		(at 58.627962 173.4965)
		(size 0.45)
		(drill 0.1)
		(layers "F.Cu" "B.Cu")
		(net 3)
	)
	(via
		(at 88.50814 175.19158)
		(size 0.45)
		(drill 0.1)
		(layers "F.Cu" "B.Cu")
		(net 3)
	)
	(via
		(at 143.242962 141.4165)
		(size 0.45)
		(drill 0.1)
		(layers "F.Cu" "B.Cu")
		(net 3)
	)
	(via
		(at 75.942962 119.9665)
		(size 0.45)
		(drill 0.1)
		(layers "F.Cu" "B.Cu")
		(net 3)
	)
	(via
		(at 70.037962 130.1465)
		(size 0.45)
		(drill 0.1)
		(layers "F.Cu" "B.Cu")
		(free yes)
		(net 3)
	)
	(via
		(at 100.867962 123.1865)
		(size 0.45)
		(drill 0.1)
		(layers "F.Cu" "B.Cu")
		(net 3)
	)
	(via
		(at 116.317962 162.9165)
		(size 0.45)
		(drill 0.1)
		(layers "F.Cu" "B.Cu")
		(net 3)
	)
	(via
		(at 78.867962 123.7165)
		(size 0.45)
		(drill 0.1)
		(layers "F.Cu" "B.Cu")
		(net 3)
	)
	(via
		(at 121.5 156.9195)
		(size 0.45)
		(drill 0.1)
		(layers "F.Cu" "B.Cu")
		(net 3)
	)
	(via
		(at 82.477962 112.6865)
		(size 0.45)
		(drill 0.1)
		(layers "F.Cu" "B.Cu")
		(net 3)
	)
	(via
		(at 90.517962 140.8665)
		(size 0.45)
		(drill 0.1)
		(layers "F.Cu" "B.Cu")
		(net 3)
	)
	(via
		(at 44.237962 162.2875)
		(size 0.45)
		(drill 0.1)
		(layers "F.Cu" "B.Cu")
		(free yes)
		(net 3)
	)
	(via
		(at 106.302962 133.5165)
		(size 0.45)
		(drill 0.1)
		(layers "F.Cu" "B.Cu")
		(net 3)
	)
	(via
		(at 80.092962 149.7665)
		(size 0.45)
		(drill 0.1)
		(layers "F.Cu" "B.Cu")
		(net 3)
	)
	(via
		(at 87.617962 127.8915)
		(size 0.45)
		(drill 0.1)
		(layers "F.Cu" "B.Cu")
		(net 3)
	)
	(via
		(at 74.177962 119.7665)
		(size 0.45)
		(drill 0.1)
		(layers "F.Cu" "B.Cu")
		(net 3)
	)
	(via
		(at 136.292962 130.4665)
		(size 0.45)
		(drill 0.1)
		(layers "F.Cu" "B.Cu")
		(net 3)
	)
	(via
		(at 136.292962 131.9915)
		(size 0.45)
		(drill 0.1)
		(layers "F.Cu" "B.Cu")
		(net 3)
	)
	(via
		(at 125.192962 165.2415)
		(size 0.45)
		(drill 0.1)
		(layers "F.Cu" "B.Cu")
		(free yes)
		(net 3)
	)
	(via
		(at 119.09 156.9195)
		(size 0.45)
		(drill 0.1)
		(layers "F.Cu" "B.Cu")
		(net 3)
	)
	(via
		(at 101.037962 154.9565)
		(size 0.45)
		(drill 0.1)
		(layers "F.Cu" "B.Cu")
		(net 3)
	)
	(via
		(at 113.167962 152.1165)
		(size 0.45)
		(drill 0.1)
		(layers "F.Cu" "B.Cu")
		(net 3)
	)
	(via
		(at 95.217962 152.7915)
		(size 0.45)
		(drill 0.1)
		(layers "F.Cu" "B.Cu")
		(net 3)
	)
	(via
		(at 77.393787 155.386073)
		(size 0.45)
		(drill 0.1)
		(layers "F.Cu" "B.Cu")
		(net 3)
	)
	(via
		(at 140.292962 159.0165)
		(size 0.45)
		(drill 0.1)
		(layers "F.Cu" "B.Cu")
		(net 3)
	)
	(via
		(at 118.237962 158.1135)
		(size 0.45)
		(drill 0.1)
		(layers "F.Cu" "B.Cu")
		(net 3)
	)
	(via
		(at 61.187962 171.2265)
		(size 0.45)
		(drill 0.1)
		(layers "F.Cu" "B.Cu")
		(free yes)
		(net 3)
	)
	(via
		(at 64.892962 171.6165)
		(size 0.45)
		(drill 0.1)
		(layers "F.Cu" "B.Cu")
		(net 3)
	)
	(via
		(at 109.987962 178.8365)
		(size 0.45)
		(drill 0.1)
		(layers "F.Cu" "B.Cu")
		(net 3)
	)
	(via
		(at 108.787962 136.3065)
		(size 0.45)
		(drill 0.1)
		(layers "F.Cu" "B.Cu")
		(net 3)
	)
	(via
		(at 51.907962 121.7365)
		(size 0.45)
		(drill 0.1)
		(layers "F.Cu" "B.Cu")
		(net 3)
	)
	(via
		(at 136.567962 155.4165)
		(size 0.45)
		(drill 0.1)
		(layers "F.Cu" "B.Cu")
		(net 3)
	)
	(via
		(at 139.327962 127.2265)
		(size 0.45)
		(drill 0.1)
		(layers "F.Cu" "B.Cu")
		(free yes)
		(net 3)
	)
	(via
		(at 51.092962 117.9665)
		(size 0.45)
		(drill 0.1)
		(layers "F.Cu" "B.Cu")
		(net 3)
	)
	(via
		(at 90.467962 173.7665)
		(size 0.45)
		(drill 0.1)
		(layers "F.Cu" "B.Cu")
		(net 3)
	)
	(via
		(at 48.177962 158.7965)
		(size 0.45)
		(drill 0.1)
		(layers "F.Cu" "B.Cu")
		(free yes)
		(net 3)
	)
	(via
		(at 79.967962 156.9965)
		(size 0.45)
		(drill 0.1)
		(layers "F.Cu" "B.Cu")
		(net 3)
	)
	(via
		(at 100.267962 175.0665)
		(size 0.45)
		(drill 0.1)
		(layers "F.Cu" "B.Cu")
		(net 3)
	)
	(via
		(at 85.395823 133.238639)
		(size 0.45)
		(drill 0.1)
		(layers "F.Cu" "B.Cu")
		(net 3)
	)
	(via
		(at 76.567962 119.9665)
		(size 0.45)
		(drill 0.1)
		(layers "F.Cu" "B.Cu")
		(net 3)
	)
	(via
		(at 89.142962 120.0915)
		(size 0.45)
		(drill 0.1)
		(layers "F.Cu" "B.Cu")
		(net 3)
	)
	(via
		(at 58.767962 179.1065)
		(size 0.45)
		(drill 0.1)
		(layers "F.Cu" "B.Cu")
		(net 3)
	)
	(via
		(at 113.187962 160.516)
		(size 0.45)
		(drill 0.1)
		(layers "F.Cu" "B.Cu")
		(free yes)
		(net 3)
	)
	(via
		(at 112.867962 124.2415)
		(size 0.45)
		(drill 0.1)
		(layers "F.Cu" "B.Cu")
		(net 3)
	)
	(via
		(at 96.742962 138.7915)
		(size 0.45)
		(drill 0.1)
		(layers "F.Cu" "B.Cu")
		(net 3)
	)
	(via
		(at 80.842962 164.5665)
		(size 0.45)
		(drill 0.1)
		(layers "F.Cu" "B.Cu")
		(net 3)
	)
	(via
		(at 135.392962 161.454)
		(size 0.45)
		(drill 0.1)
		(layers "F.Cu" "B.Cu")
		(net 3)
	)
	(via
		(at 95.217962 154.1915)
		(size 0.45)
		(drill 0.1)
		(layers "F.Cu" "B.Cu")
		(net 3)
	)
	(via
		(at 90.492962 147.1165)
		(size 0.45)
		(drill 0.1)
		(layers "F.Cu" "B.Cu")
		(net 3)
	)
	(via
		(at 82.417962 159.5415)
		(size 0.45)
		(drill 0.1)
		(layers "F.Cu" "B.Cu")
		(net 3)
	)
	(via
		(at 129.417962 132.0165)
		(size 0.45)
		(drill 0.1)
		(layers "F.Cu" "B.Cu")
		(net 3)
	)
	(via
		(at 105.592962 133.5915)
		(size 0.45)
		(drill 0.1)
		(layers "F.Cu" "B.Cu")
		(net 3)
	)
	(via
		(at 140.092962 136.6415)
		(size 0.45)
		(drill 0.1)
		(layers "F.Cu" "B.Cu")
		(net 3)
	)
	(via
		(at 51.092962 119.3665)
		(size 0.45)
		(drill 0.1)
		(layers "F.Cu" "B.Cu")
		(net 3)
	)
	(via
		(at 135.079462 150.036611)
		(size 0.45)
		(drill 0.1)
		(layers "F.Cu" "B.Cu")
		(net 3)
	)
	(via
		(at 139.217962 144.4665)
		(size 0.45)
		(drill 0.1)
		(layers "F.Cu" "B.Cu")
		(free yes)
		(net 3)
	)
	(via
		(at 137.487962 169.0765)
		(size 0.45)
		(drill 0.1)
		(layers "F.Cu" "B.Cu")
		(net 3)
	)
	(via
		(at 96.617962 152.7915)
		(size 0.45)
		(drill 0.1)
		(layers "F.Cu" "B.Cu")
		(net 3)
	)
	(via
		(at 118.131265 160.5245)
		(size 0.45)
		(drill 0.1)
		(layers "F.Cu" "B.Cu")
		(net 3)
	)
	(via
		(at 116.317962 148.5165)
		(size 0.45)
		(drill 0.1)
		(layers "F.Cu" "B.Cu")
		(net 3)
	)
	(via
		(at 68.790962 175.130476)
		(size 0.45)
		(drill 0.1)
		(layers "F.Cu" "B.Cu")
		(net 3)
	)
	(via
		(at 116.227962 132.6665)
		(size 0.45)
		(drill 0.1)
		(layers "F.Cu" "B.Cu")
		(net 3)
	)
	(via
		(at 76.417962 175.3915)
		(size 0.45)
		(drill 0.1)
		(layers "F.Cu" "B.Cu")
		(net 3)
	)
	(via
		(at 92.767962 122.239108)
		(size 0.45)
		(drill 0.1)
		(layers "F.Cu" "B.Cu")
		(net 3)
	)
	(via
		(at 94.342962 127.2915)
		(size 0.45)
		(drill 0.1)
		(layers "F.Cu" "B.Cu")
		(net 3)
	)
	(via
		(at 83.277962 116.9865)
		(size 0.45)
		(drill 0.1)
		(layers "F.Cu" "B.Cu")
		(net 3)
	)
	(via
		(at 140.092962 134.5665)
		(size 0.45)
		(drill 0.1)
		(layers "F.Cu" "B.Cu")
		(net 3)
	)
	(via
		(at 92.217962 135.7665)
		(size 0.45)
		(drill 0.1)
		(layers "F.Cu" "B.Cu")
		(net 3)
	)
	(via
		(at 116.683861 154.5195)
		(size 0.45)
		(drill 0.1)
		(layers "F.Cu" "B.Cu")
		(net 3)
	)
	(via
		(at 93.317962 165.9165)
		(size 0.45)
		(drill 0.1)
		(layers "F.Cu" "B.Cu")
		(free yes)
		(net 3)
	)
	(via
		(at 53.507962 172.3565)
		(size 0.45)
		(drill 0.1)
		(layers "F.Cu" "B.Cu")
		(free yes)
		(net 3)
	)
	(via
		(at 85.892962 166.0665)
		(size 0.45)
		(drill 0.1)
		(layers "F.Cu" "B.Cu")
		(free yes)
		(net 3)
	)
	(via
		(at 103.307962 127.6565)
		(size 0.45)
		(drill 0.1)
		(layers "F.Cu" "B.Cu")
		(net 3)
	)
	(via
		(at 93.817962 151.3915)
		(size 0.45)
		(drill 0.1)
		(layers "F.Cu" "B.Cu")
		(net 3)
	)
	(via
		(at 57.617962 130.2965)
		(size 0.45)
		(drill 0.1)
		(layers "F.Cu" "B.Cu")
		(net 3)
	)
	(via
		(at 59.527962 156.4865)
		(size 0.45)
		(drill 0.1)
		(layers "F.Cu" "B.Cu")
		(net 3)
	)
	(via
		(at 140.372962 127.4315)
		(size 0.45)
		(drill 0.1)
		(layers "F.Cu" "B.Cu")
		(net 3)
	)
	(via
		(at 130.55 129.25)
		(size 0.5)
		(drill 0.15)
		(layers "F.Cu" "B.Cu")
		(free yes)
		(net 3)
	)
	(via
		(at 54.867962 156.4265)
		(size 0.45)
		(drill 0.1)
		(layers "F.Cu" "B.Cu")
		(free yes)
		(net 3)
	)
	(via
		(at 37.847962 171.7765)
		(size 0.45)
		(drill 0.1)
		(layers "F.Cu" "B.Cu")
		(net 3)
	)
	(via
		(at 111.554957 146.229)
		(size 0.45)
		(drill 0.1)
		(layers "F.Cu" "B.Cu")
		(free yes)
		(net 3)
	)
	(via
		(at 90.467962 172.1915)
		(size 0.45)
		(drill 0.1)
		(layers "F.Cu" "B.Cu")
		(net 3)
	)
	(via
		(at 48.847962 158.4765)
		(size 0.45)
		(drill 0.1)
		(layers "F.Cu" "B.Cu")
		(net 3)
	)
	(via
		(at 119.09 155.72)
		(size 0.45)
		(drill 0.1)
		(layers "F.Cu" "B.Cu")
		(net 3)
	)
	(via
		(at 90.397962 165.9365)
		(size 0.45)
		(drill 0.1)
		(layers "F.Cu" "B.Cu")
		(net 3)
	)
	(via
		(at 111.717962 152.1165)
		(size 0.45)
		(drill 0.1)
		(layers "F.Cu" "B.Cu")
		(net 3)
	)
	(via
		(at 88.542962 172.1665)
		(size 0.45)
		(drill 0.1)
		(layers "F.Cu" "B.Cu")
		(net 3)
	)
	(via
		(at 129.417962 115.2665)
		(size 0.45)
		(drill 0.1)
		(layers "F.Cu" "B.Cu")
		(net 3)
	)
	(via
		(at 127.067962 123.0165)
		(size 0.45)
		(drill 0.1)
		(layers "F.Cu" "B.Cu")
		(net 3)
	)
	(via
		(at 73.792962 175.566502)
		(size 0.45)
		(drill 0.1)
		(layers "F.Cu" "B.Cu")
		(net 3)
	)
	(via
		(at 111.367962 136.5915)
		(size 0.45)
		(drill 0.1)
		(layers "F.Cu" "B.Cu")
		(net 3)
	)
	(via
		(at 44.207962 128.4165)
		(size 0.45)
		(drill 0.1)
		(layers "F.Cu" "B.Cu")
		(free yes)
		(net 3)
	)
	(via
		(at 88.692962 147.2665)
		(size 0.45)
		(drill 0.1)
		(layers "F.Cu" "B.Cu")
		(net 3)
	)
	(via
		(at 89.647962 112.5465)
		(size 0.45)
		(drill 0.1)
		(layers "F.Cu" "B.Cu")
		(net 3)
	)
	(via
		(at 116.705736 153.307394)
		(size 0.45)
		(drill 0.1)
		(layers "F.Cu" "B.Cu")
		(net 3)
	)
	(via
		(at 107.15 155.05)
		(size 0.45)
		(drill 0.1)
		(layers "F.Cu" "B.Cu")
		(free yes)
		(net 3)
	)
	(via
		(at 40.177962 156.1365)
		(size 0.45)
		(drill 0.1)
		(layers "F.Cu" "B.Cu")
		(free yes)
		(net 3)
	)
	(via
		(at 65.62 169.78)
		(size 0.45)
		(drill 0.1)
		(layers "F.Cu" "B.Cu")
		(net 3)
	)
	(via
		(at 88.734962 130.7365)
		(size 0.45)
		(drill 0.1)
		(layers "F.Cu" "B.Cu")
		(net 3)
	)
	(via
		(at 118.107962 114.5465)
		(size 0.45)
		(drill 0.1)
		(layers "F.Cu" "B.Cu")
		(free yes)
		(net 3)
	)
	(via
		(at 71.592962 170.1165)
		(size 0.45)
		(drill 0.1)
		(layers "F.Cu" "B.Cu")
		(net 3)
	)
	(via
		(at 95.017962 165.8915)
		(size 0.45)
		(drill 0.1)
		(layers "F.Cu" "B.Cu")
		(free yes)
		(net 3)
	)
	(via
		(at 91.392962 146.0665)
		(size 0.45)
		(drill 0.1)
		(layers "F.Cu" "B.Cu")
		(net 3)
	)
	(via
		(at 62.327962 130.3265)
		(size 0.45)
		(drill 0.1)
		(layers "F.Cu" "B.Cu")
		(free yes)
		(net 3)
	)
	(via
		(at 89.657962 117.0665)
		(size 0.45)
		(drill 0.1)
		(layers "F.Cu" "B.Cu")
		(net 3)
	)
	(via
		(at 140.367962 160.8915)
		(size 0.45)
		(drill 0.1)
		(layers "F.Cu" "B.Cu")
		(net 3)
	)
	(via
		(at 109.847962 120.9065)
		(size 0.45)
		(drill 0.1)
		(layers "F.Cu" "B.Cu")
		(free yes)
		(net 3)
	)
	(via
		(at 84.142962 146.6165)
		(size 0.45)
		(drill 0.1)
		(layers "F.Cu" "B.Cu")
		(net 3)
	)
	(via
		(at 66.517962 141.8865)
		(size 0.45)
		(drill 0.1)
		(layers "F.Cu" "B.Cu")
		(net 3)
	)
	(via
		(at 53.757962 166.4465)
		(size 0.45)
		(drill 0.1)
		(layers "F.Cu" "B.Cu")
		(free yes)
		(net 3)
	)
	(via
		(at 96.817962 119.9665)
		(size 0.45)
		(drill 0.1)
		(layers "F.Cu" "B.Cu")
		(net 3)
	)
	(via
		(at 95.217962 151.3915)
		(size 0.45)
		(drill 0.1)
		(layers "F.Cu" "B.Cu")
		(net 3)
	)
	(via
		(at 71.837962 112.7265)
		(size 0.45)
		(drill 0.1)
		(layers "F.Cu" "B.Cu")
		(net 3)
	)
	(via
		(at 119.142962 135.4415)
		(size 0.45)
		(drill 0.1)
		(layers "F.Cu" "B.Cu")
		(free yes)
		(net 3)
	)
	(via
		(at 70.692962 162.4165)
		(size 0.45)
		(drill 0.1)
		(layers "F.Cu" "B.Cu")
		(free yes)
		(net 3)
	)
	(via
		(at 88.817962 137.4665)
		(size 0.45)
		(drill 0.1)
		(layers "F.Cu" "B.Cu")
		(net 3)
	)
	(via
		(at 139.444878 125.341467)
		(size 0.45)
		(drill 0.1)
		(layers "F.Cu" "B.Cu")
		(free yes)
		(net 3)
	)
	(via
		(at 105.357962 124.1365)
		(size 0.45)
		(drill 0.1)
		(layers "F.Cu" "B.Cu")
		(free yes)
		(net 3)
	)
	(via
		(at 135.192962 142.3665)
		(size 0.45)
		(drill 0.1)
		(layers "F.Cu" "B.Cu")
		(free yes)
		(net 3)
	)
	(via
		(at 76.167962 177.8415)
		(size 0.45)
		(drill 0.1)
		(layers "F.Cu" "B.Cu")
		(net 3)
	)
	(via
		(at 52.727962 157.6565)
		(size 0.45)
		(drill 0.1)
		(layers "F.Cu" "B.Cu")
		(free yes)
		(net 3)
	)
	(via
		(at 95.867962 146.7665)
		(size 0.45)
		(drill 0.1)
		(layers "F.Cu" "B.Cu")
		(net 3)
	)
	(via
		(at 90.467962 175.1915)
		(size 0.45)
		(drill 0.1)
		(layers "F.Cu" "B.Cu")
		(net 3)
	)
	(via
		(at 113.280962 164.534)
		(size 0.45)
		(drill 0.1)
		(layers "F.Cu" "B.Cu")
		(free yes)
		(net 3)
	)
	(via
		(at 107.642962 128.3165)
		(size 0.45)
		(drill 0.1)
		(layers "F.Cu" "B.Cu")
		(free yes)
		(net 3)
	)
	(via
		(at 89.257962 163.1065)
		(size 0.45)
		(drill 0.1)
		(layers "F.Cu" "B.Cu")
		(net 3)
	)
	(via
		(at 88.539782 176.660199)
		(size 0.45)
		(drill 0.1)
		(layers "F.Cu" "B.Cu")
		(net 3)
	)
	(via
		(at 124.557962 112.9065)
		(size 0.45)
		(drill 0.1)
		(layers "F.Cu" "B.Cu")
		(net 3)
	)
	(via
		(at 140.067962 140.4165)
		(size 0.45)
		(drill 0.1)
		(layers "F.Cu" "B.Cu")
		(free yes)
		(net 3)
	)
	(via
		(at 69.892962 173.5165)
		(size 0.45)
		(drill 0.1)
		(layers "F.Cu" "B.Cu")
		(net 3)
	)
	(via
		(at 69.717962 164.7165)
		(size 0.45)
		(drill 0.1)
		(layers "F.Cu" "B.Cu")
		(free yes)
		(net 3)
	)
	(via
		(at 51.627962 158.8065)
		(size 0.45)
		(drill 0.1)
		(layers "F.Cu" "B.Cu")
		(free yes)
		(net 3)
	)
	(via
		(at 90.517962 135.7665)
		(size 0.45)
		(drill 0.1)
		(layers "F.Cu" "B.Cu")
		(net 3)
	)
	(via
		(at 58.628693 165.447486)
		(size 0.45)
		(drill 0.1)
		(layers "F.Cu" "B.Cu")
		(free yes)
		(net 3)
	)
	(via
		(at 106.092962 128.3165)
		(size 0.45)
		(drill 0.1)
		(layers "F.Cu" "B.Cu")
		(free yes)
		(net 3)
	)
	(via
		(at 123.19 148.84)
		(size 0.45)
		(drill 0.1)
		(layers "F.Cu" "B.Cu")
		(net 3)
	)
	(via
		(at 40.747962 157.6365)
		(size 0.45)
		(drill 0.1)
		(layers "F.Cu" "B.Cu")
		(free yes)
		(net 3)
	)
	(via
		(at 136.030462 161.454)
		(size 0.45)
		(drill 0.1)
		(layers "F.Cu" "B.Cu")
		(net 3)
	)
	(via
		(at 137.862962 161.1665)
		(size 0.45)
		(drill 0.1)
		(layers "F.Cu" "B.Cu")
		(net 3)
	)
	(via
		(at 67.967962 146.0665)
		(size 0.45)
		(drill 0.1)
		(layers "F.Cu" "B.Cu")
		(net 3)
	)
	(via
		(at 83.088073 152.171389)
		(size 0.45)
		(drill 0.1)
		(layers "F.Cu" "B.Cu")
		(net 3)
	)
	(via
		(at 88.542962 170.6915)
		(size 0.45)
		(drill 0.1)
		(layers "F.Cu" "B.Cu")
		(net 3)
	)
	(via
		(at 65.629731 166.704731)
		(size 0.45)
		(drill 0.1)
		(layers "F.Cu" "B.Cu")
		(net 3)
	)
	(via
		(at 83.642962 119.9665)
		(size 0.45)
		(drill 0.1)
		(layers "F.Cu" "B.Cu")
		(net 3)
	)
	(via
		(at 92.467962 147.4165)
		(size 0.45)
		(drill 0.1)
		(layers "F.Cu" "B.Cu")
		(net 3)
	)
	(via
		(at 119.09 154.52)
		(size 0.45)
		(drill 0.1)
		(layers "F.Cu" "B.Cu")
		(free yes)
		(net 3)
	)
	(via
		(at 134.336032 178.796344)
		(size 0.45)
		(drill 0.1)
		(layers "F.Cu" "B.Cu")
		(net 3)
	)
	(via
		(at 73.737962 129.0065)
		(size 0.45)
		(drill 0.1)
		(layers "F.Cu" "B.Cu")
		(net 3)
	)
	(via
		(at 119.117962 128.4865)
		(size 0.45)
		(drill 0.1)
		(layers "F.Cu" "B.Cu")
		(free yes)
		(net 3)
	)
	(via
		(at 97.092962 122.8915)
		(size 0.45)
		(drill 0.1)
		(layers "F.Cu" "B.Cu")
		(net 3)
	)
	(via
		(at 113.167962 147.3165)
		(size 0.45)
		(drill 0.1)
		(layers "F.Cu" "B.Cu")
		(net 3)
	)
	(via
		(at 119.067962 114.4965)
		(size 0.45)
		(drill 0.1)
		(layers "F.Cu" "B.Cu")
		(free yes)
		(net 3)
	)
	(via
		(at 75.03 174.88)
		(size 0.45)
		(drill 0.1)
		(layers "F.Cu" "B.Cu")
		(net 3)
	)
	(via
		(at 73.292962 170.1165)
		(size 0.45)
		(drill 0.1)
		(layers "F.Cu" "B.Cu")
		(net 3)
	)
	(via
		(at 87.867962 144.6665)
		(size 0.45)
		(drill 0.1)
		(layers "F.Cu" "B.Cu")
		(net 3)
	)
	(via
		(at 65.5 167.7765)
		(size 0.45)
		(drill 0.1)
		(layers "F.Cu" "B.Cu")
		(net 3)
	)
	(via
		(at 137.567962 149.4415)
		(size 0.45)
		(drill 0.1)
		(layers "F.Cu" "B.Cu")
		(free yes)
		(net 3)
	)
	(via
		(at 96.617962 154.1915)
		(size 0.45)
		(drill 0.1)
		(layers "F.Cu" "B.Cu")
		(net 3)
	)
	(via
		(at 116.328062 150.9165)
		(size 0.45)
		(drill 0.1)
		(layers "F.Cu" "B.Cu")
		(net 3)
	)
	(via
		(at 109.3 155.67)
		(size 0.45)
		(drill 0.1)
		(layers "F.Cu" "B.Cu")
		(free yes)
		(net 3)
	)
	(via
		(at 64.342962 177.0415)
		(size 0.45)
		(drill 0.1)
		(layers "F.Cu" "B.Cu")
		(net 3)
	)
	(via
		(at 131.564716 132.689716)
		(size 0.5)
		(drill 0.15)
		(layers "F.Cu" "B.Cu")
		(free yes)
		(net 3)
	)
	(via
		(at 90.467962 176.6915)
		(size 0.45)
		(drill 0.1)
		(layers "F.Cu" "B.Cu")
		(net 3)
	)
	(via
		(at 67.657436 129.907)
		(size 0.45)
		(drill 0.1)
		(layers "F.Cu" "B.Cu")
		(free yes)
		(net 3)
	)
	(via
		(at 129.242962 127.5165)
		(size 0.5)
		(drill 0.15)
		(layers "F.Cu" "B.Cu")
		(net 3)
	)
	(via
		(at 81.547962 144.4915)
		(size 0.45)
		(drill 0.1)
		(layers "F.Cu" "B.Cu")
		(free yes)
		(net 3)
	)
	(via
		(at 102.517962 134.1415)
		(size 0.45)
		(drill 0.1)
		(layers "F.Cu" "B.Cu")
		(net 3)
	)
	(via
		(at 90.517962 139.1665)
		(size 0.45)
		(drill 0.1)
		(layers "F.Cu" "B.Cu")
		(net 3)
	)
	(via
		(at 110.067962 117.713782)
		(size 0.45)
		(drill 0.1)
		(layers "F.Cu" "B.Cu")
		(net 3)
	)
	(via
		(at 53.317962 112.4665)
		(size 0.45)
		(drill 0.1)
		(layers "F.Cu" "B.Cu")
		(net 3)
	)
	(via
		(at 96.217962 119.9665)
		(size 0.45)
		(drill 0.1)
		(layers "F.Cu" "B.Cu")
		(net 3)
	)
	(via
		(at 106.107962 126.3565)
		(size 0.45)
		(drill 0.1)
		(layers "F.Cu" "B.Cu")
		(free yes)
		(net 3)
	)
	(via
		(at 81.917231 136.517231)
		(size 0.45)
		(drill 0.1)
		(layers "F.Cu" "B.Cu")
		(net 3)
	)
	(via
		(at 88.502255 173.681092)
		(size 0.45)
		(drill 0.1)
		(layers "F.Cu" "B.Cu")
		(net 3)
	)
	(via
		(at 143.242962 144.3915)
		(size 0.45)
		(drill 0.1)
		(layers "F.Cu" "B.Cu")
		(net 3)
	)
	(via
		(at 129.417962 133.5165)
		(size 0.45)
		(drill 0.1)
		(layers "F.Cu" "B.Cu")
		(net 3)
	)
	(via
		(at 87.211617 131.324807)
		(size 0.45)
		(drill 0.1)
		(layers "F.Cu" "B.Cu")
		(net 3)
	)
	(via
		(at 129.242962 126.0165)
		(size 0.5)
		(drill 0.15)
		(layers "F.Cu" "B.Cu")
		(net 3)
	)
	(via
		(at 93.817962 154.1915)
		(size 0.45)
		(drill 0.1)
		(layers "F.Cu" "B.Cu")
		(net 3)
	)
	(via
		(at 84.140724 149.241164)
		(size 0.45)
		(drill 0.1)
		(layers "F.Cu" "B.Cu")
		(net 3)
	)
	(via
		(at 121.027962 112.9165)
		(size 0.45)
		(drill 0.1)
		(layers "F.Cu" "B.Cu")
		(net 3)
	)
	(via
		(at 64.825 167.0915)
		(size 0.45)
		(drill 0.1)
		(layers "F.Cu" "B.Cu")
		(net 3)
	)
	(via
		(at 124.025 122.15)
		(size 0.5)
		(drill 0.15)
		(layers "F.Cu" "B.Cu")
		(free yes)
		(net 3)
	)
	(via
		(at 37.977962 120.4565)
		(size 0.45)
		(drill 0.1)
		(layers "F.Cu" "B.Cu")
		(net 3)
	)
	(via
		(at 113.167966 148.517)
		(size 0.45)
		(drill 0.1)
		(layers "F.Cu" "B.Cu")
		(net 3)
	)
	(via
		(at 142.917962 133.0565)
		(size 0.45)
		(drill 0.1)
		(layers "F.Cu" "B.Cu")
		(net 3)
	)
	(via
		(at 75.842962 140.1415)
		(size 0.45)
		(drill 0.1)
		(layers "F.Cu" "B.Cu")
		(net 3)
	)
	(via
		(at 109.908759 148.154481)
		(size 0.45)
		(drill 0.1)
		(layers "F.Cu" "B.Cu")
		(net 3)
	)
	(via
		(at 109.858962 124.154958)
		(size 0.45)
		(drill 0.1)
		(layers "F.Cu" "B.Cu")
		(free yes)
		(net 3)
	)
	(via
		(at 128.017962 118.6665)
		(size 0.45)
		(drill 0.1)
		(layers "F.Cu" "B.Cu")
		(net 3)
	)
	(via
		(at 116.6 155.719)
		(size 0.45)
		(drill 0.1)
		(layers "F.Cu" "B.Cu")
		(net 3)
	)
	(via
		(at 136.392962 128.9665)
		(size 0.45)
		(drill 0.1)
		(layers "F.Cu" "B.Cu")
		(net 3)
	)
	(via
		(at 87.117962 137.4665)
		(size 0.45)
		(drill 0.1)
		(layers "F.Cu" "B.Cu")
		(net 3)
	)
	(via
		(at 133.342962 126.3915)
		(size 0.45)
		(drill 0.1)
		(layers "F.Cu" "B.Cu")
		(free yes)
		(net 3)
	)
	(via
		(at 140.355462 161.479)
		(size 0.45)
		(drill 0.1)
		(layers "F.Cu" "B.Cu")
		(net 3)
	)
	(via
		(at 116.317962 140.7165)
		(size 0.45)
		(drill 0.1)
		(layers "F.Cu" "B.Cu")
		(net 3)
	)
	(via
		(at 74.387962 155.0465)
		(size 0.45)
		(drill 0.1)
		(layers "F.Cu" "B.Cu")
		(net 3)
	)
	(via
		(at 105.592962 135.4915)
		(size 0.45)
		(drill 0.1)
		(layers "F.Cu" "B.Cu")
		(net 3)
	)
	(via
		(at 87.117962 135.7665)
		(size 0.45)
		(drill 0.1)
		(layers "F.Cu" "B.Cu")
		(net 3)
	)
	(via
		(at 75.407962 121.1565)
		(size 0.45)
		(drill 0.1)
		(layers "F.Cu" "B.Cu")
		(net 3)
	)
	(via
		(at 73.292962 173.5165)
		(size 0.45)
		(drill 0.1)
		(layers "F.Cu" "B.Cu")
		(net 3)
	)
	(via
		(at 110.667962 135.9415)
		(size 0.45)
		(drill 0.1)
		(layers "F.Cu" "B.Cu")
		(free yes)
		(net 3)
	)
	(via
		(at 134.117962 118.0415)
		(size 0.45)
		(drill 0.1)
		(layers "F.Cu" "B.Cu")
		(net 3)
	)
	(via
		(at 62.357962 167.0765)
		(size 0.45)
		(drill 0.1)
		(layers "F.Cu" "B.Cu")
		(net 3)
	)
	(via
		(at 46.267962 116.0665)
		(size 0.45)
		(drill 0.1)
		(layers "F.Cu" "B.Cu")
		(net 3)
	)
	(via
		(at 116.255962 164.5265)
		(size 0.45)
		(drill 0.1)
		(layers "F.Cu" "B.Cu")
		(net 3)
	)
	(via
		(at 70.737962 167.0165)
		(size 0.45)
		(drill 0.1)
		(layers "F.Cu" "B.Cu")
		(net 3)
	)
	(via
		(at 74.727962 122.7765)
		(size 0.45)
		(drill 0.1)
		(layers "F.Cu" "B.Cu")
		(free yes)
		(net 3)
	)
	(via
		(at 77.137962 112.6365)
		(size 0.45)
		(drill 0.1)
		(layers "F.Cu" "B.Cu")
		(net 3)
	)
	(via
		(at 49.687962 119.3665)
		(size 0.45)
		(drill 0.1)
		(layers "F.Cu" "B.Cu")
		(net 3)
	)
	(via
		(at 125.436274 164.080676)
		(size 0.45)
		(drill 0.1)
		(layers "F.Cu" "B.Cu")
		(free yes)
		(net 3)
	)
	(via
		(at 66.692962 146.0165)
		(size 0.45)
		(drill 0.1)
		(layers "F.Cu" "B.Cu")
		(net 3)
	)
	(via
		(at 121.5 155.7165)
		(size 0.45)
		(drill 0.1)
		(layers "F.Cu" "B.Cu")
		(net 3)
	)
	(via
		(at 112.842962 120.8915)
		(size 0.45)
		(drill 0.1)
		(layers "F.Cu" "B.Cu")
		(net 3)
	)
	(via
		(at 111.417962 138.7665)
		(size 0.45)
		(drill 0.1)
		(layers "F.Cu" "B.Cu")
		(free yes)
		(net 3)
	)
	(via
		(at 90.407962 154.9365)
		(size 0.45)
		(drill 0.1)
		(layers "F.Cu" "B.Cu")
		(net 3)
	)
	(via
		(at 75.717962 178.8165)
		(size 0.45)
		(drill 0.1)
		(layers "F.Cu" "B.Cu")
		(net 3)
	)
	(via
		(at 46.267962 114.2665)
		(size 0.45)
		(drill 0.1)
		(layers "F.Cu" "B.Cu")
		(net 3)
	)
	(via
		(at 118.187962 128.4965)
		(size 0.45)
		(drill 0.1)
		(layers "F.Cu" "B.Cu")
		(free yes)
		(net 3)
	)
	(via
		(at 139.307962 154.1665)
		(size 0.45)
		(drill 0.1)
		(layers "F.Cu" "B.Cu")
		(net 3)
	)
	(via
		(at 124.317962 115.5165)
		(size 0.45)
		(drill 0.1)
		(layers "F.Cu" "B.Cu")
		(net 3)
	)
	(via
		(at 133.897962 112.8465)
		(size 0.45)
		(drill 0.1)
		(layers "F.Cu" "B.Cu")
		(net 3)
	)
	(via
		(at 74.967962 138.2215)
		(size 0.45)
		(drill 0.1)
		(layers "F.Cu" "B.Cu")
		(net 3)
	)
	(via
		(at 76.507962 116.8265)
		(size 0.45)
		(drill 0.1)
		(layers "F.Cu" "B.Cu")
		(net 3)
	)
	(via
		(at 135.197962 172.3465)
		(size 0.45)
		(drill 0.1)
		(layers "F.Cu" "B.Cu")
		(net 3)
	)
	(via
		(at 105.917962 140.6665)
		(size 0.45)
		(drill 0.1)
		(layers "F.Cu" "B.Cu")
		(free yes)
		(net 3)
	)
	(via
		(at 80.617962 151.2415)
		(size 0.45)
		(drill 0.1)
		(layers "F.Cu" "B.Cu")
		(net 3)
	)
	(via
		(at 98.467962 141.6165)
		(size 0.45)
		(drill 0.1)
		(layers "F.Cu" "B.Cu")
		(net 3)
	)
	(via
		(at 82.317962 147.4065)
		(size 0.45)
		(drill 0.1)
		(layers "F.Cu" "B.Cu")
		(free yes)
		(net 3)
	)
	(via
		(at 95.867962 135.2165)
		(size 0.45)
		(drill 0.1)
		(layers "F.Cu" "B.Cu")
		(net 3)
	)
	(via
		(at 37.907962 178.8365)
		(size 0.45)
		(drill 0.1)
		(layers "F.Cu" "B.Cu")
		(net 3)
	)
	(via
		(at 116.187962 112.5765)
		(size 0.45)
		(drill 0.1)
		(layers "F.Cu" "B.Cu")
		(net 3)
	)
	(via
		(at 116.317964 149.717)
		(size 0.45)
		(drill 0.1)
		(layers "F.Cu" "B.Cu")
		(net 3)
	)
	(via
		(at 67.692962 133.9165)
		(size 0.45)
		(drill 0.1)
		(layers "F.Cu" "B.Cu")
		(net 3)
	)
	(via
		(at 77.667962 156.491492)
		(size 0.45)
		(drill 0.1)
		(layers "F.Cu" "B.Cu")
		(net 3)
	)
	(via
		(at 122.948732 119.859526)
		(size 0.45)
		(drill 0.1)
		(layers "F.Cu" "B.Cu")
		(free yes)
		(net 3)
	)
	(via
		(at 97.055347 121.952914)
		(size 0.45)
		(drill 0.1)
		(layers "F.Cu" "B.Cu")
		(net 3)
	)
	(via
		(at 126.017962 123.0165)
		(size 0.5)
		(drill 0.15)
		(layers "F.Cu" "B.Cu")
		(free yes)
		(net 3)
	)
	(via
		(at 53.317962 114.2665)
		(size 0.45)
		(drill 0.1)
		(layers "F.Cu" "B.Cu")
		(net 3)
	)
	(via
		(at 116.317962 159.3165)
		(size 0.45)
		(drill 0.1)
		(layers "F.Cu" "B.Cu")
		(net 3)
	)
	(via
		(at 64.492962 160.1665)
		(size 0.45)
		(drill 0.1)
		(layers "F.Cu" "B.Cu")
		(free yes)
		(net 3)
	)
	(via
		(at 69.892962 171.8165)
		(size 0.45)
		(drill 0.1)
		(layers "F.Cu" "B.Cu")
		(net 3)
	)
	(via
		(at 135.692962 160.7415)
		(size 0.45)
		(drill 0.1)
		(layers "F.Cu" "B.Cu")
		(net 3)
	)
	(via
		(at 143.207962 137.6665)
		(size 0.45)
		(drill 0.1)
		(layers "F.Cu" "B.Cu")
		(net 3)
	)
	(via
		(at 74.127962 123.8465)
		(size 0.45)
		(drill 0.1)
		(layers "F.Cu" "B.Cu")
		(net 3)
	)
	(via
		(at 96.327962 112.5465)
		(size 0.45)
		(drill 0.1)
		(layers "F.Cu" "B.Cu")
		(net 3)
	)
	(via
		(at 59.677962 172.3565)
		(size 0.45)
		(drill 0.1)
		(layers "F.Cu" "B.Cu")
		(net 3)
	)
	(via
		(at 96.817962 141.1165)
		(size 0.45)
		(drill 0.1)
		(layers "F.Cu" "B.Cu")
		(net 3)
	)
	(via
		(at 60.542962 177.2505)
		(size 0.45)
		(drill 0.1)
		(layers "F.Cu" "B.Cu")
		(net 3)
	)
	(via
		(at 119.07 158.15)
		(size 0.45)
		(drill 0.1)
		(layers "F.Cu" "B.Cu")
		(net 3)
	)
	(via
		(at 54.837962 173.4465)
		(size 0.45)
		(drill 0.1)
		(layers "F.Cu" "B.Cu")
		(free yes)
		(net 3)
	)
	(via
		(at 138.517962 127.4665)
		(size 0.45)
		(drill 0.1)
		(layers "F.Cu" "B.Cu")
		(net 3)
	)
	(via
		(at 89.508529 167.513998)
		(size 0.45)
		(drill 0.1)
		(layers "F.Cu" "B.Cu")
		(free yes)
		(net 3)
	)
	(via
		(at 118.792962 131.1415)
		(size 0.45)
		(drill 0.1)
		(layers "F.Cu" "B.Cu")
		(free yes)
		(net 3)
	)
	(via
		(at 118.257962 159.324499)
		(size 0.45)
		(drill 0.1)
		(layers "F.Cu" "B.Cu")
		(net 3)
	)
	(via
		(at 62.407962 157.4565)
		(size 0.45)
		(drill 0.1)
		(layers "F.Cu" "B.Cu")
		(net 3)
	)
	(via
		(at 92.217962 137.4665)
		(size 0.45)
		(drill 0.1)
		(layers "F.Cu" "B.Cu")
		(net 3)
	)
	(via
		(at 102.997962 112.6165)
		(size 0.45)
		(drill 0.1)
		(layers "F.Cu" "B.Cu")
		(net 3)
	)
	(via
		(at 126.542962 134.0165)
		(size 0.45)
		(drill 0.1)
		(layers "F.Cu" "B.Cu")
		(net 3)
	)
	(via
		(at 98.317962 178.2165)
		(size 0.45)
		(drill 0.1)
		(layers "F.Cu" "B.Cu")
		(net 3)
	)
	(via
		(at 111.717962 150.9165)
		(size 0.45)
		(drill 0.1)
		(layers "F.Cu" "B.Cu")
		(net 3)
	)
	(via
		(at 73.827962 115.3865)
		(size 0.45)
		(drill 0.1)
		(layers "F.Cu" "B.Cu")
		(net 3)
	)
	(via
		(at 127.067962 120.0165)
		(size 0.45)
		(drill 0.1)
		(layers "F.Cu" "B.Cu")
		(net 3)
	)
	(via
		(at 40.607962 129.3465)
		(size 0.45)
		(drill 0.1)
		(layers "F.Cu" "B.Cu")
		(free yes)
		(net 3)
	)
	(via
		(at 98.697962 167.5665)
		(size 0.45)
		(drill 0.1)
		(layers "F.Cu" "B.Cu")
		(net 3)
	)
	(segment
		(start 119.1 173.23)
		(end 119.1 173.8)
		(width 0.254)
		(layer "B.Cu")
		(net 3)
	)
	(segment
		(start 135.313872 145.99559)
		(end 135.766962 145.5425)
		(width 0.2)
		(layer "B.Cu")
		(net 3)
	)
	(segment
		(start 74.858962 136.9915)
		(end 74.858962 136.0175)
		(width 0.15)
		(layer "B.Cu")
		(net 3)
	)
	(segment
		(start 88.50822 175.1915)
		(end 89.118462 175.1915)
		(width 0.15)
		(layer "B.Cu")
		(net 3)
	)
	(segment
		(start 88.392962 127.9165)
		(end 88.267962 127.9165)
		(width 0.35)
		(layer "B.Cu")
		(net 3)
	)
	(segment
		(start 89.893462 168.1785)
		(end 90.429962 168.1785)
		(width 0.15)
		(layer "B.Cu")
		(net 3)
	)
	(segment
		(start 118.87 173)
		(end 119.1 173.23)
		(width 0.254)
		(layer "B.Cu")
		(net 3)
	)
	(segment
		(start 127.070462 126.019)
		(end 127.067962 126.0165)
		(width 0.15)
		(layer "B.Cu")
		(net 3)
	)
	(segment
		(start 90.470962 169.1885)
		(end 90.467962 169.1915)
		(width 0.15)
		(layer "B.Cu")
		(net 3)
	)
	(segment
		(start 136.866963 137.9665)
		(end 136.867963 137.9655)
		(width 0.127)
		(layer "B.Cu")
		(net 3)
	)
	(segment
		(start 88.567962 128.0195)
		(end 88.428962 127.8805)
		(width 0.35)
		(layer "B.Cu")
		(net 3)
	)
	(segment
		(start 71.869962 150.1185)
		(end 70.942962 149.1915)
		(width 0.15)
		(layer "B.Cu")
		(net 3)
	)
	(segment
		(start 112.893962 118.9675)
		(end 112.893962 119.4665)
		(width 0.15)
		(layer "B.Cu")
		(net 3)
	)
	(segment
		(start 76.45 153.15)
		(end 76.45 154.442286)
		(width 0.15)
		(layer "B.Cu")
		(net 3)
	)
	(segment
		(start 86.942962 127.9165)
		(end 85.767962 127.9165)
		(width 0.35)
		(layer "B.Cu")
		(net 3)
	)
	(segment
		(start 128.167962 132.019)
		(end 129.415462 132.019)
		(width 0.15)
		(layer "B.Cu")
		(net 3)
	)
	(segment
		(start 127.069462 123.018)
		(end 127.067962 123.0165)
		(width 0.15)
		(layer "B.Cu")
		(net 3)
	)
	(segment
		(start 137.887962 161.1915)
		(end 137.862962 161.1665)
		(width 0.2)
		(layer "B.Cu")
		(net 3)
	)
	(segment
		(start 54.397962 152.8215)
		(end 54.832962 153.2565)
		(width 0.2)
		(layer "B.Cu")
		(net 3)
	)
	(segment
		(start 128.167962 127.518)
		(end 129.241462 127.518)
		(width 0.15)
		(layer "B.Cu")
		(net 3)
	)
	(segment
		(start 126.080462 165.0915)
		(end 125.342962 165.0915)
		(width 0.15)
		(layer "B.Cu")
		(net 3)
	)
	(segment
		(start 129.414462 133.52)
		(end 129.417962 133.5165)
		(width 0.15)
		(layer "B.Cu")
		(net 3)
	)
	(segment
		(start 87.617962 127.8915)
		(end 87.592962 127.9165)
		(width 0.35)
		(layer "B.Cu")
		(net 3)
	)
	(segment
		(start 71.458962 129.9365)
		(end 71.458962 130.4375)
		(width 0.254)
		(layer "B.Cu")
		(net 3)
	)
	(segment
		(start 91.312962 169.1885)
		(end 90.470962 169.1885)
		(width 0.15)
		(layer "B.Cu")
		(net 3)
	)
	(segment
		(start 112.542962 118.6165)
		(end 112.893962 118.9675)
		(width 0.15)
		(layer "B.Cu")
		(net 3)
	)
	(segment
		(start 89.118462 172.1785)
		(end 89.893462 172.1785)
		(width 0.15)
		(layer "B.Cu")
		(net 3)
	)
	(segment
		(start 90.467962 168.2165)
		(end 90.442962 168.1915)
		(width 0.15)
		(layer "B.Cu")
		(net 3)
	)
	(segment
		(start 76.45 154.442286)
		(end 77.393787 155.386073)
		(width 0.15)
		(layer "B.Cu")
		(net 3)
	)
	(segment
		(start 112.567962 118.3665)
		(end 112.542962 118.3415)
		(width 0.15)
		(layer "B.Cu")
		(net 3)
	)
	(segment
		(start 110.092962 115.7165)
		(end 110.092962 113.3215)
		(width 0.15)
		(layer "B.Cu")
		(net 3)
	)
	(segment
		(start 89.118462 169.1785)
		(end 89.893462 169.1785)
		(width 0.15)
		(layer "B.Cu")
		(net 3)
	)
	(segment
		(start 91.454962 165.9365)
		(end 91.499962 165.9815)
		(width 0.254)
		(layer "B.Cu")
		(net 3)
	)
	(segment
		(start 136.317962 131.9665)
		(end 136.292962 131.9915)
		(width 0.15)
		(layer "B.Cu")
		(net 3)
	)
	(segment
		(start 88.267962 127.9165)
		(end 88.242962 127.8915)
		(width 0.35)
		(layer "B.Cu")
		(net 3)
	)
	(segment
		(start 140.067962 161.1915)
		(end 140.355462 161.479)
		(width 0.2)
		(layer "B.Cu")
		(net 3)
	)
	(segment
		(start 137.467962 127.4665)
		(end 138.517962 127.4665)
		(width 0.15)
		(layer "B.Cu")
		(net 3)
	)
	(segment
		(start 95.721962 176.6875)
		(end 95.717962 176.6915)
		(width 0.2)
		(layer "B.Cu")
		(net 3)
	)
	(segment
		(start 53.917962 158.0755)
		(end 53.917962 157.2655)
		(width 0.254)
		(layer "B.Cu")
		(net 3)
	)
	(segment
		(start 110.092962 113.3215)
		(end 109.437962 112.6665)
		(width 0.15)
		(layer "B.Cu")
		(net 3)
	)
	(segment
		(start 72.092962 163.8165)
		(end 70.949962 164.9595)
		(width 0.254)
		(layer "B.Cu")
		(net 3)
	)
	(segment
		(start 90.467962 175.1915)
		(end 89.893462 175.1915)
		(width 0.15)
		(layer "B.Cu")
		(net 3)
	)
	(segment
		(start 71.458962 130.4375)
		(end 71.897962 130.8765)
		(width 0.254)
		(layer "B.Cu")
		(net 3)
	)
	(segment
		(start 129.415462 130.519)
		(end 129.417962 130.5165)
		(width 0.15)
		(layer "B.Cu")
		(net 3)
	)
	(segment
		(start 113.333962 118.3665)
		(end 112.567962 118.3665)
		(width 0.15)
		(layer "B.Cu")
		(net 3)
	)
	(segment
		(start 74.858962 138.1125)
		(end 74.967962 138.2215)
		(width 0.15)
		(layer "B.Cu")
		(net 3)
	)
	(segment
		(start 89.118462 168.6785)
		(end 89.893462 168.6785)
		(width 0.15)
		(layer "B.Cu")
		(net 3)
	)
	(segment
		(start 125.436274 164.080676)
		(end 125.447098 164.0915)
		(width 0.15)
		(layer "B.Cu")
		(net 3)
	)
	(segment
		(start 136.542962 137.9665)
		(end 136.866963 137.9665)
		(width 0.127)
		(layer "B.Cu")
		(net 3)
	)
	(segment
		(start 99.442962 175.2755)
		(end 100.058962 175.2755)
		(width 0.2)
		(layer "B.Cu")
		(net 3)
	)
	(segment
		(start 88.428962 127.8805)
		(end 88.264962 127.7165)
		(width 0.35)
		(layer "B.Cu")
		(net 3)
	)
	(segment
		(start 100.693462 172.6785)
		(end 101.468462 172.6785)
		(width 0.15)
		(layer "B.Cu")
		(net 3)
	)
	(segment
		(start 51.547962 157.4165)
		(end 50.717962 157.4365)
		(width 0.4)
		(layer "B.Cu")
		(net 3)
	)
	(segment
		(start 110.067962 117.713782)
		(end 110.092962 117.688782)
		(width 0.15)
		(layer "B.Cu")
		(net 3)
	)
	(segment
		(start 101.468462 172.6785)
		(end 102.080962 172.6785)
		(width 0.15)
		(layer "B.Cu")
		(net 3)
	)
	(segment
		(start 100.693462 169.8785)
		(end 101.468462 169.8785)
		(width 0.15)
		(layer "B.Cu")
		(net 3)
	)
	(segment
		(start 99.417962 177.4505)
		(end 99.417962 178.2165)
		(width 0.2)
		(layer "B.Cu")
		(net 3)
	)
	(segment
		(start 90.467962 168.9165)
		(end 90.467962 168.2165)
		(width 0.15)
		(layer "B.Cu")
		(net 3)
	)
	(segment
		(start 126.855462 164.0915)
		(end 126.080462 164.0915)
		(width 0.15)
		(layer "B.Cu")
		(net 3)
	)
	(segment
		(start 83.680168 125.169294)
		(end 84.182962 124.6665)
		(width 0.2)
		(layer "B.Cu")
		(net 3)
	)
	(segment
		(start 52.167962 156.7965)
		(end 51.547962 157.4165)
		(width 0.4)
		(layer "B.Cu")
		(net 3)
	)
	(segment
		(start 91.312962 176.6875)
		(end 90.471962 176.6875)
		(width 0.15)
		(layer "B.Cu")
		(net 3)
	)
	(segment
		(start 88.50814 175.19158)
		(end 88.50822 175.1915)
		(width 0.15)
		(layer "B.Cu")
		(net 3)
	)
	(segment
		(start 64.825 167.0915)
		(end 63.512962 167.0915)
		(width 0.254)
		(layer "B.Cu")
		(net 3)
	)
	(segment
		(start 98.342962 177.5405)
		(end 98.342962 178.1915)
		(width 0.2)
		(layer "B.Cu")
		(net 3)
	)
	(segment
		(start 90.454962 172.1785)
		(end 90.467962 172.1915)
		(width 0.15)
		(layer "B.Cu")
		(net 3)
	)
	(segment
		(start 86.96 117.7)
		(end 86.96 118.4)
		(width 0.254)
		(layer "B.Cu")
		(net 3)
	)
	(segment
		(start 74.142962 146.4435)
		(end 73.640962 146.4435)
		(width 0.127)
		(layer "B.Cu")
		(net 3)
	)
	(segment
		(start 89.893462 175.1915)
		(end 89.118462 175.1915)
		(width 0.15)
		(layer "B.Cu")
		(net 3)
	)
	(segment
		(start 136.867963 137.9655)
		(end 137.467962 137.9655)
		(width 0.127)
		(layer "B.Cu")
		(net 3)
	)
	(segment
		(start 88.567962 128.8665)
		(end 88.567962 130.7265)
		(width 0.35)
		(layer "B.Cu")
		(net 3)
	)
	(segment
		(start 135.270372 146.0075)
		(end 134.567962 146.0075)
		(width 0.2)
		(layer "B.Cu")
		(net 3)
	)
	(segment
		(start 128.167962 124.519)
		(end 127.070462 124.519)
		(width 0.15)
		(layer "B.Cu")
		(net 3)
	)
	(segment
		(start 54.397962 152.5965)
		(end 54.397962 152.8215)
		(width 0.2)
		(layer "B.Cu")
		(net 3)
	)
	(segment
		(start 77.01 136.84)
		(end 75.6285 138.2215)
		(width 0.125)
		(layer "B.Cu")
		(net 3)
	)
	(segment
		(start 53.917962 156.3165)
		(end 53.917962 157.2655)
		(width 0.2)
		(layer "B.Cu")
		(net 3)
	)
	(segment
		(start 128.167962 129.019)
		(end 129.415462 129.019)
		(width 0.15)
		(layer "B.Cu")
		(net 3)
	)
	(segment
		(start 126.855462 165.0915)
		(end 126.080462 165.0915)
		(width 0.15)
		(layer "B.Cu")
		(net 3)
	)
	(segment
		(start 112.542962 118.3415)
		(end 112.542962 118.6165)
		(width 0.15)
		(layer "B.Cu")
		(net 3)
	)
	(segment
		(start 62.602962 136.1165)
		(end 63.992962 136.1165)
		(width 0.15)
		(layer "B.Cu")
		(net 3)
	)
	(segment
		(start 129.415462 129.019)
		(end 129.417962 129.0165)
		(width 0.15)
		(layer "B.Cu")
		(net 3)
	)
	(segment
		(start 127.070462 120.019)
		(end 127.067962 120.0165)
		(width 0.15)
		(layer "B.Cu")
		(net 3)
	)
	(segment
		(start 126.855462 166.9915)
		(end 126.080462 166.9915)
		(width 0.15)
		(layer "B.Cu")
		(net 3)
	)
	(segment
		(start 76.45 153.15)
		(end 75.698 153.15)
		(width 0.15)
		(layer "B.Cu")
		(net 3)
	)
	(segment
		(start 96.809962 173.6875)
		(end 95.721962 173.6875)
		(width 0.2)
		(layer "B.Cu")
		(net 3)
	)
	(segment
		(start 90.467962 169.1915)
		(end 89.906462 169.1915)
		(width 0.15)
		(layer "B.Cu")
		(net 3)
	)
	(segment
		(start 88.567962 128.8665)
		(end 88.567962 128.0195)
		(width 0.35)
		(layer "B.Cu")
		(net 3)
	)
	(segment
		(start 126.542962 134.0165)
		(end 126.542962 134.8165)
		(width 0.15)
		(layer "B.Cu")
		(net 3)
	)
	(segment
		(start 102.050862 169.8785)
		(end 101.468462 169.8785)
		(width 0.15)
		(layer "B.Cu")
		(net 3)
	)
	(segment
		(start 87.642962 127.9165)
		(end 87.617962 127.8915)
		(width 0.35)
		(layer "B.Cu")
		(net 3)
	)
	(segment
		(start 98.492962 174.8925)
		(end 98.492962 175.349499)
		(width 0.2)
		(layer "B.Cu")
		(net 3)
	)
	(segment
		(start 89.118462 172.1785)
		(end 88.554962 172.1785)
		(width 0.15)
		(layer "B.Cu")
		(net 3)
	)
	(segment
		(start 88.264962 127.7165)
		(end 88.264962 126.9175)
		(width 0.35)
		(layer "B.Cu")
		(net 3)
	)
	(segment
		(start 75.6285 138.2215)
		(end 74.967962 138.2215)
		(width 0.125)
		(layer "B.Cu")
		(net 3)
	)
	(segment
		(start 137.467962 130.4665)
		(end 136.292962 130.4665)
		(width 0.15)
		(layer "B.Cu")
		(net 3)
	)
	(segment
		(start 90.467962 173.7665)
		(end 90.546962 173.6875)
		(width 0.15)
		(layer "B.Cu")
		(net 3)
	)
	(segment
		(start 88.554962 172.1785)
		(end 88.542962 172.1665)
		(width 0.15)
		(layer "B.Cu")
		(net 3)
	)
	(segment
		(start 126.543462 134.017)
		(end 126.542962 134.0165)
		(width 0.15)
		(layer "B.Cu")
		(net 3)
	)
	(segment
		(start 90.471962 176.6875)
		(end 90.467962 176.6915)
		(width 0.15)
		(layer "B.Cu")
		(net 3)
	)
	(segment
		(start 83.573574 125.169294)
		(end 83.680168 125.169294)
		(width 0.2)
		(layer "B.Cu")
		(net 3)
	)
	(segment
		(start 128.167962 120.019)
		(end 127.070462 120.019)
		(width 0.15)
		(layer "B.Cu")
		(net 3)
	)
	(segment
		(start 86.992962 127.9165)
		(end 86.967962 127.8915)
		(width 0.35)
		(layer "B.Cu")
		(net 3)
	)
	(segment
		(start 71.442962 128.9565)
		(end 71.442962 129.9205)
		(width 0.254)
		(layer "B.Cu")
		(net 3)
	)
	(segment
		(start 89.893462 168.6785)
		(end 90.429962 168.6785)
		(width 0.15)
		(layer "B.Cu")
		(net 3)
	)
	(segment
		(start 67.109962 166.2115)
		(end 67.109962 166.3335)
		(width 0.254)
		(layer "B.Cu")
		(net 3)
	)
	(segment
		(start 67.092962 166.3505)
		(end 67.092962 167.8165)
		(width 0.254)
		(layer "B.Cu")
		(net 3)
	)
	(segment
		(start 131.107962 170.6665)
		(end 130.670462 170.229)
		(width 0.15)
		(layer "B.Cu")
		(net 3)
	)
	(segment
		(start 129.241462 127.518)
		(end 129.242962 127.5165)
		(width 0.15)
		(layer "B.Cu")
		(net 3)
	)
	(segment
		(start 75.698 153.15)
		(end 75.45 153.398)
		(width 0.15)
		(layer "B.Cu")
		(net 3)
	)
	(segment
		(start 66.901962 133.9165)
		(end 67.692962 133.9165)
		(width 0.15)
		(layer "B.Cu")
		(net 3)
	)
	(segment
		(start 90.429962 168.6785)
		(end 90.467962 168.7165)
		(width 0.15)
		(layer "B.Cu")
		(net 3)
	)
	(segment
		(start 127.069462 121.518)
		(end 127.067962 121.5165)
		(width 0.15)
		(layer "B.Cu")
		(net 3)
	)
	(segment
		(start 96.809962 176.6875)
		(end 95.721962 176.6875)
		(width 0.2)
		(layer "B.Cu")
		(net 3)
	)
	(segment
		(start 90.407962 154.919567)
		(end 90.407962 154.9365)
		(width 0.2)
		(layer "B.Cu")
		(net 3)
	)
	(segment
		(start 73.827962 128.9165)
		(end 75.144962 128.9165)
		(width 0.15)
		(layer "B.Cu")
		(net 3)
	)
	(segment
		(start 139.054462 161.1915)
		(end 140.067962 161.1915)
		(width 0.2)
		(layer "B.Cu")
		(net 3)
	)
	(segment
		(start 140.367962 160.8915)
		(end 140.067962 161.1915)
		(width 0.2)
		(layer "B.Cu")
		(net 3)
	)
	(segment
		(start 88.242962 127.8915)
		(end 88.217962 127.9165)
		(width 0.35)
		(layer "B.Cu")
		(net 3)
	)
	(segment
		(start 91.312962 172.1875)
		(end 90.471962 172.1875)
		(width 0.15)
		(layer "B.Cu")
		(net 3)
	)
	(segment
		(start 129.240462 126.019)
		(end 129.242962 126.0165)
		(width 0.15)
		(layer "B.Cu")
		(net 3)
	)
	(segment
		(start 128.167962 133.52)
		(end 129.414462 133.52)
		(width 0.15)
		(layer "B.Cu")
		(net 3)
	)
	(segment
		(start 95.695962 169.1885)
		(end 95.692962 169.1915)
		(width 0.2)
		(layer "B.Cu")
		(net 3)
	)
	(segment
		(start 107.127962 133.5265)
		(end 106.312962 133.5265)
		(width 0.15)
		(layer "B.Cu")
		(net 3)
	)
	(segment
		(start 73.417962 146.6665)
		(end 73.417962 146.9165)
		(width 0.127)
		(layer "B.Cu")
		(net 3)
	)
	(segment
		(start 89.893462 172.1785)
		(end 90.454962 172.1785)
		(width 0.15)
		(layer "B.Cu")
		(net 3)
	)
	(segment
		(start 88.217962 127.9165)
		(end 87.642962 127.9165)
		(width 0.35)
		(layer "B.Cu")
		(net 3)
	)
	(segment
		(start 139.054462 161.1915)
		(end 137.887962 161.1915)
		(width 0.2)
		(layer "B.Cu")
		(net 3)
	)
	(segment
		(start 73.640962 146.4435)
		(end 73.417962 146.6665)
		(width 0.127)
		(layer "B.Cu")
		(net 3)
	)
	(segment
		(start 89.118462 168.1785)
		(end 89.893462 168.1785)
		(width 0.15)
		(layer "B.Cu")
		(net 3)
	)
	(segment
		(start 74.858962 136.9915)
		(end 74.858962 138.1125)
		(width 0.15)
		(layer "B.Cu")
		(net 3)
	)
	(segment
		(start 89.902962 154.414567)
		(end 90.407962 154.919567)
		(width 0.2)
		(layer "B.Cu")
		(net 3)
	)
	(segment
		(start 134.617962 148.9255)
		(end 134.617962 149.575111)
		(width 0.2)
		(layer "B.Cu")
		(net 3)
	)
	(segment
		(start 70.949962 164.9595)
		(end 67.197962 164.9595)
		(width 0.254)
		(layer "B.Cu")
		(net 3)
	)
	(segment
		(start 90.471962 175.1875)
		(end 90.467962 175.1915)
		(width 0.15)
		(layer "B.Cu")
		(net 3)
	)
	(segment
		(start 130.670462 170.229)
		(end 130.670462 169.4405)
		(width 0.15)
		(layer "B.Cu")
		(net 3)
	)
	(segment
		(start 135.313872 146.051)
		(end 135.270372 146.0075)
		(width 0.2)
		(layer "B.Cu")
		(net 3)
	)
	(segment
		(start 90.471962 172.1875)
		(end 90.467962 172.1915)
		(width 0.15)
		(layer "B.Cu")
		(net 3)
	)
	(segment
		(start 84.692962 128.1915)
		(end 85.517962 128.1665)
		(width 0.35)
		(layer "B.Cu")
		(net 3)
	)
	(segment
		(start 86.967962 127.8915)
		(end 86.942962 127.9165)
		(width 0.35)
		(layer "B.Cu")
		(net 3)
	)
	(segment
		(start 73.692962 150.1185)
		(end 71.869962 150.1185)
		(width 0.15)
		(layer "B.Cu")
		(net 3)
	)
	(segment
		(start 96.809962 169.1885)
		(end 95.695962 169.1885)
		(width 0.2)
		(layer "B.Cu")
		(net 3)
	)
	(segment
		(start 102.080962 172.6785)
		(end 102.092962 172.6665)
		(width 0.15)
		(layer "B.Cu")
		(net 3)
	)
	(segment
		(start 81.594462 136.84)
		(end 77.01 136.84)
		(width 0.125)
		(layer "B.Cu")
		(net 3)
	)
	(segment
		(start 129.415462 132.019)
		(end 129.417962 132.0165)
		(width 0.15)
		(layer "B.Cu")
		(net 3)
	)
	(segment
		(start 79.552962 122.591779)
		(end 79.5148 122.553617)
		(width 0.2)
		(layer "B.Cu")
		(net 3)
	)
	(segment
		(start 65.242962 167.0915)
		(end 64.825 167.0915)
		(width 0.254)
		(layer "B.Cu")
		(net 3)
	)
	(segment
		(start 128.167962 126.019)
		(end 127.070462 126.019)
		(width 0.15)
		(layer "B.Cu")
		(net 3)
	)
	(segment
		(start 89.902962 154.3665)
		(end 89.902962 152.4265)
		(width 0.2)
		(layer "B.Cu")
		(net 3)
	)
	(segment
		(start 91.312962 175.1875)
		(end 90.471962 175.1875)
		(width 0.15)
		(layer "B.Cu")
		(net 3)
	)
	(segment
		(start 128.167962 134.017)
		(end 126.543462 134.017)
		(width 0.15)
		(layer "B.Cu")
		(net 3)
	)
	(segment
		(start 136.517885 136.446423)
		(end 137.449885 136.446423)
		(width 0.15)
		(layer "B.Cu")
		(net 3)
	)
	(segment
		(start 67.109962 166.3335)
		(end 67.092962 166.3505)
		(width 0.254)
		(layer "B.Cu")
		(net 3)
	)
	(segment
		(start 100.058962 175.2755)
		(end 100.267962 175.0665)
		(width 0.2)
		(layer "B.Cu")
		(net 3)
	)
	(segment
		(start 86.998 119.4395)
		(end 86.998 118.438)
		(width 0.254)
		(layer "B.Cu")
		(net 3)
	)
	(segment
		(start 110.092962 116.329)
		(end 110.092962 117.104)
		(width 0.15)
		(layer "B.Cu")
		(net 3)
	)
	(segment
		(start 110.092962 117.688782)
		(end 110.092962 117.104)
		(width 0.15)
		(layer "B.Cu")
		(net 3)
	)
	(segment
		(start 86.998 118.438)
		(end 86.96 118.4)
		(width 0.254)
		(layer "B.Cu")
		(net 3)
	)
	(segment
		(start 50.702962 157.4165)
		(end 48.867962 157.4165)
		(width 1)
		(layer "B.Cu")
		(net 3)
	)
	(segment
		(start 134.617962 149.575111)
		(end 135.079462 150.036611)
		(width 0.2)
		(layer "B.Cu")
		(net 3)
	)
	(segment
		(start 135.079462 150.036611)
		(end 135.717962 149.398111)
		(width 0.2)
		(layer "B.Cu")
		(net 3)
	)
	(segment
		(start 90.467962 168.7165)
		(end 90.467962 168.9165)
		(width 0.15)
		(layer "B.Cu")
		(net 3)
	)
	(segment
		(start 66.122962 166.2115)
		(end 65.629731 166.704731)
		(width 0.254)
		(layer "B.Cu")
		(net 3)
	)
	(segment
		(start 73.737962 129.0065)
		(end 73.827962 128.9165)
		(width 0.15)
		(layer "B.Cu")
		(net 3)
	)
	(segment
		(start 126.080462 166.9915)
		(end 125.042962 166.9915)
		(width 0.15)
		(layer "B.Cu")
		(net 3)
	)
	(segment
		(start 91.312962 170.6875)
		(end 90.471962 170.6875)
		(width 0.15)
		(layer "B.Cu")
		(net 3)
	)
	(segment
		(start 125.342962 165.0915)
		(end 125.192962 165.2415)
		(width 0.15)
		(layer "B.Cu")
		(net 3)
	)
	(segment
		(start 65.629731 166.704731)
		(end 65.242962 167.0915)
		(width 0.254)
		(layer "B.Cu")
		(net 3)
	)
	(segment
		(start 128.167962 130.519)
		(end 129.415462 130.519)
		(width 0.15)
		(layer "B.Cu")
		(net 3)
	)
	(segment
		(start 128.167962 126.019)
		(end 129.240462 126.019)
		(width 0.15)
		(layer "B.Cu")
		(net 3)
	)
	(segment
		(start 67.109962 165.0475)
		(end 67.109962 166.2115)
		(width 0.254)
		(layer "B.Cu")
		(net 3)
	)
	(segment
		(start 52.167962 155.90119)
		(end 52.167962 156.7965)
		(width 0.4)
		(layer "B.Cu")
		(net 3)
	)
	(segment
		(start 110.092962 116.329)
		(end 110.092962 115.7165)
		(width 0.15)
		(layer "B.Cu")
		(net 3)
	)
	(segment
		(start 85.517962 128.1665)
		(end 85.767962 127.9165)
		(width 0.35)
		(layer "B.Cu")
		(net 3)
	)
	(segment
		(start 52.146694 155.879922)
		(end 52.167962 155.90119)
		(width 0.4)
		(layer "B.Cu")
		(net 3)
	)
	(segment
		(start 125.447098 164.0915)
		(end 126.080462 164.0915)
		(width 0.15)
		(layer "B.Cu")
		(net 3)
	)
	(segment
		(start 127.070462 124.519)
		(end 127.067962 124.5165)
		(width 0.15)
		(layer "B.Cu")
		(net 3)
	)
	(segment
		(start 88.428962 127.8805)
		(end 88.392962 127.9165)
		(width 0.35)
		(layer "B.Cu")
		(net 3)
	)
	(segment
		(start 128.167962 123.018)
		(end 127.069462 123.018)
		(width 0.15)
		(layer "B.Cu")
		(net 3)
	)
	(segment
		(start 128.167962 121.518)
		(end 127.069462 121.518)
		(width 0.15)
		(layer "B.Cu")
		(net 3)
	)
	(segment
		(start 90.397962 165.9365)
		(end 91.454962 165.9365)
		(width 0.254)
		(layer "B.Cu")
		(net 3)
	)
	(segment
		(start 87.592962 127.9165)
		(end 86.992962 127.9165)
		(width 0.35)
		(layer "B.Cu")
		(net 3)
	)
	(segment
		(start 78.073927 155.386073)
		(end 78.492962 154.967038)
		(width 0.15)
		(layer "B.Cu")
		(net 3)
	)
	(segment
		(start 137.467962 131.9665)
		(end 136.317962 131.9665)
		(width 0.15)
		(layer "B.Cu")
		(net 3)
	)
	(segment
		(start 77.393787 155.386073)
		(end 78.073927 155.386073)
		(width 0.15)
		(layer "B.Cu")
		(net 3)
	)
	(segment
		(start 67.109962 166.2115)
		(end 66.122962 166.2115)
		(width 0.254)
		(layer "B.Cu")
		(net 3)
	)
	(segment
		(start 98.342962 178.1915)
		(end 98.317962 178.2165)
		(width 0.2)
		(layer "B.Cu")
		(net 3)
	)
	(segment
		(start 54.258962 158.4165)
		(end 53.917962 158.0755)
		(width 0.254)
		(layer "B.Cu")
		(net 3)
	)
	(segment
		(start 90.429962 168.1785)
		(end 90.442962 168.1915)
		(width 0.15)
		(layer "B.Cu")
		(net 3)
	)
	(segment
		(start 81.917231 136.517231)
		(end 81.594462 136.84)
		(width 0.125)
		(layer "B.Cu")
		(net 3)
	)
	(segment
		(start 90.546962 173.6875)
		(end 91.312962 173.6875)
		(width 0.15)
		(layer "B.Cu")
		(net 3)
	)
	(segment
		(start 52.917962 156.3145)
		(end 52.181962 156.3145)
		(width 0.35)
		(layer "B.Cu")
		(net 3)
	)
	(segment
		(start 95.721962 173.6875)
		(end 95.717962 173.6915)
		(width 0.2)
		(layer "B.Cu")
		(net 3)
	)
	(segment
		(start 90.467962 168.9165)
		(end 90.467962 169.1915)
		(width 0.15)
		(layer "B.Cu")
		(net 3)
	)
	(segment
		(start 118.28 173)
		(end 118.87 173)
		(width 0.254)
		(layer "B.Cu")
		(net 3)
	)
	(segment
		(start 90.471962 170.6875)
		(end 90.467962 170.6915)
		(width 0.15)
		(layer "B.Cu")
		(net 3)
	)
	(segment
		(start 135.313872 146.051)
		(end 135.313872 145.99559)
		(width 0.2)
		(layer "B.Cu")
		(net 3)
	)
	(segment
		(start 137.467962 128.9665)
		(end 136.392962 128.9665)
		(width 0.15)
		(layer "B.Cu")
		(net 3)
	)
	(segment
		(start 78.492962 154.967038)
		(end 78.492962 154.1215)
		(width 0.15)
		(layer "B.Cu")
		(net 3)
	)
	(segment
		(start 98.146684 178.63)
		(end 97.951184 178.4345)
		(width 0.127)
		(layer "F.Cu")
		(net 4)
	)
	(segment
		(start 129.715962 120.8185)
		(end 129.715962 124.9165)
		(width 0.254)
		(layer "F.Cu")
		(net 4)
	)
	(segment
		(start 132.55 133.665962)
		(end 132.015962 134.2)
		(width 0.127)
		(layer "F.Cu")
		(net 4)
	)
	(segment
		(start 132.015962 134.2)
		(end 132.015962 153.464038)
		(width 0.127)
		(layer "F.Cu")
		(net 4)
	)
	(segment
		(start 129.674962 158.864962)
		(end 129.674962 160.728118)
		(width 0.127)
		(layer "F.Cu")
		(net 4)
	)
	(segment
		(start 132.015962 125.9645)
		(end 132.015962 131.215962)
		(width 0.127)
		(layer "F.Cu")
		(net 4)
	)
	(segment
		(start 132.55 131.75)
		(end 132.55 133.665962)
		(width 0.127)
		(layer "F.Cu")
		(net 4)
	)
	(segment
		(start 131.842962 125.7915)
		(end 132.015962 125.9645)
		(width 0.127)
		(layer "F.Cu")
		(net 4)
	)
	(segment
		(start 104.9655 178.4345)
		(end 99.78474 178.4345)
		(width 0.127)
		(layer "F.Cu")
		(net 4)
	)
	(segment
		(start 122.0585 161.3415)
		(end 104.9655 178.4345)
		(width 0.127)
		(layer "F.Cu")
		(net 4)
	)
	(segment
		(start 130.640962 125.7915)
		(end 131.842962 125.7915)
		(width 0.127)
		(layer "F.Cu")
		(net 4)
	)
	(segment
		(start 129.06158 161.3415)
		(end 122.0585 161.3415)
		(width 0.127)
		(layer "F.Cu")
		(net 4)
	)
	(segment
		(start 99.58924 178.63)
		(end 98.146684 178.63)
		(width 0.127)
		(layer "F.Cu")
		(net 4)
	)
	(segment
		(start 83.149962 170.3685)
		(end 82.822962 170.0415)
		(width 0.127)
		(layer "F.Cu")
		(net 4)
	)
	(segment
		(start 129.54 158.73)
		(end 129.674962 158.864962)
		(width 0.127)
		(layer "F.Cu")
		(net 4)
	)
	(segment
		(start 129.752962 119.6165)
		(end 129.752962 118.6675)
		(width 0.254)
		(layer "F.Cu")
		(net 4)
	)
	(segment
		(start 132.015962 153.464038)
		(end 129.54 155.94)
		(width 0.127)
		(layer "F.Cu")
		(net 4)
	)
	(segment
		(start 85.069962 172.137118)
		(end 83.301344 170.3685)
		(width 0.127)
		(layer "F.Cu")
		(net 4)
	)
	(segment
		(start 99.78474 178.4345)
		(end 99.58924 178.63)
		(width 0.127)
		(layer "F.Cu")
		(net 4)
	)
	(segment
		(start 129.54 155.94)
		(end 129.54 158.73)
		(width 0.127)
		(layer "F.Cu")
		(net 4)
	)
	(segment
		(start 85.069962 175.306264)
		(end 85.069962 172.137118)
		(width 0.127)
		(layer "F.Cu")
		(net 4)
	)
	(segment
		(start 83.301344 170.3685)
		(end 83.149962 170.3685)
		(width 0.127)
		(layer "F.Cu")
		(net 4)
	)
	(segment
		(start 129.765962 124.9165)
		(end 130.640962 125.7915)
		(width 0.127)
		(layer "F.Cu")
		(net 4)
	)
	(segment
		(start 129.674962 160.728118)
		(end 129.06158 161.3415)
		(width 0.127)
		(layer "F.Cu")
		(net 4)
	)
	(segment
		(start 88.198198 178.4345)
		(end 85.069962 175.306264)
		(width 0.127)
		(layer "F.Cu")
		(net 4)
	)
	(segment
		(start 129.715962 120.8185)
		(end 129.715962 119.6175)
		(width 0.254)
		(layer "F.Cu")
		(net 4)
	)
	(segment
		(start 132.015962 131.215962)
		(end 132.55 131.75)
		(width 0.127)
		(layer "F.Cu")
		(net 4)
	)
	(segment
		(start 97.951184 178.4345)
		(end 88.198198 178.4345)
		(width 0.127)
		(layer "F.Cu")
		(net 4)
	)
	(segment
		(start 124.290476 162.7165)
		(end 124.917962 162.7165)
		(width 0.21)
		(layer "F.Cu")
		(net 5)
	)
	(segment
		(start 124.917962 162.7165)
		(end 125.217962 163.0165)
		(width 0.21)
		(layer "F.Cu")
		(net 5)
	)
	(segment
		(start 80.542962 158.2415)
		(end 80.417462 158.116)
		(width 0.21)
		(layer "F.Cu")
		(net 5)
	)
	(segment
		(start 80.417462 158.116)
		(end 78.473961 158.116)
		(width 0.21)
		(layer "F.Cu")
		(net 5)
	)
	(via
		(at 125.217962 163.0165)
		(size 0.45)
		(drill 0.1)
		(layers "F.Cu" "B.Cu")
		(net 5)
	)
	(via
		(at 80.542962 158.2415)
		(size 0.45)
		(drill 0.1)
		(layers "F.Cu" "B.Cu")
		(net 5)
	)
	(segment
		(start 131.991595 160.107279)
		(end 132.295651 160.411335)
		(width 0.21)
		(layer "B.Cu")
		(net 5)
	)
	(segment
		(start 131.44712 161.599277)
		(end 131.362269 161.684129)
		(width 0.21)
		(layer "B.Cu")
		(net 5)
	)
	(segment
		(start 131.397623 160.361839)
		(end 130.923861 159.888077)
		(width 0.21)
		(layer "B.Cu")
		(net 5)
	)
	(segment
		(start 130.37939 161.380074)
		(end 130.294536 161.464927)
		(width 0.21)
		(layer "B.Cu")
		(net 5)
	)
	(segment
		(start 131.022857 161.684129)
		(end 130.718802 161.380074)
		(width 0.21)
		(layer "B.Cu")
		(net 5)
	)
	(segment
		(start 130.294536 161.464927)
		(end 129.946405 161.813057)
		(width 0.21)
		(layer "B.Cu")
		(net 5)
	)
	(segment
		(start 125.292962 163.0915)
		(end 128.667962 163.0915)
		(width 0.21)
		(layer "B.Cu")
		(net 5)
	)
	(segment
		(start 118.9 167.5)
		(end 123.3835 163.0165)
		(width 0.21)
		(layer "B.Cu")
		(net 5)
	)
	(segment
		(start 80.542962 158.2415)
		(end 98.692962 158.2415)
		(width 0.21)
		(layer "B.Cu")
		(net 5)
	)
	(segment
		(start 130.58445 159.888077)
		(end 130.499597 159.972929)
		(width 0.21)
		(layer "B.Cu")
		(net 5)
	)
	(segment
		(start 131.143065 160.955809)
		(end 131.447121 161.259865)
		(width 0.21)
		(layer "B.Cu")
		(net 5)
	)
	(segment
		(start 132.295651 160.750747)
		(end 132.210798 160.835601)
		(width 0.21)
		(layer "B.Cu")
		(net 5)
	)
	(segment
		(start 98.692962 158.252108)
		(end 107.940854 167.5)
		(width 0.21)
		(layer "B.Cu")
		(net 5)
	)
	(segment
		(start 130.973358 160.786102)
		(end 131.143065 160.955809)
		(width 0.21)
		(layer "B.Cu")
		(net 5)
	)
	(segment
		(start 130.499597 160.312341)
		(end 130.973358 160.786102)
		(width 0.21)
		(layer "B.Cu")
		(net 5)
	)
	(segment
		(start 128.667962 163.0915)
		(end 129.946405 161.813057)
		(width 0.21)
		(layer "B.Cu")
		(net 5)
	)
	(segment
		(start 131.871386 160.835601)
		(end 131.567331 160.531546)
		(width 0.21)
		(layer "B.Cu")
		(net 5)
	)
	(segment
		(start 132.768962 158.9905)
		(end 131.991595 159.767867)
		(width 0.21)
		(layer "B.Cu")
		(net 5)
	)
	(segment
		(start 125.217962 163.0165)
		(end 125.292962 163.0915)
		(width 0.21)
		(layer "B.Cu")
		(net 5)
	)
	(segment
		(start 98.692962 158.2415)
		(end 98.692962 158.252108)
		(width 0.21)
		(layer "B.Cu")
		(net 5)
	)
	(segment
		(start 139.054462 158.9905)
		(end 132.768962 158.9905)
		(width 0.21)
		(layer "B.Cu")
		(net 5)
	)
	(segment
		(start 107.940854 167.5)
		(end 118.9 167.5)
		(width 0.21)
		(layer "B.Cu")
		(net 5)
	)
	(segment
		(start 123.3835 163.0165)
		(end 125.217962 163.0165)
		(width 0.21)
		(layer "B.Cu")
		(net 5)
	)
	(segment
		(start 131.567331 160.531546)
		(end 131.397623 160.361839)
		(width 0.21)
		(layer "B.Cu")
		(net 5)
	)
	(arc
		(start 130.923861 159.888077)
		(mid 130.754156 159.817782)
		(end 130.58445 159.888077)
		(width 0.21)
		(layer "B.Cu")
		(net 5)
	)
	(arc
		(start 130.718802 161.380074)
		(mid 130.549095 161.30978)
		(end 130.37939 161.380074)
		(width 0.21)
		(layer "B.Cu")
		(net 5)
	)
	(arc
		(start 132.295651 160.411335)
		(mid 132.365945 160.581042)
		(end 132.295651 160.750747)
		(width 0.21)
		(layer "B.Cu")
		(net 5)
	)
	(arc
		(start 131.991595 159.767867)
		(mid 131.921299 159.937574)
		(end 131.991595 160.107279)
		(width 0.21)
		(layer "B.Cu")
		(net 5)
	)
	(arc
		(start 131.447121 161.259865)
		(mid 131.517416 161.42957)
		(end 131.44712 161.599277)
		(width 0.21)
		(layer "B.Cu")
		(net 5)
	)
	(arc
		(start 131.362269 161.684129)
		(mid 131.192562 161.754425)
		(end 131.022857 161.684129)
		(width 0.21)
		(layer "B.Cu")
		(net 5)
	)
	(arc
		(start 130.499597 159.972929)
		(mid 130.429302 160.142635)
		(end 130.499597 160.312341)
		(width 0.21)
		(layer "B.Cu")
		(net 5)
	)
	(arc
		(start 132.210798 160.835601)
		(mid 132.041093 160.905895)
		(end 131.871386 160.835601)
		(width 0.21)
		(layer "B.Cu")
		(net 5)
	)
	(segment
		(start 124.967962 163.6665)
		(end 125.042962 163.5915)
		(width 0.21)
		(layer "F.Cu")
		(net 6)
	)
	(segment
		(start 79.817962 157.659)
		(end 79.36743 157.659)
		(width 0.21)
		(layer "F.Cu")
		(net 6)
	)
	(segment
		(start 79.02543 157.317)
		(end 78.473961 157.317)
		(width 0.21)
		(layer "F.Cu")
		(net 6)
	)
	(segment
		(start 124.290476 163.6665)
		(end 124.967962 163.6665)
		(width 0.21)
		(layer "F.Cu")
		(net 6)
	)
	(segment
		(start 79.36743 157.659)
		(end 79.02543 157.317)
		(width 0.21)
		(layer "F.Cu")
		(net 6)
	)
	(via
		(at 125.042962 163.5915)
		(size 0.45)
		(drill 0.1)
		(layers "F.Cu" "B.Cu")
		(net 6)
	)
	(via
		(at 79.817962 157.659)
		(size 0.45)
		(drill 0.1)
		(layers "F.Cu" "B.Cu")
		(net 6)
	)
	(segment
		(start 132.850206 161.517294)
		(end 133.07648 161.743568)
		(width 0.21)
		(layer "B.Cu")
		(net 6)
	)
	(segment
		(start 133.642167 162.648667)
		(end 133.557314 162.733521)
		(width 0.21)
		(layer "B.Cu")
		(net 6)
	)
	(segment
		(start 98.323272 159.0845)
		(end 107.538772 168.3)
		(width 0.21)
		(layer "B.Cu")
		(net 6)
	)
	(segment
		(start 133.217902 162.733521)
		(end 132.821923 162.337542)
		(width 0.21)
		(layer "B.Cu")
		(net 6)
	)
	(segment
		(start 131.567962 163.5915)
		(end 125.042962 163.5915)
		(width 0.21)
		(layer "B.Cu")
		(net 6)
	)
	(segment
		(start 132.001676 162.365825)
		(end 132.22795 162.592099)
		(width 0.21)
		(layer "B.Cu")
		(net 6)
	)
	(segment
		(start 107.538772 168.3)
		(end 119.3 168.3)
		(width 0.21)
		(layer "B.Cu")
		(net 6)
	)
	(segment
		(start 132.086529 161.941561)
		(end 132.001676 162.026413)
		(width 0.21)
		(layer "B.Cu")
		(net 6)
	)
	(segment
		(start 131.869905 163.289557)
		(end 131.567962 163.5915)
		(width 0.21)
		(layer "B.Cu")
		(net 6)
	)
	(segment
		(start 132.935059 161.09303)
		(end 132.850206 161.177882)
		(width 0.21)
		(layer "B.Cu")
		(net 6)
	)
	(segment
		(start 133.246187 161.913275)
		(end 133.642167 162.309255)
		(width 0.21)
		(layer "B.Cu")
		(net 6)
	)
	(segment
		(start 132.652215 162.167835)
		(end 132.425941 161.941561)
		(width 0.21)
		(layer "B.Cu")
		(net 6)
	)
	(segment
		(start 135.081462 160.078)
		(end 133.840157 161.319305)
		(width 0.21)
		(layer "B.Cu")
		(net 6)
	)
	(segment
		(start 133.500745 161.319305)
		(end 133.27447 161.09303)
		(width 0.21)
		(layer "B.Cu")
		(net 6)
	)
	(segment
		(start 124.0085 163.5915)
		(end 125.042962 163.5915)
		(width 0.21)
		(layer "B.Cu")
		(net 6)
	)
	(segment
		(start 79.817962 157.659)
		(end 79.817962 158.5915)
		(width 0.21)
		(layer "B.Cu")
		(net 6)
	)
	(segment
		(start 133.07648 161.743568)
		(end 133.246187 161.913275)
		(width 0.21)
		(layer "B.Cu")
		(net 6)
	)
	(segment
		(start 80.310962 159.0845)
		(end 98.323272 159.0845)
		(width 0.21)
		(layer "B.Cu")
		(net 6)
	)
	(segment
		(start 139.066962 160.078)
		(end 135.081462 160.078)
		(width 0.21)
		(layer "B.Cu")
		(net 6)
	)
	(segment
		(start 132.821923 162.337542)
		(end 132.652215 162.167835)
		(width 0.21)
		(layer "B.Cu")
		(net 6)
	)
	(segment
		(start 132.22795 162.93151)
		(end 132.143098 163.016363)
		(width 0.21)
		(layer "B.Cu")
		(net 6)
	)
	(segment
		(start 119.3 168.3)
		(end 124.0085 163.5915)
		(width 0.21)
		(layer "B.Cu")
		(net 6)
	)
	(segment
		(start 132.143098 163.016363)
		(end 131.869905 163.289557)
		(width 0.21)
		(layer "B.Cu")
		(net 6)
	)
	(segment
		(start 79.817962 158.5915)
		(end 80.310962 159.0845)
		(width 0.21)
		(layer "B.Cu")
		(net 6)
	)
	(arc
		(start 133.642167 162.309255)
		(mid 133.712461 162.478962)
		(end 133.642167 162.648667)
		(width 0.21)
		(layer "B.Cu")
		(net 6)
	)
	(arc
		(start 132.22795 162.592099)
		(mid 132.298244 162.761805)
		(end 132.22795 162.93151)
		(width 0.21)
		(layer "B.Cu")
		(net 6)
	)
	(arc
		(start 132.850206 161.177882)
		(mid 132.779911 161.347588)
		(end 132.850206 161.517294)
		(width 0.21)
		(layer "B.Cu")
		(net 6)
	)
	(arc
		(start 133.557314 162.733521)
		(mid 133.387609 162.803815)
		(end 133.217902 162.733521)
		(width 0.21)
		(layer "B.Cu")
		(net 6)
	)
	(arc
		(start 133.840157 161.319305)
		(mid 133.670451 161.3896)
		(end 133.500745 161.319305)
		(width 0.21)
		(layer "B.Cu")
		(net 6)
	)
	(arc
		(start 132.425941 161.941561)
		(mid 132.256235 161.871266)
		(end 132.086529 161.941561)
		(width 0.21)
		(layer "B.Cu")
		(net 6)
	)
	(arc
		(start 132.001676 162.026413)
		(mid 131.931381 162.196119)
		(end 132.001676 162.365825)
		(width 0.21)
		(layer "B.Cu")
		(net 6)
	)
	(arc
		(start 133.27447 161.09303)
		(mid 133.104765 161.022735)
		(end 132.935059 161.09303)
		(width 0.21)
		(layer "B.Cu")
		(net 6)
	)
	(segment
		(start 79.085962 156.660531)
		(end 79.366937 156.941506)
		(width 0.21)
		(layer "F.Cu")
		(net 7)
	)
	(segment
		(start 124.290476 164.8165)
		(end 124.942962 164.8165)
		(width 0.21)
		(layer "F.Cu")
		(net 7)
	)
	(segment
		(start 124.942962 164.8165)
		(end 125.167962 164.5915)
		(width 0.21)
		(layer "F.Cu")
		(net 7)
	)
	(segment
		(start 79.085962 156.213001)
		(end 79.085962 156.660531)
		(width 0.21)
		(layer "F.Cu")
		(net 7)
	)
	(segment
		(start 78.987961 156.115)
		(end 79.085962 156.213001)
		(width 0.21)
		(layer "F.Cu")
		(net 7)
	)
	(segment
		(start 78.473961 156.115)
		(end 78.987961 156.115)
		(width 0.21)
		(layer "F.Cu")
		(net 7)
	)
	(via
		(at 125.167962 164.5915)
		(size 0.45)
		(drill 0.1)
		(layers "F.Cu" "B.Cu")
		(net 7)
	)
	(via
		(at 79.366937 156.941506)
		(size 0.45)
		(drill 0.1)
		(layers "F.Cu" "B.Cu")
		(net 7)
	)
	(segment
		(start 135.274997 163.364415)
		(end 135.451774 163.541192)
		(width 0.21)
		(layer "B.Cu")
		(net 7)
	)
	(segment
		(start 134.151031 164.148969)
		(end 133.7075 164.5925)
		(width 0.21)
		(layer "B.Cu")
		(net 7)
	)
	(segment
		(start 127.130462 164.5925)
		(end 127.129462 164.5915)
		(width 0.21)
		(layer "B.Cu")
		(net 7)
	)
	(segment
		(start 119.8 169)
		(end 106.96598 169)
		(width 0.21)
		(layer "B.Cu")
		(net 7)
	)
	(segment
		(start 97.96448 159.9985)
		(end 80.099962 159.9985)
		(width 0.21)
		(layer "B.Cu")
		(net 7)
	)
	(segment
		(start 134.935584 163.025002)
		(end 135.274997 163.364415)
		(width 0.21)
		(layer "B.Cu")
		(net 7)
	)
	(segment
		(start 133.7075 164.5925)
		(end 127.130462 164.5925)
		(width 0.21)
		(layer "B.Cu")
		(net 7)
	)
	(segment
		(start 125.167962 164.5915)
		(end 124.2085 164.5915)
		(width 0.21)
		(layer "B.Cu")
		(net 7)
	)
	(segment
		(start 135.359849 162.600739)
		(end 135.183072 162.423962)
		(width 0.21)
		(layer "B.Cu")
		(net 7)
	)
	(segment
		(start 134.758808 162.848226)
		(end 134.935584 163.025002)
		(width 0.21)
		(layer "B.Cu")
		(net 7)
	)
	(segment
		(start 124.2085 164.5915)
		(end 119.8 169)
		(width 0.21)
		(layer "B.Cu")
		(net 7)
	)
	(segment
		(start 136.0095 162.2905)
		(end 135.699261 162.600739)
		(width 0.21)
		(layer "B.Cu")
		(net 7)
	)
	(segment
		(start 134.843661 162.423962)
		(end 134.758808 162.508814)
		(width 0.21)
		(layer "B.Cu")
		(net 7)
	)
	(segment
		(start 134.426468 163.873533)
		(end 134.151031 164.148969)
		(width 0.21)
		(layer "B.Cu")
		(net 7)
	)
	(segment
		(start 127.129462 164.5915)
		(end 125.167962 164.5915)
		(width 0.21)
		(layer "B.Cu")
		(net 7)
	)
	(segment
		(start 79.307962 159.2065)
		(end 79.307962 157.000481)
		(width 0.21)
		(layer "B.Cu")
		(net 7)
	)
	(segment
		(start 139.054462 162.2905)
		(end 136.0095 162.2905)
		(width 0.21)
		(layer "B.Cu")
		(net 7)
	)
	(segment
		(start 80.099962 159.9985)
		(end 79.307962 159.2065)
		(width 0.21)
		(layer "B.Cu")
		(net 7)
	)
	(segment
		(start 135.02751 163.965456)
		(end 134.850734 163.78868)
		(width 0.21)
		(layer "B.Cu")
		(net 7)
	)
	(segment
		(start 135.451773 163.880604)
		(end 135.366922 163.965456)
		(width 0.21)
		(layer "B.Cu")
		(net 7)
	)
	(segment
		(start 79.307962 157.000481)
		(end 79.366937 156.941506)
		(width 0.21)
		(layer "B.Cu")
		(net 7)
	)
	(segment
		(start 106.96598 169)
		(end 97.96448 159.9985)
		(width 0.21)
		(layer "B.Cu")
		(net 7)
	)
	(segment
		(start 134.511322 163.788681)
		(end 134.426468 163.873533)
		(width 0.21)
		(layer "B.Cu")
		(net 7)
	)
	(arc
		(start 135.451774 163.541192)
		(mid 135.522069 163.710897)
		(end 135.451773 163.880604)
		(width 0.21)
		(layer "B.Cu")
		(net 7)
	)
	(arc
		(start 135.699261 162.600739)
		(mid 135.529555 162.671034)
		(end 135.359849 162.600739)
		(width 0.21)
		(layer "B.Cu")
		(net 7)
	)
	(arc
		(start 134.850734 163.78868)
		(mid 134.681028 163.718386)
		(end 134.511322 163.788681)
		(width 0.21)
		(layer "B.Cu")
		(net 7)
	)
	(arc
		(start 134.758808 162.508814)
		(mid 134.688513 162.67852)
		(end 134.758808 162.848226)
		(width 0.21)
		(layer "B.Cu")
		(net 7)
	)
	(arc
		(start 135.183072 162.423962)
		(mid 135.013367 162.353667)
		(end 134.843661 162.423962)
		(width 0.21)
		(layer "B.Cu")
		(net 7)
	)
	(arc
		(start 135.366922 163.965456)
		(mid 135.197215 164.035752)
		(end 135.02751 163.965456)
		(width 0.21)
		(layer "B.Cu")
		(net 7)
	)
	(segment
		(start 124.290476 165.9665)
		(end 125.120242 165.9665)
		(width 0.21)
		(layer "F.Cu")
		(net 8)
	)
	(segment
		(start 80.056732 156.4165)
		(end 79.642962 156.4165)
		(width 0.21)
		(layer "F.Cu")
		(net 8)
	)
	(segment
		(start 80.557232 156.917)
		(end 80.056732 156.4165)
		(width 0.21)
		(layer "F.Cu")
		(net 8)
	)
	(segment
		(start 125.120242 165.9665)
		(end 125.17185 165.914892)
		(width 0.21)
		(layer "F.Cu")
		(net 8)
	)
	(segment
		(start 81.554961 156.917)
		(end 80.557232 156.917)
		(width 0.21)
		(layer "F.Cu")
		(net 8)
	)
	(via
		(at 125.17185 165.914892)
		(size 0.45)
		(drill 0.1)
		(layers "F.Cu" "B.Cu")
		(net 8)
	)
	(via
		(at 79.642962 156.4165)
		(size 0.45)
		(drill 0.1)
		(layers "F.Cu" "B.Cu")
		(net 8)
	)
	(segment
		(start 97.470044 160.7415)
		(end 79.767962 160.7415)
		(width 0.21)
		(layer "B.Cu")
		(net 8)
	)
	(segment
		(start 135.742962 164.4915)
		(end 134.642962 165.5915)
		(width 0.21)
		(layer "B.Cu")
		(net 8)
	)
	(segment
		(start 120.1 169.8)
		(end 106.528544 169.8)
		(width 0.21)
		(layer "B.Cu")
		(net 8)
	)
	(segment
		(start 78.817962 156.6665)
		(end 79.067962 156.4165)
		(width 0.21)
		(layer "B.Cu")
		(net 8)
	)
	(segment
		(start 125.248458 165.9915)
		(end 125.17185 165.914892)
		(width 0.21)
		(layer "B.Cu")
		(net 8)
	)
	(segment
		(start 134.642962 165.5915)
		(end 128.267962 165.5915)
		(width 0.21)
		(layer "B.Cu")
		(net 8)
	)
	(segment
		(start 128.267962 165.5915)
		(end 127.867962 165.9915)
		(width 0.21)
		(layer "B.Cu")
		(net 8)
	)
	(segment
		(start 78.817962 159.7915)
		(end 78.817962 156.6665)
		(width 0.21)
		(layer "B.Cu")
		(net 8)
	)
	(segment
		(start 125.17185 165.914892)
		(end 123.985108 165.914892)
		(width 0.21)
		(layer "B.Cu")
		(net 8)
	)
	(segment
		(start 106.528544 169.8)
		(end 97.470044 160.7415)
		(width 0.21)
		(layer "B.Cu")
		(net 8)
	)
	(segment
		(start 79.067962 156.4165)
		(end 79.642962 156.4165)
		(width 0.21)
		(layer "B.Cu")
		(net 8)
	)
	(segment
		(start 79.767962 160.7415)
		(end 78.817962 159.7915)
		(width 0.21)
		(layer "B.Cu")
		(net 8)
	)
	(segment
		(start 123.985108 165.914892)
		(end 120.1 169.8)
		(width 0.21)
		(layer "B.Cu")
		(net 8)
	)
	(segment
		(start 139.054462 164.4915)
		(end 135.742962 164.4915)
		(width 0.21)
		(layer "B.Cu")
		(net 8)
	)
	(segment
		(start 127.867962 165.9915)
		(end 125.248458 165.9915)
		(width 0.21)
		(layer "B.Cu")
		(net 8)
	)
	(segment
		(start 65.609764 168.489764)
		(end 65.799528 168.3)
		(width 0.2)
		(layer "F.Cu")
		(net 9)
	)
	(segment
		(start 75.667962 161.1665)
		(end 75.667962 157.739293)
		(width 0.15)
		(layer "F.Cu")
		(net 9)
	)
	(segment
		(start 76.115246 166.7165)
		(end 76.13348 166.734734)
		(width 0.2)
		(layer "F.Cu")
		(net 9)
	)
	(segment
		(start 74.357343 154.425194)
		(end 74.23314 154.34221)
		(width 0.15)
		(layer "F.Cu")
		(net 9)
	)
	(segment
		(start 86.947754 148.2165)
		(end 86.897962 148.2165)
		(width 0.127)
		(layer "F.Cu")
		(net 9)
	)
	(segment
		(start 92.322962 156.1265)
		(end 92.332962 156.1165)
		(width 0.2)
		(layer "F.Cu")
		(net 9)
	)
	(segment
		(start 123.307962 170.551962)
		(end 123.307962 167.8665)
		(width 0.15)
		(layer "F.Cu")
		(net 9)
	)
	(segment
		(start 83.563962 150.7075)
		(end 84.183962 150.7075)
		(width 0.2)
		(layer "F.Cu")
		(net 9)
	)
	(segment
		(start 138.217962 164.4165)
		(end 138.667962 164.4165)
		(width 0.2)
		(layer "F.Cu")
		(net 9)
	)
	(segment
		(start 106.947962 139.1665)
		(end 106.947962 139.8865)
		(width 0.254)
		(layer "F.Cu")
		(net 9)
	)
	(segment
		(start 137.792962 163.4165)
		(end 138.533962 163.4165)
		(width 0.254)
		(layer "F.Cu")
		(net 9)
	)
	(segment
		(start 97.782962 142.1715)
		(end 98.622962 142.1715)
		(width 0.2)
		(layer "F.Cu")
		(net 9)
	)
	(segment
		(start 138.642962 147.1415)
		(end 138.642962 149.7175)
		(width 0.254)
		(layer "F.Cu")
		(net 9)
	)
	(segment
		(start 74.817962 162.0165)
		(end 74.817962 164.1915)
		(width 0.2)
		(layer "F.Cu")
		(net 9)
	)
	(segment
		(start 75.234462 154.747108)
		(end 75.000353 154.512999)
		(width 0.15)
		(layer "F.Cu")
		(net 9)
	)
	(segment
		(start 87.787962 150.8865)
		(end 88.067962 151.1665)
		(width 0.15)
		(layer "F.Cu")
		(net 9)
	)
	(segment
		(start 135.985962 119.7865)
		(end 136.842962 120.6435)
		(width 0.254)
		(layer "F.Cu")
		(net 9)
	)
	(segment
		(start 123.317962 117.64192)
		(end 123.487962 117.81192)
		(width 0.254)
		(layer "F.Cu")
		(net 9)
	)
	(segment
		(start 106.947962 139.8865)
		(end 106.892962 139.9415)
		(width 0.254)
		(layer "F.Cu")
		(net 9)
	)
	(segment
		(start 140.393962 150.8175)
		(end 140.917962 151.3415)
		(width 0.254)
		(layer "F.Cu")
		(net 9)
	)
	(segment
		(start 75.552962 166.7165)
		(end 76.115246 166.7165)
		(width 0.2)
		(layer "F.Cu")
		(net 9)
	)
	(segment
		(start 88.547754 149.8165)
		(end 86.947754 148.2165)
		(width 0.127)
		(layer "F.Cu")
		(net 9)
	)
	(segment
		(start 123.317962 116.7665)
		(end 123.317962 117.64192)
		(width 0.254)
		(layer "F.Cu")
		(net 9)
	)
	(segment
		(start 130.717962 158.2765)
		(end 131.397962 158.2765)
		(width 0.2)
		(layer "F.Cu")
		(net 9)
	)
	(segment
		(start 136.842962 124.7415)
		(end 136.842962 120.6435)
		(width 0.254)
		(layer "F.Cu")
		(net 9)
	)
	(segment
		(start 86.631462 150.13)
		(end 87.333962 150.8325)
		(width 0.2)
		(layer "F.Cu")
		(net 9)
	)
	(segment
		(start 65.862962 146.326277)
		(end 65.862962 143.9165)
		(width 0.15)
		(layer "F.Cu")
		(net 9)
	)
	(segment
		(start 141.905462 151.3415)
		(end 142.680462 151.3415)
		(width 0.127)
		(layer "F.Cu")
		(net 9)
	)
	(segment
		(start 91.267962 149.8165)
		(end 88.547754 149.8165)
		(width 0.127)
		(layer "F.Cu")
		(net 9)
	)
	(segment
		(start 137.792962 163.4165)
		(end 137.792962 163.9915)
		(width 0.2)
		(layer "F.Cu")
		(net 9)
	)
	(segment
		(start 139.319962 146.4645)
		(end 138.642962 147.1415)
		(width 0.254)
		(layer "F.Cu")
		(net 9)
	)
	(segment
		(start 92.592962 155.2665)
		(end 92.592962 155.8565)
		(width 0.2)
		(layer "F.Cu")
		(net 9)
	)
	(segment
		(start 123.592962 120.0915)
		(end 123.487962 119.9865)
		(width 0.254)
		(layer "F.Cu")
		(net 9)
	)
	(segment
		(start 94.567962 149.9415)
		(end 94.567962 148.8005)
		(width 0.2)
		(layer "F.Cu")
		(net 9)
	)
	(segment
		(start 135.03692 160.910458)
		(end 135.137962 160.809416)
		(width 0.4)
		(layer "F.Cu")
		(net 9)
	)
	(segment
		(start 140.917962 151.3415)
		(end 141.342962 151.3415)
		(width 0.254)
		(layer "F.Cu")
		(net 9)
	)
	(segment
		(start 86.320962 147.6395)
		(end 86.320962 147.2665)
		(width 0.127)
		(layer "F.Cu")
		(net 9)
	)
	(segment
		(start 99.817402 146.6165)
		(end 99.417962 146.6165)
		(width 0.2)
		(layer "F.Cu")
		(net 9)
	)
	(segment
		(start 83.563962 149.487498)
		(end 83.563962 150.7075)
		(width 0.2)
		(layer "F.Cu")
		(net 9)
	)
	(segment
		(start 137.792962 163.9915)
		(end 138.217962 164.4165)
		(width 0.2)
		(layer "F.Cu")
		(net 9)
	)
	(segment
		(start 91.242962 156.1265)
		(end 92.322962 156.1265)
		(width 0.2)
		(layer "F.Cu")
		(net 9)
	)
	(segment
		(start 137.192962 163.3915)
		(end 137.217962 163.4165)
		(width 0.254)
		(layer "F.Cu")
		(net 9)
	)
	(segment
		(start 75.742962 157.664293)
		(end 75.742962 156.918707)
		(width 0.15)
		(layer "F.Cu")
		(net 9)
	)
	(segment
		(start 125.3 172.8)
		(end 125.222 172.8)
		(width 0.15)
		(layer "F.Cu")
		(net 9)
	)
	(segment
		(start 133.999962 160.0505)
		(end 133.864962 159.9155)
		(width 0.4)
		(layer "F.Cu")
		(net 9)
	)
	(segment
		(start 135.957962 119.7865)
		(end 135.985962 119.7865)
		(width 0.254)
		(layer "F.Cu")
		(net 9)
	)
	(segment
		(start 75.742962 156.918707)
		(end 75.234462 156.410207)
		(width 0.15)
		(layer "F.Cu")
		(net 9)
	)
	(segment
		(start 139.389962 150.4645)
		(end 140.393962 150.4645)
		(width 0.254)
		(layer "F.Cu")
		(net 9)
	)
	(segment
		(start 133.577962 158.9415)
		(end 133.864962 159.2285)
		(width 0.2)
		(layer "F.Cu")
		(net 9)
	)
	(segment
		(start 75.157962 165.8365)
		(end 75.547962 166.2265)
		(width 0.127)
		(layer "F.Cu")
		(net 9)
	)
	(segment
		(start 131.397962 158.2765)
		(end 132.062962 158.9415)
		(width 0.2)
		(layer "F.Cu")
		(net 9)
	)
	(segment
		(start 74.179272 154.290455)
		(end 71.937962 152.049145)
		(width 0.15)
		(layer "F.Cu")
		(net 9)
	)
	(segment
		(start 97.237962 142.7165)
		(end 97.782962 142.1715)
		(width 0.2)
		(layer "F.Cu")
		(net 9)
	)
	(segment
		(start 123.487962 119.284)
		(end 123.487962 119.8165)
		(width 0.15)
		(layer "F.Cu")
		(net 9)
	)
	(segment
		(start 132.817962 121.6765)
		(end 132.175962 121.6765)
		(width 0.254)
		(layer "F.Cu")
		(net 9)
	)
	(segment
		(start 123.487962 118.509)
		(end 123.487962 119.284)
		(width 0.15)
		(layer "F.Cu")
		(net 9)
	)
	(segment
		(start 138.642962 149.7175)
		(end 139.389962 150.4645)
		(width 0.254)
		(layer "F.Cu")
		(net 9)
	)
	(segment
		(start 92.592962 155.8565)
		(end 92.322962 156.1265)
		(width 0.2)
		(layer "F.Cu")
		(net 9)
	)
	(segment
		(start 123.487962 118.509)
		(end 123.487962 117.9915)
		(width 0.15)
		(layer "F.Cu")
		(net 9)
	)
	(segment
		(start 88.389962 151.6665)
		(end 88.389962 151.2385)
		(width 0.15)
		(layer "F.Cu")
		(net 9)
	)
	(segment
		(start 75.234462 156.410207)
		(end 75.234462 154.747108)
		(width 0.15)
		(layer "F.Cu")
		(net 9)
	)
	(segment
		(start 100.793962 145.63994)
		(end 99.817402 146.6165)
		(width 0.2)
		(layer "F.Cu")
		(net 9)
	)
	(segment
		(start 86.631462 149.9665)
		(end 86.631462 150.13)
		(width 0.2)
		(layer "F.Cu")
		(net 9)
	)
	(segment
		(start 123.487962 119.9865)
		(end 123.487962 119.8165)
		(width 0.254)
		(layer "F.Cu")
		(net 9)
	)
	(segment
		(start 132.175962 121.6765)
		(end 131.317962 120.8185)
		(width 0.254)
		(layer "F.Cu")
		(net 9)
	)
	(segment
		(start 70.186962 147.0255)
		(end 66.757962 147.0255)
		(width 0.15)
		(layer "F.Cu")
		(net 9)
	)
	(segment
		(start 135.137962 160.0505)
		(end 133.999962 160.0505)
		(width 0.4)
		(layer "F.Cu")
		(net 9)
	)
	(segment
		(start 65.799528 168.3)
		(end 66.445 168.3)
		(width 0.2)
		(layer "F.Cu")
		(net 9)
	)
	(segment
		(start 73.902962 162.0665)
		(end 74.817962 162.0665)
		(width 0.2)
		(layer "F.Cu")
		(net 9)
	)
	(segment
		(start 92.332962 156.1165)
		(end 92.332962 156.7665)
		(width 0.2)
		(layer "F.Cu")
		(net 9)
	)
	(segment
		(start 84.564962 151.0885)
		(end 84.392962 150.9165)
		(width 0.15)
		(layer "F.Cu")
		(net 9)
	)
	(segment
		(start 91.417962 149.9665)
		(end 91.267962 149.8165)
		(width 0.127)
		(layer "F.Cu")
		(net 9)
	)
	(segment
		(start 142.680462 151.3415)
		(end 142.992962 151.3415)
		(width 0.127)
		(layer "F.Cu")
		(net 9)
	)
	(segment
		(start 66.757962 147.0255)
		(end 66.562185 147.0255)
		(width 0.15)
		(layer "F.Cu")
		(net 9)
	)
	(segment
		(start 132.817962 121.6765)
		(end 132.817962 122.3165)
		(width 0.254)
		(layer "F.Cu")
		(net 9)
	)
	(segment
		(start 71.937962 148.7765)
		(end 70.186962 147.0255)
		(width 0.15)
		(layer "F.Cu")
		(net 9)
	)
	(segment
		(start 96.961962 142.9925)
		(end 97.237962 142.7165)
		(width 0.2)
		(layer "F.Cu")
		(net 9)
	)
	(segment
		(start 123.592962 120.0915)
		(end 124.142962 120.0915)
		(width 0.254)
		(layer "F.Cu")
		(net 9)
	)
	(segment
		(start 100.793962 144.3425)
		(end 100.793962 145.63994)
		(width 0.2)
		(layer "F.Cu")
		(net 9)
	)
	(segment
		(start 87.392962 150.8865)
		(end 87.787962 150.8865)
		(width 0.15)
		(layer "F.Cu")
		(net 9)
	)
	(segment
		(start 131.317962 120.8185)
		(end 131.317962 124.9165)
		(width 0.254)
		(layer "F.Cu")
		(net 9)
	)
	(segment
		(start 133.864962 159.2285)
		(end 133.864962 159.9155)
		(width 0.2)
		(layer "F.Cu")
		(net 9)
	)
	(segment
		(start 137.217962 163.4165)
		(end 137.792962 163.4165)
		(width 0.254)
		(layer "F.Cu")
		(net 9)
	)
	(segment
		(start 98.622962 142.1715)
		(end 100.793962 144.3425)
		(width 0.2)
		(layer "F.Cu")
		(net 9)
	)
	(segment
		(start 94.576962 147.822255)
		(end 94.576962 148.7915)
		(width 0.2)
		(layer "F.Cu")
		(net 9)
	)
	(segment
		(start 140.393962 150.4645)
		(end 140.393962 150.8175)
		(width 0.254)
		(layer "F.Cu")
		(net 9)
	)
	(segment
		(start 72.387962 166.4365)
		(end 72.387962 166.0365)
		(width 0.127)
		(layer "F.Cu")
		(net 9)
	)
	(segment
		(start 74.817962 162.0165)
		(end 75.667962 161.1665)
		(width 0.15)
		(layer "F.Cu")
		(net 9)
	)
	(segment
		(start 125.222 172.466)
		(end 123.307962 170.551962)
		(width 0.15)
		(layer "F.Cu")
		(net 9)
	)
	(segment
		(start 96.961962 143.7665)
		(end 96.961962 142.9925)
		(width 0.2)
		(layer "F.Cu")
		(net 9)
	)
	(segment
		(start 141.342962 151.3415)
		(end 141.980462 151.3415)
		(width 0.127)
		(layer "F.Cu")
		(net 9)
	)
	(segment
		(start 84.564962 151.5965)
		(end 84.564962 151.0885)
		(width 0.15)
		(layer "F.Cu")
		(net 9)
	)
	(segment
		(start 132.817962 122.3165)
		(end 132.817962 122.9165)
		(width 0.254)
		(layer "F.Cu")
		(net 9)
	)
	(segment
		(start 132.062962 158.9415)
		(end 133.577962 158.9415)
		(width 0.2)
		(layer "F.Cu")
		(net 9)
	)
	(segment
		(start 123.320476 162.7165)
		(end 123.320476 167.853986)
		(width 0.15)
		(layer "F.Cu")
		(net 9)
	)
	(segment
		(start 71.937962 152.049145)
		(end 71.937962 148.7765)
		(width 0.15)
		(layer "F.Cu")
		(net 9)
	)
	(segment
		(start 66.562185 147.0255)
		(end 65.862962 146.326277)
		(width 0.15)
		(layer "F.Cu")
		(net 9)
	)
	(segment
		(start 75.547962 166.2265)
		(end 75.547962 166.7165)
		(width 0.127)
		(layer "F.Cu")
		(net 9)
	)
	(segment
		(start 74.641854 154.511486)
		(end 74.495349 154.482352)
		(width 0.15)
		(layer "F.Cu")
		(net 9)
	)
	(segment
		(start 123.487962 117.81192)
		(end 123.487962 117.9915)
		(width 0.254)
		(layer "F.Cu")
		(net 9)
	)
	(segment
		(start 72.387962 166.0365)
		(end 72.587962 165.8365)
		(width 0.127)
		(layer "F.Cu")
		(net 9)
	)
	(segment
		(start 75.000353 154.512999)
		(end 74.716541 154.512999)
		(width 0.15)
		(layer "F.Cu")
		(net 9)
	)
	(segment
		(start 86.897962 148.2165)
		(end 86.320962 147.6395)
		(width 0.127)
		(layer "F.Cu")
		(net 9)
	)
	(segment
		(start 74.817962 164.1915)
		(end 74.767962 164.2415)
		(width 0.2)
		(layer "F.Cu")
		(net 9)
	)
	(segment
		(start 74.716541 154.512999)
		(end 74.641854 154.511486)
		(width 0.15)
		(layer "F.Cu")
		(net 9)
	)
	(segment
		(start 142.992962 151.3415)
		(end 143.217962 151.5665)
		(width 0.127)
		(layer "F.Cu")
		(net 9)
	)
	(segment
		(start 88.317962 151.1665)
		(end 88.067962 151.1665)
		(width 0.15)
		(layer "F.Cu")
		(net 9)
	)
	(segment
		(start 140.393962 146.4645)
		(end 139.319962 146.4645)
		(width 0.254)
		(layer "F.Cu")
		(net 9)
	)
	(segment
		(start 135.137962 160.809416)
		(end 135.137962 160.0505)
		(width 0.4)
		(layer "F.Cu")
		(net 9)
	)
	(segment
		(start 125.222 172.8)
		(end 125.222 172.466)
		(width 0.15)
		(layer "F.Cu")
		(net 9)
	)
	(segment
		(start 83.317964 149.2415)
		(end 83.563962 149.487498)
		(width 0.2)
		(layer "F.Cu")
		(net 9)
	)
	(segment
		(start 74.23314 154.34221)
		(end 74.179272 154.290455)
		(width 0.15)
		(layer "F.Cu")
		(net 9)
	)
	(segment
		(start 88.389962 151.2385)
		(end 88.317962 151.1665)
		(width 0.15)
		(layer "F.Cu")
		(net 9)
	)
	(segment
		(start 71.317962 168.8415)
		(end 71.317962 167.5365)
		(width 0.2)
		(layer "F.Cu")
		(net 9)
	)
	(segment
		(start 84.183962 150.7075)
		(end 84.392962 150.9165)
		(width 0.2)
		(layer "F.Cu")
		(net 9)
	)
	(segment
		(start 72.587962 165.8365)
		(end 75.157962 165.8365)
		(width 0.127)
		(layer "F.Cu")
		(net 9)
	)
	(segment
		(start 74.495349 154.482352)
		(end 74.357343 154.425194)
		(width 0.15)
		(layer "F.Cu")
		(net 9)
	)
	(segment
		(start 75.667962 157.739293)
		(end 75.742962 157.664293)
		(width 0.15)
		(layer "F.Cu")
		(net 9)
	)
	(segment
		(start 93.969012 147.214305)
		(end 94.576962 147.822255)
		(width 0.2)
		(layer "F.Cu")
		(net 9)
	)
	(via
		(at 80.247962 138.5065)
		(size 0.45)
		(drill 0.1)
		(layers "F.Cu" "B.Cu")
		(net 9)
	)
	(via
		(at 124.333 178.689)
		(size 0.45)
		(drill 0.15)
		(layers "F.Cu" "B.Cu")
		(net 9)
	)
	(via
		(at 115.7 172.814)
		(size 0.45)
		(drill 0.15)
		(layers "F.Cu" "B.Cu")
		(net 9)
	)
	(via
		(at 135.03692 160.910458)
		(size 0.45)
		(drill 0.1)
		(layers "F.Cu" "B.Cu")
		(net 9)
	)
	(via
		(at 73.492962 164.2415)
		(size 0.45)
		(drill 0.1)
		(layers "F.Cu" "B.Cu")
		(net 9)
	)
	(via
		(at 91.417962 149.9665)
		(size 0.45)
		(drill 0.1)
		(layers "F.Cu" "B.Cu")
		(net 9)
	)
	(via
		(at 134.327962 160.0465)
		(size 0.45)
		(drill 0.1)
		(layers "F.Cu" "B.Cu")
		(net 9)
	)
	(via
		(at 137.192962 163.3915)
		(size 0.45)
		(drill 0.1)
		(layers "F.Cu" "B.Cu")
		(net 9)
	)
	(via
		(at 99.417962 146.6165)
		(size 0.45)
		(drill 0.1)
		(layers "F.Cu" "B.Cu")
		(net 9)
	)
	(via
		(at 86.631462 149.9665)
		(size 0.45)
		(drill 0.1)
		(layers "F.Cu" "B.Cu")
		(net 9)
	)
	(via
		(at 74.817962 164.2415)
		(size 0.45)
		(drill 0.1)
		(layers "F.Cu" "B.Cu")
		(net 9)
	)
	(via
		(at 74.167962 164.8415)
		(size 0.45)
		(drill 0.1)
		(layers "F.Cu" "B.Cu")
		(net 9)
	)
	(via
		(at 114.1 172.814)
		(size 0.45)
		(drill 0.15)
		(layers "F.Cu" "B.Cu")
		(net 9)
	)
	(via
		(at 92.592962 155.2665)
		(size 0.45)
		(drill 0.1)
		(layers "F.Cu" "B.Cu")
		(net 9)
	)
	(via
		(at 125.3 172.8)
		(size 0.45)
		(drill 0.15)
		(layers "F.Cu" "B.Cu")
		(net 9)
	)
	(via
		(at 132.817962 122.3165)
		(size 0.45)
		(drill 0.1)
		(layers "F.Cu" "B.Cu")
		(net 9)
	)
	(via
		(at 111.7 172.80275)
		(size 0.45)
		(drill 0.15)
		(layers "F.Cu" "B.Cu")
		(net 9)
	)
	(via
		(at 132.817962 122.9165)
		(size 0.45)
		(drill 0.1)
		(layers "F.Cu" "B.Cu")
		(net 9)
	)
	(via
		(at 135.957962 119.7865)
		(size 0.45)
		(drill 0.1)
		(layers "F.Cu" "B.Cu")
		(net 9)
	)
	(via
		(at 113.3 172.814)
		(size 0.45)
		(drill 0.15)
		(layers "F.Cu" "B.Cu")
		(net 9)
	)
	(via
		(at 71.317962 168.0665)
		(size 0.45)
		(drill 0.1)
		(layers "F.Cu" "B.Cu")
		(net 9)
	)
	(via
		(at 75.767962 173.2165)
		(size 0.45)
		(drill 0.1)
		(layers "F.Cu" "B.Cu")
		(net 9)
	)
	(via
		(at 74.817962 164.8415)
		(size 0.45)
		(drill 0.1)
		(layers "F.Cu" "B.Cu")
		(net 9)
	)
	(via
		(at 106.892962 139.9415)
		(size 0.45)
		(drill 0.1)
		(layers "F.Cu" "B.Cu")
		(net 9)
	)
	(via
		(at 75.517962 164.8415)
		(size 0.45)
		(drill 0.1)
		(layers "F.Cu" "B.Cu")
		(net 9)
	)
	(via
		(at 76.13348 166.734734)
		(size 0.45)
		(drill 0.1)
		(layers "F.Cu" "B.Cu")
		(net 9)
	)
	(via
		(at 100.967962 175.1165)
		(size 0.45)
		(drill 0.1)
		(layers "F.Cu" "B.Cu")
		(net 9)
	)
	(via
		(at 124.142962 120.0915)
		(size 0.45)
		(drill 0.1)
		(layers "F.Cu" "B.Cu")
		(net 9)
	)
	(via
		(at 65.609764 168.489764)
		(size 0.45)
		(drill 0.1)
		(layers "F.Cu" "B.Cu")
		(net 9)
	)
	(via
		(at 112.5 172.814)
		(size 0.45)
		(drill 0.15)
		(layers "F.Cu" "B.Cu")
		(net 9)
	)
	(via
		(at 123.592962 120.0915)
		(size 0.45)
		(drill 0.1)
		(layers "F.Cu" "B.Cu")
		(net 9)
	)
	(via
		(at 93.969012 147.214305)
		(size 0.45)
		(drill 0.1)
		(layers "F.Cu" "B.Cu")
		(net 9)
	)
	(via
		(at 83.317964 149.2415)
		(size 0.45)
		(drill 0.1)
		(layers "F.Cu" "B.Cu")
		(net 9)
	)
	(via
		(at 114.9 172.814)
		(size 0.45)
		(drill 0.15)
		(layers "F.Cu" "B.Cu")
		(net 9)
	)
	(via
		(at 75.517962 164.2415)
		(size 0.45)
		(drill 0.1)
		(layers "F.Cu" "B.Cu")
		(net 9)
	)
	(via
		(at 137.792962 163.4165)
		(size 0.45)
		(drill 0.1)
		(layers "F.Cu" "B.Cu")
		(net 9)
	)
	(via
		(at 73.492962 164.8415)
		(size 0.45)
		(drill 0.1)
		(layers "F.Cu" "B.Cu")
		(net 9)
	)
	(via
		(at 74.167962 164.2415)
		(size 0.45)
		(drill 0.1)
		(layers "F.Cu" "B.Cu")
		(net 9)
	)
	(via
		(at 116.586 173.609)
		(size 0.45)
		(drill 0.15)
		(layers "F.Cu" "B.Cu")
		(net 9)
	)
	(via
		(at 137.392962 153.9415)
		(size 0.45)
		(drill 0.1)
		(layers "F.Cu" "B.Cu")
		(net 9)
	)
	(via
		(at 137.792962 163.9665)
		(size 0.45)
		(drill 0.1)
		(layers "F.Cu" "B.Cu")
		(net 9)
	)
	(via
		(at 143.217962 151.5665)
		(size 0.45)
		(drill 0.1)
		(layers "F.Cu" "B.Cu")
		(net 9)
	)
	(segment
		(start 137.192962 163.3915)
		(end 137.992962 163.3915)
		(width 0.254)
		(layer "B.Cu")
		(net 9)
	)
	(segment
		(start 136.640743 154.693719)
		(end 137.392962 153.9415)
		(width 0.15)
		(layer "B.Cu")
		(net 9)
	)
	(segment
		(start 137.792962 163.4165)
		(end 137.817962 163.3915)
		(width 0.254)
		(layer "B.Cu")
		(net 9)
	)
	(segment
		(start 93.969012 147.214305)
		(end 93.969012 147.75545)
		(width 0.254)
		(layer "B.Cu")
		(net 9)
	)
	(segment
		(start 83.317964 147.816502)
		(end 83.317962 147.8165)
		(width 0.2)
		(layer "B.Cu")
		(net 9)
	)
	(segment
		(start 93.017962 154.8415)
		(end 92.592962 155.2665)
		(width 0.254)
		(layer "B.Cu")
		(net 9)
	)
	(segment
		(start 99.032962 174.3075)
		(end 98.917962 174.1925)
		(width 0.2)
		(layer "B.Cu")
		(net 9)
	)
	(segment
		(start 99.442962 174.3075)
		(end 100.158962 174.3075)
		(width 0.2)
		(layer "B.Cu")
		(net 9)
	)
	(segment
		(start 116.586 174.117)
		(end 116.84 174.371)
		(width 0.254)
		(layer "B.Cu")
		(net 9)
	)
	(segment
		(start 137.817962 163.3915)
		(end 137.992962 163.3915)
		(width 0.254)
		(layer "B.Cu")
		(net 9)
	)
	(segment
		(start 91.757962 149.9665)
		(end 91.417962 149.9665)
		(width 0.254)
		(layer "B.Cu")
		(net 9)
	)
	(segment
		(start 93.017962 154.8415)
		(end 93.017962 152.4165)
		(width 0.254)
		(layer "B.Cu")
		(net 9)
	)
	(segment
		(start 128.782962 156.5415)
		(end 130.630743 154.693719)
		(width 0.15)
		(layer "B.Cu")
		(net 9)
	)
	(segment
		(start 130.630743 154.693719)
		(end 136.640743 154.693719)
		(width 0.15)
		(layer "B.Cu")
		(net 9)
	)
	(segment
		(start 116.84 174.371)
		(end 117.811 174.371)
		(width 0.254)
		(layer "B.Cu")
		(net 9)
	)
	(segment
		(start 137.992962 163.3915)
		(end 139.053462 163.3915)
		(width 0.254)
		(layer "B.Cu")
		(net 9)
	)
	(segment
		(start 116.586 173.228)
		(end 116.586 173.609)
		(width 0.254)
		(layer "B.Cu")
		(net 9)
	)
	(segment
		(start 137.792962 163.9665)
		(end 137.792962 163.4165)
		(width 0.254)
		(layer "B.Cu")
		(net 9)
	)
	(segment
		(start 96.809962 174.1875)
		(end 98.487962 174.1875)
		(width 0.2)
		(layer "B.Cu")
		(net 9)
	)
	(segment
		(start 116.814 173)
		(end 116.586 173.228)
		(width 0.254)
		(layer "B.Cu")
		(net 9)
	)
	(segment
		(start 91.417962 149.9665)
		(end 91.467962 150.0165)
		(width 0.4)
		(layer "B.Cu")
		(net 9)
	)
	(segment
		(start 83.317964 149.2415)
		(end 83.317964 147.816502)
		(width 0.2)
		(layer "B.Cu")
		(net 9)
	)
	(segment
		(start 93.969012 147.75545)
		(end 91.757962 149.9665)
		(width 0.254)
		(layer "B.Cu")
		(net 9)
	)
	(segment
		(start 98.492962 174.1925)
		(end 98.917962 174.1925)
		(width 0.2)
		(layer "B.Cu")
		(net 9)
	)
	(segment
		(start 124.344 178.7)
		(end 124.333 178.689)
		(width 0.254)
		(layer "B.Cu")
		(net 9)
	)
	(segment
		(start 99.442962 174.3075)
		(end 99.032962 174.3075)
		(width 0.2)
		(layer "B.Cu")
		(net 9)
	)
	(segment
		(start 116.586 173.609)
		(end 116.586 174.117)
		(width 0.254)
		(layer "B.Cu")
		(net 9)
	)
	(segment
		(start 83.317962 147.8165)
		(end 83.317962 147.3665)
		(width 0.2)
		(layer "B.Cu")
		(net 9)
	)
	(segment
		(start 124.901 178.7)
		(end 124.344 178.7)
		(width 0.254)
		(layer "B.Cu")
		(net 9)
	)
	(segment
		(start 117.32 173)
		(end 116.814 173)
		(width 0.254)
		(layer "B.Cu")
		(net 9)
	)
	(segment
		(start 80.247962 144.2965)
		(end 80.247962 138.5065)
		(width 0.2)
		(layer "B.Cu")
		(net 9)
	)
	(segment
		(start 83.317962 147.3665)
		(end 80.247962 144.2965)
		(width 0.2)
		(layer "B.Cu")
		(net 9)
	)
	(segment
		(start 100.158962 174.3075)
		(end 100.967962 175.1165)
		(width 0.2)
		(layer "B.Cu")
		(net 9)
	)
	(segment
		(start 104.642962 139.9415)
		(end 106.892962 139.9415)
		(width 0.254)
		(layer "In2.Cu")
		(net 9)
	)
	(segment
		(start 83.317964 149.2415)
		(end 83.292964 149.2165)
		(width 0.4)
		(layer "In2.Cu")
		(net 9)
	)
	(segment
		(start 80.247962 138.168684)
		(end 77.417962 135.338684)
		(width 0.15)
		(layer "In2.Cu")
		(net 9)
	)
	(segment
		(start 76.392962 122.829393)
		(end 74.775069 121.2115)
		(width 0.15)
		(layer "In2.Cu")
		(net 9)
	)
	(segment
		(start 113.3 172.814)
		(end 112.5 172.814)
		(width 0.6)
		(layer "In2.Cu")
		(net 9)
	)
	(segment
		(start 70.448512 117.711)
		(end 61.631512 117.711)
		(width 0.15)
		(layer "In2.Cu")
		(net 9)
	)
	(segment
		(start 99.417962 145.1665)
		(end 99.417962 145.55)
		(width 0.254)
		(layer "In2.Cu")
		(net 9)
	)
	(segment
		(start 77.417962 135.338684)
		(end 77.417962 129.5915)
		(width 0.15)
		(layer "In2.Cu")
		(net 9)
	)
	(segment
		(start 83.317964 149.2415)
		(end 84.042964 149.9665)
		(width 0.4)
		(layer "In2.Cu")
		(net 9)
	)
	(segment
		(start 75.467962 164.1415)
		(end 74.817962 164.7915)
		(width 0.4)
		(layer "In2.Cu")
		(net 9)
	)
	(segment
		(start 84.042964 149.9665)
		(end 91.417962 149.9665)
		(width 0.4)
		(layer "In2.Cu")
		(net 9)
	)
	(segment
		(start 74.775069 121.2115)
		(end 73.949012 121.2115)
		(width 0.15)
		(layer "In2.Cu")
		(net 9)
	)
	(segment
		(start 112.5 172.814)
		(end 111.71125 172.814)
		(width 0.6)
		(layer "In2.Cu")
		(net 9)
	)
	(segment
		(start 86.631462 149.9665)
		(end 86.942962 149.9665)
		(width 0.4)
		(layer "In2.Cu")
		(net 9)
	)
	(segment
		(start 76.392962 128.5665)
		(end 76.392962 122.829393)
		(width 0.15)
		(layer "In2.Cu")
		(net 9)
	)
	(segment
		(start 92.592962 155.2665)
		(end 92.592962 150.21329)
		(width 0.4)
		(layer "In2.Cu")
		(net 9)
	)
	(segment
		(start 80.247962 138.5065)
		(end 80.247962 138.168684)
		(width 0.15)
		(layer "In2.Cu")
		(net 9)
	)
	(segment
		(start 61.631512 117.711)
		(end 60.669512 118.673)
		(width 0.15)
		(layer "In2.Cu")
		(net 9)
	)
	(segment
		(start 92.540172 150.13829)
		(end 94.446172 150.13829)
		(width 0.254)
		(layer "In2.Cu")
		(net 9)
	)
	(segment
		(start 99.117231 145.467231)
		(end 104.642962 139.9415)
		(width 0.254)
		(layer "In2.Cu")
		(net 9)
	)
	(segment
		(start 77.417962 129.5915)
		(end 76.392962 128.5665)
		(width 0.15)
		(layer "In2.Cu")
		(net 9)
	)
	(segment
		(start 115.7 172.814)
		(end 114.9 172.814)
		(width 0.6)
		(layer "In2.Cu")
		(net 9)
	)
	(segment
		(start 73.949012 121.2115)
		(end 71.410512 118.673)
		(width 0.15)
		(layer "In2.Cu")
		(net 9)
	)
	(segment
		(start 99.417962 145.55)
		(end 99.417962 146.6165)
		(width 0.254)
		(layer "In2.Cu")
		(net 9)
	)
	(segment
		(start 111.71125 172.814)
		(end 111.7 172.80275)
		(width 0.6)
		(layer "In2.Cu")
		(net 9)
	)
	(segment
		(start 92.368382 149.9665)
		(end 92.540172 150.13829)
		(width 0.254)
		(layer "In2.Cu")
		(net 9)
	)
	(segment
		(start 91.417962 149.9665)
		(end 92.368382 149.9665)
		(width 0.254)
		(layer "In2.Cu")
		(net 9)
	)
	(segment
		(start 99.2 145.55)
		(end 99.117231 145.467231)
		(width 0.254)
		(layer "In2.Cu")
		(net 9)
	)
	(segment
		(start 71.410512 118.673)
		(end 70.448512 117.711)
		(width 0.15)
		(layer "In2.Cu")
		(net 9)
	)
	(segment
		(start 83.292964 149.2165)
		(end 77.137962 149.2165)
		(width 0.4)
		(layer "In2.Cu")
		(net 9)
	)
	(segment
		(start 92.590962 150.21129)
		(end 92.509934 150.21129)
		(width 0.4)
		(layer "In2.Cu")
		(net 9)
	)
	(segment
		(start 94.446172 150.13829)
		(end 99.117231 145.467231)
		(width 0.254)
		(layer "In2.Cu")
		(net 9)
	)
	(segment
		(start 92.509934 150.21129)
		(end 92.265144 149.9665)
		(width 0.4)
		(layer "In2.Cu")
		(net 9)
	)
	(segment
		(start 114.1 172.814)
		(end 113.3 172.814)
		(width 0.6)
		(layer "In2.Cu")
		(net 9)
	)
	(segment
		(start 114.9 172.814)
		(end 114.1 172.814)
		(width 0.6)
		(layer "In2.Cu")
		(net 9)
	)
	(segment
		(start 75.467962 150.8865)
		(end 75.467962 164.1415)
		(width 0.4)
		(layer "In2.Cu")
		(net 9)
	)
	(segment
		(start 99.417962 145.55)
		(end 99.2 145.55)
		(width 0.254)
		(layer "In2.Cu")
		(net 9)
	)
	(segment
		(start 92.592962 150.21329)
		(end 92.590962 150.21129)
		(width 0.4)
		(layer "In2.Cu")
		(net 9)
	)
	(segment
		(start 77.137962 149.2165)
		(end 75.467962 150.8865)
		(width 0.4)
		(layer "In2.Cu")
		(net 9)
	)
	(segment
		(start 92.265144 149.9665)
		(end 91.417962 149.9665)
		(width 0.4)
		(layer "In2.Cu")
		(net 9)
	)
	(segment
		(start 115.68875 172.80275)
		(end 111.7 172.80275)
		(width 0.75)
		(layer "In3.Cu")
		(net 9)
	)
	(segment
		(start 115.7 172.814)
		(end 115.68875 172.80275)
		(width 0.75)
		(layer "In3.Cu")
		(net 9)
	)
	(segment
		(start 77.044462 161.715)
		(end 77.042962 161.7165)
		(width 0.2)
		(layer "F.Cu")
		(net 10)
	)
	(segment
		(start 75.067962 150.2915)
		(end 75.067962 150.367962)
		(width 0.15)
		(layer "F.Cu")
		(net 10)
	)
	(segment
		(start 77.192962 161.316)
		(end 77.067462 161.316)
		(width 0.2)
		(layer "F.Cu")
		(net 10)
	)
	(segment
		(start 78.473961 160.117)
		(end 77.043462 160.117)
		(width 0.2)
		(layer "F.Cu")
		(net 10)
	)
	(segment
		(start 106.367962 149.416)
		(end 105.593962 149.416)
		(width 0.254)
		(layer "F.Cu")
		(net 10)
	)
	(segment
		(start 77.042962 161.4665)
		(end 77.042962 161.7165)
		(width 0.2)
		(layer "F.Cu")
		(net 10)
	)
	(segment
		(start 75.017962 150.2915)
		(end 75.017962 149.2915)
		(width 0.15)
		(layer "F.Cu")
		(net 10)
	)
	(segment
		(start 138.412962 160.9165)
		(end 138.412962 161.773804)
		(width 0.4)
		(layer "F.Cu")
		(net 10)
	)
	(segment
		(start 138.032962 158.9565)
		(end 136.657962 158.9565)
		(width 0.2)
		(layer "F.Cu")
		(net 10)
	)
	(segment
		(start 136.657962 158.9565)
		(end 135.832962 158.1315)
		(width 0.2)
		(layer "F.Cu")
		(net 10)
	)
	(segment
		(start 77.167462 161.316)
		(end 77.042962 161.1915)
		(width 0.2)
		(layer "F.Cu")
		(net 10)
	)
	(segment
		(start 74.767962 159.6665)
		(end 74.002962 159.6665)
		(width 0.2)
		(layer "F.Cu")
		(net 10)
	)
	(segment
		(start 77.043462 160.917)
		(end 77.042962 160.9165)
		(width 0.2)
		(layer "F.Cu")
		(net 10)
	)
	(segment
		(start 78.473961 160.917)
		(end 77.043462 160.917)
		(width 0.2)
		(layer "F.Cu")
		(net 10)
	)
	(segment
		(start 102.167962 131.9915)
		(end 102.616962 131.5425)
		(width 0.254)
		(layer "F.Cu")
		(net 10)
	)
	(segment
		(start 77.043462 160.117)
		(end 77.042962 160.1165)
		(width 0.2)
		(layer "F.Cu")
		(net 10)
	)
	(segment
		(start 77.192962 161.316)
		(end 77.167462 161.316)
		(width 0.2)
		(layer "F.Cu")
		(net 10)
	)
	(segment
		(start 104.917962 154.267)
		(end 104.917962 154.7415)
		(width 0.254)
		(layer "F.Cu")
		(net 10)
	)
	(segment
		(start 77.042962 160.6415)
		(end 77.042962 161.1915)
		(width 0.2)
		(layer "F.Cu")
		(net 10)
	)
	(segment
		(start 104.705462 150.3045)
		(end 104.705462 150.779)
		(width 0.254)
		(layer "F.Cu")
		(net 10)
	)
	(segment
		(start 104.917962 154.7415)
		(end 103.918462 155.741)
		(width 0.254)
		(layer "F.Cu")
		(net 10)
	)
	(segment
		(start 103.817962 130.2765)
		(end 103.277962 130.8165)
		(width 0.2)
		(layer "F.Cu")
		(net 10)
	)
	(segment
		(start 103.742962 151.541)
		(end 103.742962 152.1915)
		(width 0.254)
		(layer "F.Cu")
		(net 10)
	)
	(segment
		(start 78.473961 160.516)
		(end 77.192962 160.516)
		(width 0.2)
		(layer "F.Cu")
		(net 10)
	)
	(segment
		(start 75.017962 149.2915)
		(end 74.817962 149.0915)
		(width 0.15)
		(layer "F.Cu")
		(net 10)
	)
	(segment
		(start 133.041462 151.384261)
		(end 133.297223 151.1285)
		(width 0.127)
		(layer "F.Cu")
		(net 10)
	)
	(segment
		(start 77.042962 161.2915)
		(end 77.042962 161.4665)
		(width 0.2)
		(layer "F.Cu")
		(net 10)
	)
	(segment
		(start 138.264962 159.1885)
		(end 138.032962 158.9565)
		(width 0.2)
		(layer "F.Cu")
		(net 10)
	)
	(segment
		(start 103.277962 130.8165)
		(end 102.616962 130.8165)
		(width 0.2)
		(layer "F.Cu")
		(net 10)
	)
	(segment
		(start 78.473961 161.316)
		(end 77.192962 161.316)
		(width 0.2)
		(layer "F.Cu")
		(net 10)
	)
	(segment
		(start 77.042962 160.1165)
		(end 77.042962 160.3915)
		(width 0.2)
		(layer "F.Cu")
		(net 10)
	)
	(segment
		(start 103.543462 151.541)
		(end 102.717962 152.3665)
		(width 0.254)
		(layer "F.Cu")
		(net 10)
	)
	(segment
		(start 101.676962 131.9915)
		(end 102.167962 131.9915)
		(width 0.254)
		(layer "F.Cu")
		(net 10)
	)
	(segment
		(start 136.442962 150.4645)
		(end 136.442962 149.9645)
		(width 0.254)
		(layer "F.Cu")
		(net 10)
	)
	(segment
		(start 77.167462 160.516)
		(end 77.042962 160.3915)
		(width 0.2)
		(layer "F.Cu")
		(net 10)
	)
	(segment
		(start 106.392962 153.641)
		(end 105.543962 153.641)
		(width 0.254)
		(layer "F.Cu")
		(net 10)
	)
	(segment
		(start 102.616962 131.5425)
		(end 102.616962 130.8165)
		(width 0.254)
		(layer "F.Cu")
		(net 10)
	)
	(segment
		(start 138.264962 159.9155)
		(end 138.264962 160.7685)
		(width 0.4)
		(layer "F.Cu")
		(net 10)
	)
	(segment
		(start 104.342962 156.3165)
		(end 104.342962 156.291)
		(width 0.254)
		(layer "F.Cu")
		(net 10)
	)
	(segment
		(start 136.180962 151.1285)
		(end 136.442962 150.8665)
		(width 0.254)
		(layer "F.Cu")
		(net 10)
	)
	(segment
		(start 105.543962 153.641)
		(end 104.917962 154.267)
		(width 0.254)
		(layer "F.Cu")
		(net 10)
	)
	(segment
		(start 78.473961 162.117)
		(end 77.192962 162.117)
		(width 0.2)
		(layer "F.Cu")
		(net 10)
	)
	(segment
		(start 137.520266 162.6665)
		(end 137.122962 162.6665)
		(width 0.4)
		(layer "F.Cu")
		(net 10)
	)
	(segment
		(start 66.45 160.85)
		(end 66.45 167.27)
		(width 0.2)
		(layer "F.Cu")
		(net 10)
	)
	(segment
		(start 101.652962 132.9415)
		(end 101.652962 132.0155)
		(width 0.254)
		(layer "F.Cu")
		(net 10)
	)
	(segment
		(start 66.45 167.27)
		(end 66.445 167.275)
		(width 0.2)
		(layer "F.Cu")
		(net 10)
	)
	(segment
		(start 77.192962 162.1165)
		(end 77.042962 161.9665)
		(width 0.2)
		(layer "F.Cu")
		(net 10)
	)
	(segment
		(start 102.692962 156.2665)
		(end 103.042962 156.2665)
		(width 0.254)
		(layer "F.Cu")
		(net 10)
	)
	(segment
		(start 75.55 150.85)
		(end 75.55 151.909462)
		(width 0.15)
		(layer "F.Cu")
		(net 10)
	)
	(segment
		(start 77.067462 161.316)
		(end 77.042962 161.2915)
		(width 0.2)
		(layer "F.Cu")
		(net 10)
	)
	(segment
		(start 138.412962 161.773804)
		(end 137.520266 162.6665)
		(width 0.4)
		(layer "F.Cu")
		(net 10)
	)
	(segment
		(start 104.342962 156.291)
		(end 103.792962 155.741)
		(width 0.254)
		(layer "F.Cu")
		(net 10)
	)
	(segment
		(start 136.442962 150.4645)
		(end 136.442962 150.8665)
		(width 0.254)
		(layer "F.Cu")
		(net 10)
	)
	(segment
		(start 77.168462 160.516)
		(end 77.042962 160.6415)
		(width 0.2)
		(layer "F.Cu")
		(net 10)
	)
	(segment
		(start 135.832962 158.1315)
		(end 135.137962 158.1315)
		(width 0.2)
		(layer "F.Cu")
		(net 10)
	)
	(segment
		(start 136.537962 163.6115)
		(end 136.917962 163.9915)
		(width 0.4)
		(layer "F.Cu")
		(net 10)
	)
	(segment
		(start 139.517962 159.9755)
		(end 138.324962 159.9755)
		(width 0.4)
		(layer "F.Cu")
		(net 10)
	)
	(segment
		(start 101.792962 129.8915)
		(end 101.392962 129.4915)
		(width 0.4)
		(layer "F.Cu")
		(net 10)
	)
	(segment
		(start 77.192962 160.516)
		(end 77.067462 160.516)
		(width 0.2)
		(layer "F.Cu")
		(net 10)
	)
	(segment
		(start 103.742962 152.1915)
		(end 103.917962 152.3665)
		(width 0.254)
		(layer "F.Cu")
		(net 10)
	)
	(segment
		(start 136.092962 163.9915)
		(end 136.157962 163.9915)
		(width 0.4)
		(layer "F.Cu")
		(net 10)
	)
	(segment
		(start 77.192962 162.117)
		(end 77.192962 162.1165)
		(width 0.2)
		(layer "F.Cu")
		(net 10)
	)
	(segment
		(start 77.067462 160.516)
		(end 77.042962 160.4915)
		(width 0.2)
		(layer "F.Cu")
		(net 10)
	)
	(segment
		(start 74.817962 148.2665)
		(end 74.817962 149.0915)
		(width 0.15)
		(layer "F.Cu")
		(net 10)
	)
	(segment
		(start 134.942962 151.1285)
		(end 134.455462 151.1285)
		(width 0.127)
		(layer "F.Cu")
		(net 10)
	)
	(segment
		(start 137.122962 162.6665)
		(end 136.537962 163.2515)
		(width 0.4)
		(layer "F.Cu")
		(net 10)
	)
	(segment
		(start 75.55 151.909462)
		(end 74.817962 152.6415)
		(width 0.15)
		(layer "F.Cu")
		(net 10)
	)
	(segment
		(start 133.297223 151.1285)
		(end 133.680462 151.1285)
		(width 0.127)
		(layer "F.Cu")
		(net 10)
	)
	(segment
		(start 102.616962 130.7155)
		(end 101.792962 129.8915)
		(width 0.4)
		(layer "F.Cu")
		(net 10)
	)
	(segment
		(start 138.264962 160.7685)
		(end 138.412962 160.9165)
		(width 0.4)
		(layer "F.Cu")
		(net 10)
	)
	(segment
		(start 136.157962 163.9915)
		(end 136.537962 163.6115)
		(width 0.4)
		(layer "F.Cu")
		(net 10)
	)
	(segment
		(start 138.324962 159.9755)
		(end 138.264962 159.9155)
		(width 0.4)
		(layer "F.Cu")
		(net 10)
	)
	(segment
		(start 136.537962 163.2515)
		(end 136.537962 163.6115)
		(width 0.4)
		(layer "F.Cu")
		(net 10)
	)
	(segment
		(start 82.187962 120.7415)
		(end 82.187962 121.3)
		(width 0.254)
		(layer "F.Cu")
		(net 10)
	)
	(segment
		(start 77.192962 160.516)
		(end 77.168462 160.516)
		(width 0.2)
		(layer "F.Cu")
		(net 10)
	)
	(segment
		(start 78.473961 161.715)
		(end 77.044462 161.715)
		(width 0.2)
		(layer "F.Cu")
		(net 10)
	)
	(segment
		(start 77.042962 160.4915)
		(end 77.042962 160.6415)
		(width 0.2)
		(layer "F.Cu")
		(net 10)
	)
	(segment
		(start 105.593962 149.416)
		(end 104.705462 150.3045)
		(width 0.254)
		(layer "F.Cu")
		(net 10)
	)
	(segment
		(start 77.192962 160.516)
		(end 77.167462 160.516)
		(width 0.2)
		(layer "F.Cu")
		(net 10)
	)
	(segment
		(start 75.067962 150.367962)
		(end 75.55 150.85)
		(width 0.15)
		(layer "F.Cu")
		(net 10)
	)
	(segment
		(start 77.192962 161.316)
		(end 77.192962 161.3165)
		(width 0.2)
		(layer "F.Cu")
		(net 10)
	)
	(segment
		(start 69.242962 160.5915)
		(end 66.7085 160.5915)
		(width 0.2)
		(layer "F.Cu")
		(net 10)
	)
	(segment
		(start 77.042962 160.3915)
		(end 77.042962 160.4915)
		(width 0.2)
		(layer "F.Cu")
		(net 10)
	)
	(segment
		(start 103.507462 155.741)
		(end 102.542962 154.7765)
		(width 0.254)
		(layer "F.Cu")
		(net 10)
	)
	(segment
		(start 133.767962 121.6765)
		(end 133.767962 122.2915)
		(width 0.254)
		(layer "F.Cu")
		(net 10)
	)
	(segment
		(start 103.042962 156.2665)
		(end 103.568462 155.741)
		(width 0.254)
		(layer "F.Cu")
		(net 10)
	)
	(segment
		(start 134.942962 151.1285)
		(end 136.180962 151.1285)
		(width 0.254)
		(layer "F.Cu")
		(net 10)
	)
	(segment
		(start 77.042962 161.9665)
		(end 77.042962 161.7165)
		(width 0.2)
		(layer "F.Cu")
		(net 10)
	)
	(segment
		(start 104.705462 150.779)
		(end 103.943462 151.541)
		(width 0.254)
		(layer "F.Cu")
		(net 10)
	)
	(segment
		(start 66.7085 160.5915)
		(end 66.45 160.85)
		(width 0.2)
		(layer "F.Cu")
		(net 10)
	)
	(segment
		(start 133.767962 122.2915)
		(end 133.767962 122.9165)
		(width 0.254)
		(layer "F.Cu")
		(net 10)
	)
	(segment
		(start 133.692962 151.1415)
		(end 134.467962 151.1415)
		(width 0.127)
		(layer "F.Cu")
		(net 10)
	)
	(segment
		(start 77.042962 161.1915)
		(end 77.042962 161.2915)
		(width 0.2)
		(layer "F.Cu")
		(net 10)
	)
	(segment
		(start 77.192962 161.3165)
		(end 77.042962 161.4665)
		(width 0.2)
		(layer "F.Cu")
		(net 10)
	)
	(segment
		(start 138.264962 159.9155)
		(end 138.264962 159.1885)
		(width 0.2)
		(layer "F.Cu")
		(net 10)
	)
	(via
		(at 70.642962 159.9915)
		(size 0.45)
		(drill 0.1)
		(layers "F.Cu" "B.Cu")
		(net 10)
	)
	(via
		(at 136.917962 163.9915)
		(size 0.45)
		(drill 0.1)
		(layers "F.Cu" "B.Cu")
		(net 10)
	)
	(via
		(at 82.187962 121.3)
		(size 0.45)
		(drill 0.1)
		(layers "F.Cu" "B.Cu")
		(net 10)
	)
	(via
		(at 133.767962 122.9165)
		(size 0.45)
		(drill 0.1)
		(layers "F.Cu" "B.Cu")
		(net 10)
	)
	(via
		(at 71.367962 158.1915)
		(size 0.45)
		(drill 0.1)
		(layers "F.Cu" "B.Cu")
		(net 10)
	)
	(via
		(at 102.467962 175.1165)
		(size 0.45)
		(drill 0.1)
		(layers "F.Cu" "B.Cu")
		(net 10)
	)
	(via
		(at 102.717962 152.3665)
		(size 0.45)
		(drill 0.1)
		(layers "F.Cu" "B.Cu")
		(net 10)
	)
	(via
		(at 136.092962 163.9915)
		(size 0.45)
		(drill 0.1)
		(layers "F.Cu" "B.Cu")
		(net 10)
	)
	(via
		(at 69.242962 160.0265)
		(size 0.45)
		(drill 0.1)
		(layers "F.Cu" "B.Cu")
		(free yes)
		(net 10)
	)
	(via
		(at 69.942962 159.9915)
		(size 0.45)
		(drill 0.1)
		(layers "F.Cu" "B.Cu")
		(free yes)
		(net 10)
	)
	(via
		(at 69.267962 158.1915)
		(size 0.45)
		(drill 0.1)
		(layers "F.Cu" "B.Cu")
		(free yes)
		(net 10)
	)
	(via
		(at 74.767962 159.6665)
		(size 0.5)
		(drill 0.15)
		(layers "F.Cu" "B.Cu")
		(net 10)
	)
	(via
		(at 70.642962 160.5915)
		(size 0.45)
		(drill 0.1)
		(layers "F.Cu" "B.Cu")
		(net 10)
	)
	(via
		(at 74.817962 149.0915)
		(size 0.45)
		(drill 0.1)
		(layers "F.Cu" "B.Cu")
		(net 10)
	)
	(via
		(at 70.667962 157.5915)
		(size 0.45)
		(drill 0.1)
		(layers "F.Cu" "B.Cu")
		(net 10)
	)
	(via
		(at 77.042962 161.7165)
		(size 0.45)
		(drill 0.1)
		(layers "F.Cu" "B.Cu")
		(net 10)
	)
	(via
		(at 102.692962 156.2665)
		(size 0.45)
		(drill 0.1)
		(layers "F.Cu" "B.Cu")
		(net 10)
	)
	(via
		(at 104.342962 156.3165)
		(size 0.45)
		(drill 0.1)
		(layers "F.Cu" "B.Cu")
		(net 10)
	)
	(via
		(at 72.042962 159.9915)
		(size 0.45)
		(drill 0.1)
		(layers "F.Cu" "B.Cu")
		(free yes)
		(net 10)
	)
	(via
		(at 69.942962 160.5915)
		(size 0.45)
		(drill 0.1)
		(layers "F.Cu" "B.Cu")
		(net 10)
	)
	(via
		(at 71.342962 159.9915)
		(size 0.45)
		(drill 0.1)
		(layers "F.Cu" "B.Cu")
		(net 10)
	)
	(via
		(at 69.242962 160.5915)
		(size 0.45)
		(drill 0.1)
		(layers "F.Cu" "B.Cu")
		(free yes)
		(net 10)
	)
	(via
		(at 101.792962 129.8915)
		(size 0.45)
		(drill 0.1)
		(layers "F.Cu" "B.Cu")
		(net 10)
	)
	(via
		(at 69.967962 158.1915)
		(size 0.45)
		(drill 0.1)
		(layers "F.Cu" "B.Cu")
		(net 10)
	)
	(via
		(at 133.767962 122.2915)
		(size 0.45)
		(drill 0.1)
		(layers "F.Cu" "B.Cu")
		(net 10)
	)
	(via
		(at 133.041462 151.384261)
		(size 0.45)
		(drill 0.1)
		(layers "F.Cu" "B.Cu")
		(net 10)
	)
	(via
		(at 77.042962 160.1165)
		(size 0.45)
		(drill 0.1)
		(layers "F.Cu" "B.Cu")
		(net 10)
	)
	(via
		(at 72.067962 157.5915)
		(size 0.45)
		(drill 0.1)
		(layers "F.Cu" "B.Cu")
		(free yes)
		(net 10)
	)
	(via
		(at 72.067962 158.1915)
		(size 0.45)
		(drill 0.1)
		(layers "F.Cu" "B.Cu")
		(free yes)
		(net 10)
	)
	(via
		(at 70.667962 158.1915)
		(size 0.45)
		(drill 0.1)
		(layers "F.Cu" "B.Cu")
		(net 10)
	)
	(via
		(at 101.392962 129.4915)
		(size 0.45)
		(drill 0.1)
		(layers "F.Cu" "B.Cu")
		(net 10)
	)
	(via
		(at 69.267962 157.5915)
		(size 0.45)
		(drill 0.1)
		(layers "F.Cu" "B.Cu")
		(free yes)
		(net 10)
	)
	(via
		(at 114.347962 114.9265)
		(size 0.45)
		(drill 0.1)
		(layers "F.Cu" "B.Cu")
		(net 10)
	)
	(via
		(at 71.367962 157.5915)
		(size 0.45)
		(drill 0.1)
		(layers "F.Cu" "B.Cu")
		(net 10)
	)
	(via
		(at 69.967962 157.5915)
		(size 0.45)
		(drill 0.1)
		(layers "F.Cu" "B.Cu")
		(free yes)
		(net 10)
	)
	(via
		(at 71.342962 160.5915)
		(size 0.45)
		(drill 0.1)
		(layers "F.Cu" "B.Cu")
		(net 10)
	)
	(via
		(at 77.042962 160.9165)
		(size 0.45)
		(drill 0.1)
		(layers "F.Cu" "B.Cu")
		(net 10)
	)
	(via
		(at 102.992962 175.1165)
		(size 0.45)
		(drill 0.1)
		(layers "F.Cu" "B.Cu")
		(net 10)
	)
	(via
		(at 72.042962 160.5915)
		(size 0.45)
		(drill 0.1)
		(layers "F.Cu" "B.Cu")
		(free yes)
		(net 10)
	)
	(via
		(at 103.917962 152.3665)
		(size 0.45)
		(drill 0.1)
		(layers "F.Cu" "B.Cu")
		(net 10)
	)
	(segment
		(start 102.467962 175.1165)
		(end 102.992962 175.1165)
		(width 0.254)
		(layer "B.Cu")
		(net 10)
	)
	(segment
		(start 102.467962 175.1165)
		(end 102.467962 175.8565)
		(width 0.254)
		(layer "B.Cu")
		(net 10)
	)
	(segment
		(start 114.347962 114.9265)
		(end 114.327962 114.9465)
		(width 0.15)
		(layer "B.Cu")
		(net 10)
	)
	(segment
		(start 102.467962 175.8565)
		(end 101.867962 176.4565)
		(width 0.254)
		(layer "B.Cu")
		(net 10)
	)
	(segment
		(start 101.867962 176.4565)
		(end 101.867962 176.4965)
		(width 0.254)
		(layer "B.Cu")
		(net 10)
	)
	(segment
		(start 114.327962 115.7105)
		(end 114.658962 116.0415)
		(width 0.15)
		(layer "B.Cu")
		(net 10)
	)
	(segment
		(start 114.327962 114.9465)
		(end 114.327962 115.7105)
		(width 0.15)
		(layer "B.Cu")
		(net 10)
	)
	(segment
		(start 78.473961 156.917)
		(end 77.881221 156.917)
		(width 0.21)
		(layer "F.Cu")
		(net 11)
	)
	(segment
		(start 77.881221 156.917)
		(end 77.706867 157.091354)
		(width 0.21)
		(layer "F.Cu")
		(net 11)
	)
	(segment
		(start 124.277962 166.9165)
		(end 124.677962 166.5165)
		(width 0.21)
		(layer "F.Cu")
		(net 11)
	)
	(segment
		(start 124.677962 166.5165)
		(end 125.417962 166.5165)
		(width 0.21)
		(layer "F.Cu")
		(net 11)
	)
	(via
		(at 77.706867 157.091354)
		(size 0.45)
		(drill 0.1)
		(layers "F.Cu" "B.Cu")
		(net 11)
	)
	(via
		(at 125.417962 166.5165)
		(size 0.45)
		(drill 0.1)
		(layers "F.Cu" "B.Cu")
		(net 11)
	)
	(segment
		(start 129.608711 166.4915)
		(end 128.944316 166.4915)
		(width 0.21)
		(layer "B.Cu")
		(net 11)
	)
	(segment
		(start 124.7655 166.5345)
		(end 120.8 170.5)
		(width 0.21)
		(layer "B.Cu")
		(net 11)
	)
	(segment
		(start 128.944316 166.4915)
		(end 125.442962 166.4915)
		(width 0.21)
		(layer "B.Cu")
		(net 11)
	)
	(segment
		(start 135.267962 166.4915)
		(end 131.738711 166.4915)
		(width 0.21)
		(layer "B.Cu")
		(net 11)
	)
	(segment
		(start 130.848711 166.6715)
		(end 130.848711 166.4915)
		(width 0.21)
		(layer "B.Cu")
		(net 11)
	)
	(segment
		(start 120.8 170.5)
		(end 106.026462 170.5)
		(width 0.21)
		(layer "B.Cu")
		(net 11)
	)
	(segment
		(start 79.472962 161.8465)
		(end 78.192962 160.5665)
		(width 0.21)
		(layer "B.Cu")
		(net 11)
	)
	(segment
		(start 130.848711 166.4915)
		(end 130.848711 166.3115)
		(width 0.21)
		(layer "B.Cu")
		(net 11)
	)
	(segment
		(start 97.372962 161.8465)
		(end 79.472962 161.8465)
		(width 0.21)
		(layer "B.Cu")
		(net 11)
	)
	(segment
		(start 78.192962 160.5665)
		(end 78.192962 157.577449)
		(width 0.21)
		(layer "B.Cu")
		(net 11)
	)
	(segment
		(start 125.417962 166.5165)
		(end 125.399962 166.5345)
		(width 0.21)
		(layer "B.Cu")
		(net 11)
	)
	(segment
		(start 106.026462 170.5)
		(end 97.372962 161.8465)
		(width 0.21)
		(layer "B.Cu")
		(net 11)
	)
	(segment
		(start 78.192962 157.577449)
		(end 77.706867 157.091354)
		(width 0.21)
		(layer "B.Cu")
		(net 11)
	)
	(segment
		(start 131.378711 166.8515)
		(end 131.028711 166.8515)
		(width 0.21)
		(layer "B.Cu")
		(net 11)
	)
	(segment
		(start 125.442962 166.4915)
		(end 125.417962 166.5165)
		(width 0.21)
		(layer "B.Cu")
		(net 11)
	)
	(segment
		(start 125.399962 166.5345)
		(end 124.7655 166.5345)
		(width 0.21)
		(layer "B.Cu")
		(net 11)
	)
	(segment
		(start 136.168962 165.5905)
		(end 135.267962 166.4915)
		(width 0.21)
		(layer "B.Cu")
		(net 11)
	)
	(segment
		(start 129.958711 166.4915)
		(end 129.608711 166.4915)
		(width 0.21)
		(layer "B.Cu")
		(net 11)
	)
	(segment
		(start 130.668711 166.1315)
		(end 130.318711 166.1315)
		(width 0.21)
		(layer "B.Cu")
		(net 11)
	)
	(segment
		(start 139.054462 165.5905)
		(end 136.168962 165.5905)
		(width 0.21)
		(layer "B.Cu")
		(net 11)
	)
	(arc
		(start 131.028711 166.8515)
		(mid 130.901432 166.798779)
		(end 130.848711 166.6715)
		(width 0.21)
		(layer "B.Cu")
		(net 11)
	)
	(arc
		(start 131.558711 166.6715)
		(mid 131.50599 166.798779)
		(end 131.378711 166.8515)
		(width 0.21)
		(layer "B.Cu")
		(net 11)
	)
	(arc
		(start 130.848711 166.3115)
		(mid 130.79599 166.184221)
		(end 130.668711 166.1315)
		(width 0.21)
		(layer "B.Cu")
		(net 11)
	)
	(arc
		(start 130.318711 166.1315)
		(mid 130.191432 166.184221)
		(end 130.138711 166.3115)
		(width 0.21)
		(layer "B.Cu")
		(net 11)
	)
	(arc
		(start 130.138711 166.3115)
		(mid 130.08599 166.438779)
		(end 129.958711 166.4915)
		(width 0.21)
		(layer "B.Cu")
		(net 11)
	)
	(arc
		(start 131.738711 166.4915)
		(mid 131.611432 166.544221)
		(end 131.558711 166.6715)
		(width 0.21)
		(layer "B.Cu")
		(net 11)
	)
	(segment
		(start 124.277962 167.8665)
		(end 124.992962 167.8665)
		(width 0.21)
		(layer "F.Cu")
		(net 12)
	)
	(segment
		(start 124.992962 167.8665)
		(end 125.392962 167.4665)
		(width 0.21)
		(layer "F.Cu")
		(net 12)
	)
	(segment
		(start 78.473961 158.516)
		(end 77.668462 158.516)
		(width 0.21)
		(layer "F.Cu")
		(net 12)
	)
	(segment
		(start 77.668462 158.516)
		(end 77.667962 158.5165)
		(width 0.21)
		(layer "F.Cu")
		(net 12)
	)
	(via
		(at 77.667962 158.5165)
		(size 0.45)
		(drill 0.1)
		(layers "F.Cu" "B.Cu")
		(net 12)
	)
	(via
		(at 125.392962 167.4665)
		(size 0.45)
		(drill 0.1)
		(layers "F.Cu" "B.Cu")
		(net 12)
	)
	(segment
		(start 127.130462 167.4925)
		(end 127.129462 167.4915)
		(width 0.21)
		(layer "B.Cu")
		(net 12)
	)
	(segment
		(start 77.567962 158.6165)
		(end 77.567962 161.3165)
		(width 0.21)
		(layer "B.Cu")
		(net 12)
	)
	(segment
		(start 132.929781 167.4925)
		(end 132.729781 167.4925)
		(width 0.21)
		(layer "B.Cu")
		(net 12)
	)
	(segment
		(start 77.667962 158.5165)
		(end 77.567962 158.6165)
		(width 0.21)
		(layer "B.Cu")
		(net 12)
	)
	(segment
		(start 134.729781 167.8925)
		(end 134.529781 167.8925)
		(width 0.21)
		(layer "B.Cu")
		(net 12)
	)
	(segment
		(start 121.2 171.3)
		(end 125.0335 167.4665)
		(width 0.21)
		(layer "B.Cu")
		(net 12)
	)
	(segment
		(start 132.329781 167.8925)
		(end 132.129781 167.8925)
		(width 0.21)
		(layer "B.Cu")
		(net 12)
	)
	(segment
		(start 78.817962 162.5665)
		(end 96.89088 162.5665)
		(width 0.21)
		(layer "B.Cu")
		(net 12)
	)
	(segment
		(start 139.054462 166.6905)
		(end 136.868962 166.6905)
		(width 0.21)
		(layer "B.Cu")
		(net 12)
	)
	(segment
		(start 133.529781 167.8925)
		(end 133.329781 167.8925)
		(width 0.21)
		(layer "B.Cu")
		(net 12)
	)
	(segment
		(start 131.729781 167.4925)
		(end 131.529781 167.4925)
		(width 0.21)
		(layer "B.Cu")
		(net 12)
	)
	(segment
		(start 127.129462 167.4915)
		(end 125.417962 167.4915)
		(width 0.21)
		(layer "B.Cu")
		(net 12)
	)
	(segment
		(start 136.868962 166.6905)
		(end 136.066962 167.4925)
		(width 0.21)
		(layer "B.Cu")
		(net 12)
	)
	(segment
		(start 131.529781 167.4925)
		(end 131.093547 167.4925)
		(width 0.21)
		(layer "B.Cu")
		(net 12)
	)
	(segment
		(start 136.066962 167.4925)
		(end 135.129781 167.4925)
		(width 0.21)
		(layer "B.Cu")
		(net 12)
	)
	(segment
		(start 96.89088 162.5665)
		(end 105.62438 171.3)
		(width 0.21)
		(layer "B.Cu")
		(net 12)
	)
	(segment
		(start 125.0335 167.4665)
		(end 125.392962 167.4665)
		(width 0.21)
		(layer "B.Cu")
		(net 12)
	)
	(segment
		(start 131.093547 167.4925)
		(end 127.130462 167.4925)
		(width 0.21)
		(layer "B.Cu")
		(net 12)
	)
	(segment
		(start 125.417962 167.4915)
		(end 125.392962 167.4665)
		(width 0.21)
		(layer "B.Cu")
		(net 12)
	)
	(segment
		(start 105.62438 171.3)
		(end 121.2 171.3)
		(width 0.21)
		(layer "B.Cu")
		(net 12)
	)
	(segment
		(start 134.129781 167.4925)
		(end 133.929781 167.4925)
		(width 0.21)
		(layer "B.Cu")
		(net 12)
	)
	(segment
		(start 77.567962 161.3165)
		(end 78.817962 162.5665)
		(width 0.21)
		(layer "B.Cu")
		(net 12)
	)
	(arc
		(start 132.529781 167.6925)
		(mid 132.471202 167.833921)
		(end 132.329781 167.8925)
		(width 0.21)
		(layer "B.Cu")
		(net 12)
	)
	(arc
		(start 133.929781 167.4925)
		(mid 133.78836 167.551079)
		(end 133.729781 167.6925)
		(width 0.21)
		(layer "B.Cu")
		(net 12)
	)
	(arc
		(start 132.729781 167.4925)
		(mid 132.58836 167.551079)
		(end 132.529781 167.6925)
		(width 0.21)
		(layer "B.Cu")
		(net 12)
	)
	(arc
		(start 132.129781 167.8925)
		(mid 131.98836 167.833921)
		(end 131.929781 167.6925)
		(width 0.21)
		(layer "B.Cu")
		(net 12)
	)
	(arc
		(start 133.129781 167.6925)
		(mid 133.071202 167.551079)
		(end 132.929781 167.4925)
		(width 0.21)
		(layer "B.Cu")
		(net 12)
	)
	(arc
		(start 135.129781 167.4925)
		(mid 134.98836 167.551079)
		(end 134.929781 167.6925)
		(width 0.21)
		(layer "B.Cu")
		(net 12)
	)
	(arc
		(start 133.729781 167.6925)
		(mid 133.671202 167.833921)
		(end 133.529781 167.8925)
		(width 0.21)
		(layer "B.Cu")
		(net 12)
	)
	(arc
		(start 131.929781 167.6925)
		(mid 131.871202 167.551079)
		(end 131.729781 167.4925)
		(width 0.21)
		(layer "B.Cu")
		(net 12)
	)
	(arc
		(start 134.929781 167.6925)
		(mid 134.871202 167.833921)
		(end 134.729781 167.8925)
		(width 0.21)
		(layer "B.Cu")
		(net 12)
	)
	(arc
		(start 134.329781 167.6925)
		(mid 134.271202 167.551079)
		(end 134.129781 167.4925)
		(width 0.21)
		(layer "B.Cu")
		(net 12)
	)
	(arc
		(start 134.529781 167.8925)
		(mid 134.38836 167.833921)
		(end 134.329781 167.6925)
		(width 0.21)
		(layer "B.Cu")
		(net 12)
	)
	(arc
		(start 133.329781 167.8925)
		(mid 133.18836 167.833921)
		(end 133.129781 167.6925)
		(width 0.21)
		(layer "B.Cu")
		(net 12)
	)
	(segment
		(start 107.112462 126.093118)
		(end 107.027462 126.178118)
		(width 0.15)
		(layer "F.Cu")
		(net 13)
	)
	(segment
		(start 116.732963 160.081501)
		(end 116.892962 160.2415)
		(width 0.15)
		(layer "F.Cu")
		(net 13)
	)
	(segment
		(start 107.113462 125.735325)
		(end 107.113462 124.961325)
		(width 0.153)
		(layer "F.Cu")
		(net 13)
	)
	(segment
		(start 107.112462 124.602)
		(end 107.367962 124.3465)
		(width 0.153)
		(layer "F.Cu")
		(net 13)
	)
	(segment
		(start 107.367962 124.3465)
		(end 107.367962 122.558958)
		(width 0.153)
		(layer "F.Cu")
		(net 13)
	)
	(segment
		(start 116.079962 160.117)
		(end 116.115462 160.0815)
		(width 0.15)
		(layer "F.Cu")
		(net 13)
	)
	(segment
		(start 116.115462 160.0815)
		(end 116.732963 160.081501)
		(width 0.15)
		(layer "F.Cu")
		(net 13)
	)
	(segment
		(start 107.112462 125.736867)
		(end 107.112462 126.093118)
		(width 0.15)
		(layer "F.Cu")
		(net 13)
	)
	(segment
		(start 107.027463 127.681501)
		(end 107.187462 127.8415)
		(width 0.15)
		(layer "F.Cu")
		(net 13)
	)
	(segment
		(start 107.112462 124.960325)
		(end 107.112462 124.602)
		(width 0.153)
		(layer "F.Cu")
		(net 13)
	)
	(segment
		(start 115.554961 160.117)
		(end 116.079962 160.117)
		(width 0.15)
		(layer "F.Cu")
		(net 13)
	)
	(segment
		(start 107.027462 126.178118)
		(end 107.027463 127.681501)
		(width 0.15)
		(layer "F.Cu")
		(net 13)
	)
	(via
		(at 116.892962 160.2415)
		(size 0.45)
		(drill 0.1)
		(layers "F.Cu" "B.Cu")
		(net 13)
	)
	(via
		(at 107.187462 127.8415)
		(size 0.45)
		(drill 0.1)
		(layers "F.Cu" "B.Cu")
		(net 13)
	)
	(segment
		(start 108.883948 163.469141)
		(end 108.883948 163.46914)
		(width 0.15)
		(layer "B.Cu")
		(net 13)
	)
	(segment
		(start 109.449635 163.751984)
		(end 109.525195 163.676423)
		(width 0.15)
		(layer "B.Cu")
		(net 13)
	)
	(segment
		(start 118.429617 160.081501)
		(end 119.742962 161.394846)
		(width 0.15)
		(layer "B.Cu")
		(net 13)
	)
	(segment
		(start 101.233811 145.79235)
		(end 101.233811 145.4665)
		(width 0.15)
		(layer "B.Cu")
		(net 13)
	)
	(segment
		(start 101.570887 147.964425)
		(end 101.405886 147.964425)
		(width 0.15)
		(layer "B.Cu")
		(net 13)
	)
	(segment
		(start 102.072962 133.894846)
		(end 107.027463 128.940345)
		(width 0.15)
		(layer "B.Cu")
		(net 13)
	)
	(segment
		(start 102.072962 146.79235)
		(end 102.072962 146.4665)
		(width 0.15)
		(layer "B.Cu")
		(net 13)
	)
	(segment
		(start 119.284155 163.174827)
		(end 119.284156 163.174827)
		(width 0.15)
		(layer "B.Cu")
		(net 13)
	)
	(segment
		(start 109.242352 163.393579)
		(end 109.242352 163.39358)
		(width 0.15)
		(layer "B.Cu")
		(net 13)
	)
	(segment
		(start 101.570853 139.964391)
		(end 101.405853 139.964391)
		(width 0.15)
		(layer "B.Cu")
		(net 13)
	)
	(segment
		(start 119.442962 162.0865)
		(end 119.442962 162.1865)
		(width 0.15)
		(layer "B.Cu")
		(net 13)
	)
	(segment
		(start 116.892962 160.2415)
		(end 117.052961 160.081501)
		(width 0.15)
		(layer "B.Cu")
		(net 13)
	)
	(segment
		(start 101.570887 143.964425)
		(end 101.405886 143.964425)
		(width 0.15)
		(layer "B.Cu")
		(net 13)
	)
	(segment
		(start 118.506337 163.740513)
		(end 118.435626 163.811223)
		(width 0.15)
		(layer "B.Cu")
		(net 13)
	)
	(segment
		(start 117.940651 164.306199)
		(end 117.86994 164.376909)
		(width 0.15)
		(layer "B.Cu")
		(net 13)
	)
	(segment
		(start 117.869939 164.801174)
		(end 117.86994 164.801173)
		(width 0.15)
		(layer "B.Cu")
		(net 13)
	)
	(segment
		(start 119.001312 163.669801)
		(end 118.930603 163.740513)
		(width 0.15)
		(layer "B.Cu")
		(net 13)
	)
	(segment
		(start 101.405886 147.294425)
		(end 101.570887 147.294425)
		(width 0.15)
		(layer "B.Cu")
		(net 13)
	)
	(segment
		(start 101.570887 141.964425)
		(end 101.405886 141.964425)
		(width 0.15)
		(layer "B.Cu")
		(net 13)
	)
	(segment
		(start 101.405886 145.294425)
		(end 101.570887 145.294425)
		(width 0.15)
		(layer "B.Cu")
		(net 13)
	)
	(segment
		(start 119.001311 163.669802)
		(end 119.001312 163.669801)
		(width 0.15)
		(layer "B.Cu")
		(net 13)
	)
	(segment
		(start 102.072962 138.792282)
		(end 102.072962 133.894846)
		(width 0.15)
		(layer "B.Cu")
		(net 13)
	)
	(segment
		(start 102.072962 148.79235)
		(end 102.072962 148.4665)
		(width 0.15)
		(layer "B.Cu")
		(net 13)
	)
	(segment
		(start 117.940651 164.306198)
		(end 117.940651 164.306199)
		(width 0.15)
		(layer "B.Cu")
		(net 13)
	)
	(segment
		(start 101.233811 141.79235)
		(end 101.233811 141.4665)
		(width 0.15)
		(layer "B.Cu")
		(net 13)
	)
	(segment
		(start 101.233811 147.79235)
		(end 101.233811 147.4665)
		(width 0.15)
		(layer "B.Cu")
		(net 13)
	)
	(segment
		(start 101.570887 145.964425)
		(end 101.405886 145.964425)
		(width 0.15)
		(layer "B.Cu")
		(net 13)
	)
	(segment
		(start 118.435625 164.235488)
		(end 118.435626 164.235487)
		(width 0.15)
		(layer "B.Cu")
		(net 13)
	)
	(segment
		(start 108.883948 163.46914)
		(end 102.072962 156.658154)
		(width 0.15)
		(layer "B.Cu")
		(net 13)
	)
	(segment
		(start 101.405886 143.294425)
		(end 101.570887 143.294425)
		(width 0.15)
		(layer "B.Cu")
		(net 13)
	)
	(segment
		(start 118.506337 163.740512)
		(end 118.506337 163.740513)
		(width 0.15)
		(layer "B.Cu")
		(net 13)
	)
	(segment
		(start 102.072962 156.658154)
		(end 102.072962 150.4665)
		(width 0.15)
		(layer "B.Cu")
		(net 13)
	)
	(segment
		(start 117.052961 160.081501)
		(end 118.429617 160.081501)
		(width 0.15)
		(layer "B.Cu")
		(net 13)
	)
	(segment
		(start 101.233744 139.792282)
		(end 101.233744 139.4665)
		(width 0.15)
		(layer "B.Cu")
		(net 13)
	)
	(segment
		(start 109.242352 163.39358)
		(end 109.166791 163.46914)
		(width 0.15)
		(layer "B.Cu")
		(net 13)
	)
	(segment
		(start 101.570887 149.964425)
		(end 101.405886 149.964425)
		(width 0.15)
		(layer "B.Cu")
		(net 13)
	)
	(segment
		(start 117.659616 165.0115)
		(end 110.426308 165.0115)
		(width 0.15)
		(layer "B.Cu")
		(net 13)
	)
	(segment
		(start 119.072023 163.174826)
		(end 119.072023 163.174827)
		(width 0.15)
		(layer "B.Cu")
		(net 13)
	)
	(segment
		(start 110.426308 165.0115)
		(end 109.449635 164.034827)
		(width 0.15)
		(layer "B.Cu")
		(net 13)
	)
	(segment
		(start 107.027463 128.940345)
		(end 107.027463 128.001499)
		(width 0.15)
		(layer "B.Cu")
		(net 13)
	)
	(segment
		(start 119.742962 162.928154)
		(end 119.496289 163.174827)
		(width 0.15)
		(layer "B.Cu")
		(net 13)
	)
	(segment
		(start 101.233811 149.79235)
		(end 101.233811 149.4665)
		(width 0.15)
		(layer "B.Cu")
		(net 13)
	)
	(segment
		(start 118.435626 164.235487)
		(end 118.364917 164.306199)
		(width 0.15)
		(layer "B.Cu")
		(net 13)
	)
	(segment
		(start 102.072962 142.79235)
		(end 102.072962 142.4665)
		(width 0.15)
		(layer "B.Cu")
		(net 13)
	)
	(segment
		(start 118.152783 164.306199)
		(end 118.152784 164.306199)
		(width 0.15)
		(layer "B.Cu")
		(net 13)
	)
	(segment
		(start 119.742962 161.394846)
		(end 119.742962 161.7865)
		(width 0.15)
		(layer "B.Cu")
		(net 13)
	)
	(segment
		(start 101.233811 143.79235)
		(end 101.233811 143.4665)
		(width 0.15)
		(layer "B.Cu")
		(net 13)
	)
	(segment
		(start 101.405886 141.294425)
		(end 101.570887 141.294425)
		(width 0.15)
		(layer "B.Cu")
		(net 13)
	)
	(segment
		(start 101.405886 149.294425)
		(end 101.570887 149.294425)
		(width 0.15)
		(layer "B.Cu")
		(net 13)
	)
	(segment
		(start 119.072023 163.174827)
		(end 119.001312 163.245537)
		(width 0.15)
		(layer "B.Cu")
		(net 13)
	)
	(segment
		(start 102.072962 140.79235)
		(end 102.072962 140.4665)
		(width 0.15)
		(layer "B.Cu")
		(net 13)
	)
	(segment
		(start 109.449634 163.751984)
		(end 109.449635 163.751984)
		(width 0.15)
		(layer "B.Cu")
		(net 13)
	)
	(segment
		(start 119.742962 162.4865)
		(end 119.742962 162.928154)
		(width 0.15)
		(layer "B.Cu")
		(net 13)
	)
	(segment
		(start 101.405853 139.294391)
		(end 101.570853 139.294391)
		(width 0.15)
		(layer "B.Cu")
		(net 13)
	)
	(segment
		(start 102.072962 144.79235)
		(end 102.072962 144.4665)
		(width 0.15)
		(layer "B.Cu")
		(net 13)
	)
	(segment
		(start 118.718469 163.740513)
		(end 118.71847 163.740513)
		(width 0.15)
		(layer "B.Cu")
		(net 13)
	)
	(segment
		(start 107.027463 128.001499)
		(end 107.187462 127.8415)
		(width 0.15)
		(layer "B.Cu")
		(net 13)
	)
	(segment
		(start 109.525196 163.39358)
		(end 109.525195 163.39358)
		(width 0.15)
		(layer "B.Cu")
		(net 13)
	)
	(segment
		(start 117.86994 164.801173)
		(end 117.659616 165.0115)
		(width 0.15)
		(layer "B.Cu")
		(net 13)
	)
	(arc
		(start 117.86994 164.376909)
		(mid 117.826006 164.482975)
		(end 117.86994 164.589041)
		(width 0.15)
		(layer "B.Cu")
		(net 13)
	)
	(arc
		(start 118.435626 164.023355)
		(mid 118.47956 164.129422)
		(end 118.435625 164.235488)
		(width 0.15)
		(layer "B.Cu")
		(net 13)
	)
	(arc
		(start 101.233811 141.4665)
		(mid 101.284211 141.344825)
		(end 101.405886 141.294425)
		(width 0.15)
		(layer "B.Cu")
		(net 13)
	)
	(arc
		(start 109.525195 163.39358)
		(mid 109.383774 163.335001)
		(end 109.242352 163.393579)
		(width 0.15)
		(layer "B.Cu")
		(net 13)
	)
	(arc
		(start 101.570887 147.294425)
		(mid 101.925908 147.147371)
		(end 102.072962 146.79235)
		(width 0.15)
		(layer "B.Cu")
		(net 13)
	)
	(arc
		(start 117.86994 164.589041)
		(mid 117.913874 164.695108)
		(end 117.869939 164.801174)
		(width 0.15)
		(layer "B.Cu")
		(net 13)
	)
	(arc
		(start 119.742962 161.7865)
		(mid 119.699028 161.892566)
		(end 119.592962 161.9365)
		(width 0.15)
		(layer "B.Cu")
		(net 13)
	)
	(arc
		(start 101.405886 147.964425)
		(mid 101.284211 147.914025)
		(end 101.233811 147.79235)
		(width 0.15)
		(layer "B.Cu")
		(net 13)
	)
	(arc
		(start 101.570887 145.294425)
		(mid 101.925908 145.147371)
		(end 102.072962 144.79235)
		(width 0.15)
		(layer "B.Cu")
		(net 13)
	)
	(arc
		(start 119.442962 162.1865)
		(mid 119.486896 162.292566)
		(end 119.592962 162.3365)
		(width 0.15)
		(layer "B.Cu")
		(net 13)
	)
	(arc
		(start 118.435626 163.811223)
		(mid 118.391692 163.917289)
		(end 118.435626 164.023355)
		(width 0.15)
		(layer "B.Cu")
		(net 13)
	)
	(arc
		(start 101.405886 143.964425)
		(mid 101.284211 143.914025)
		(end 101.233811 143.79235)
		(width 0.15)
		(layer "B.Cu")
		(net 13)
	)
	(arc
		(start 102.072962 142.4665)
		(mid 101.925908 142.111479)
		(end 101.570887 141.964425)
		(width 0.15)
		(layer "B.Cu")
		(net 13)
	)
	(arc
		(start 101.570853 139.294391)
		(mid 101.925898 139.147327)
		(end 102.072962 138.792282)
		(width 0.15)
		(layer "B.Cu")
		(net 13)
	)
	(arc
		(start 119.284156 163.174827)
		(mid 119.17809 163.130892)
		(end 119.072023 163.174826)
		(width 0.15)
		(layer "B.Cu")
		(net 13)
	)
	(arc
		(start 119.001312 163.457669)
		(mid 119.045246 163.563736)
		(end 119.001311 163.669802)
		(width 0.15)
		(layer "B.Cu")
		(net 13)
	)
	(arc
		(start 102.072962 144.4665)
		(mid 101.925908 144.111479)
		(end 101.570887 143.964425)
		(width 0.15)
		(layer "B.Cu")
		(net 13)
	)
	(arc
		(start 109.525195 163.676423)
		(mid 109.583774 163.535002)
		(end 109.525196 163.39358)
		(width 0.15)
		(layer "B.Cu")
		(net 13)
	)
	(arc
		(start 101.405886 145.964425)
		(mid 101.284211 145.914025)
		(end 101.233811 145.79235)
		(width 0.15)
		(layer "B.Cu")
		(net 13)
	)
	(arc
		(start 101.233811 143.4665)
		(mid 101.284211 143.344825)
		(end 101.405886 143.294425)
		(width 0.15)
		(layer "B.Cu")
		(net 13)
	)
	(arc
		(start 102.072962 148.4665)
		(mid 101.925908 148.111479)
		(end 101.570887 147.964425)
		(width 0.15)
		(layer "B.Cu")
		(net 13)
	)
	(arc
		(start 119.592962 161.9365)
		(mid 119.486896 161.980434)
		(end 119.442962 162.0865)
		(width 0.15)
		(layer "B.Cu")
		(net 13)
	)
	(arc
		(start 101.233811 145.4665)
		(mid 101.284211 145.344825)
		(end 101.405886 145.294425)
		(width 0.15)
		(layer "B.Cu")
		(net 13)
	)
	(arc
		(start 119.001312 163.245537)
		(mid 118.957378 163.351603)
		(end 119.001312 163.457669)
		(width 0.15)
		(layer "B.Cu")
		(net 13)
	)
	(arc
		(start 101.233811 149.4665)
		(mid 101.284211 149.344825)
		(end 101.405886 149.294425)
		(width 0.15)
		(layer "B.Cu")
		(net 13)
	)
	(arc
		(start 101.405886 149.964425)
		(mid 101.284211 149.914025)
		(end 101.233811 149.79235)
		(width 0.15)
		(layer "B.Cu")
		(net 13)
	)
	(arc
		(start 119.592962 162.3365)
		(mid 119.699028 162.380434)
		(end 119.742962 162.4865)
		(width 0.15)
		(layer "B.Cu")
		(net 13)
	)
	(arc
		(start 101.570887 141.294425)
		(mid 101.925908 141.147371)
		(end 102.072962 140.79235)
		(width 0.15)
		(layer "B.Cu")
		(net 13)
	)
	(arc
		(start 118.364917 164.306199)
		(mid 118.25885 164.350133)
		(end 118.152783 164.306199)
		(width 0.15)
		(layer "B.Cu")
		(net 13)
	)
	(arc
		(start 101.233811 147.4665)
		(mid 101.284211 147.344825)
		(end 101.405886 147.294425)
		(width 0.15)
		(layer "B.Cu")
		(net 13)
	)
	(arc
		(start 118.930603 163.740513)
		(mid 118.824536 163.784447)
		(end 118.718469 163.740513)
		(width 0.15)
		(layer "B.Cu")
		(net 13)
	)
	(arc
		(start 118.152784 164.306199)
		(mid 118.046718 164.262264)
		(end 117.940651 164.306198)
		(width 0.15)
		(layer "B.Cu")
		(net 13)
	)
	(arc
		(start 102.072962 140.4665)
		(mid 101.925898 140.111455)
		(end 101.570853 139.964391)
		(width 0.15)
		(layer "B.Cu")
		(net 13)
	)
	(arc
		(start 101.405853 139.964391)
		(mid 101.284154 139.913981)
		(end 101.233744 139.792282)
		(width 0.15)
		(layer "B.Cu")
		(net 13)
	)
	(arc
		(start 101.233744 139.4665)
		(mid 101.284154 139.344801)
		(end 101.405853 139.294391)
		(width 0.15)
		(layer "B.Cu")
		(net 13)
	)
	(arc
		(start 102.072962 146.4665)
		(mid 101.925908 146.111479)
		(end 101.570887 145.964425)
		(width 0.15)
		(layer "B.Cu")
		(net 13)
	)
	(arc
		(start 119.496289 163.174827)
		(mid 119.390222 163.218761)
		(end 119.284155 163.174827)
		(width 0.15)
		(layer "B.Cu")
		(net 13)
	)
	(arc
		(start 109.449635 164.034827)
		(mid 109.391056 163.893406)
		(end 109.449634 163.751984)
		(width 0.15)
		(layer "B.Cu")
		(net 13)
	)
	(arc
		(start 109.166791 163.46914)
		(mid 109.02537 163.527719)
		(end 108.883948 163.469141)
		(width 0.15)
		(layer "B.Cu")
		(net 13)
	)
	(arc
		(start 101.570887 149.294425)
		(mid 101.925908 149.147371)
		(end 102.072962 148.79235)
		(width 0.15)
		(layer "B.Cu")
		(net 13)
	)
	(arc
		(start 101.405886 141.964425)
		(mid 101.284211 141.914025)
		(end 101.233811 141.79235)
		(width 0.15)
		(layer "B.Cu")
		(net 13)
	)
	(arc
		(start 118.71847 163.740513)
		(mid 118.612404 163.696578)
		(end 118.506337 163.740512)
		(width 0.15)
		(layer "B.Cu")
		(net 13)
	)
	(arc
		(start 101.570887 143.294425)
		(mid 101.925908 143.147371)
		(end 102.072962 142.79235)
		(width 0.15)
		(layer "B.Cu")
		(net 13)
	)
	(arc
		(start 102.072962 150.4665)
		(mid 101.925908 150.111479)
		(end 101.570887 149.964425)
		(width 0.15)
		(layer "B.Cu")
		(net 13)
	)
	(segment
		(start 106.613462 124.59)
		(end 106.369462 124.346)
		(width 0.153)
		(layer "F.Cu")
		(net 14)
	)
	(segment
		(start 106.369462 124.346)
		(end 106.369462 124.165458)
		(width 0.153)
		(layer "F.Cu")
		(net 14)
	)
	(segment
		(start 106.613462 125.365825)
		(end 106.613462 124.59)
		(width 0.153)
		(layer "F.Cu")
		(net 14)
	)
	(segment
		(start 106.697461 127.681501)
		(end 106.537462 127.8415)
		(width 0.15)
		(layer "F.Cu")
		(net 14)
	)
	(segment
		(start 116.732963 159.751499)
		(end 116.892962 159.5915)
		(width 0.15)
		(layer "F.Cu")
		(net 14)
	)
	(segment
		(start 106.697462 126.178118)
		(end 106.697461 127.681501)
		(width 0.15)
		(layer "F.Cu")
		(net 14)
	)
	(segment
		(start 106.369462 124.165458)
		(end 106.368962 124.164958)
		(width 0.153)
		(layer "F.Cu")
		(net 14)
	)
	(segment
		(start 116.079962 159.716)
		(end 116.115462 159.7515)
		(width 0.15)
		(layer "F.Cu")
		(net 14)
	)
	(segment
		(start 115.554961 159.716)
		(end 116.079962 159.716)
		(width 0.15)
		(layer "F.Cu")
		(net 14)
	)
	(segment
		(start 116.115462 159.7515)
		(end 116.732963 159.751499)
		(width 0.15)
		(layer "F.Cu")
		(net 14)
	)
	(segment
		(start 106.368962 124.164958)
		(end 106.368962 122.558958)
		(width 0.153)
		(layer "F.Cu")
		(net 14)
	)
	(segment
		(start 106.612462 125.736867)
		(end 106.612462 126.093118)
		(width 0.15)
		(layer "F.Cu")
		(net 14)
	)
	(segment
		(start 106.612462 126.093118)
		(end 106.697462 126.178118)
		(width 0.15)
		(layer "F.Cu")
		(net 14)
	)
	(segment
		(start 106.613462 125.735325)
		(end 106.613462 124.960325)
		(width 0.153)
		(layer "F.Cu")
		(net 14)
	)
	(via
		(at 116.892962 159.5915)
		(size 0.45)
		(drill 0.1)
		(layers "F.Cu" "B.Cu")
		(net 14)
	)
	(via
		(at 106.537462 127.8415)
		(size 0.45)
		(drill 0.1)
		(layers "F.Cu" "B.Cu")
		(net 14)
	)
	(segment
		(start 101.405886 146.964425)
		(end 101.570887 146.964425)
		(width 0.15)
		(layer "B.Cu")
		(net 14)
	)
	(segment
		(start 100.903811 145.79235)
		(end 100.903811 145.4665)
		(width 0.15)
		(layer "B.Cu")
		(net 14)
	)
	(segment
		(start 101.570887 146.294425)
		(end 101.405886 146.294425)
		(width 0.15)
		(layer "B.Cu")
		(net 14)
	)
	(segment
		(start 101.742962 146.79235)
		(end 101.742962 146.4665)
		(width 0.15)
		(layer "B.Cu")
		(net 14)
	)
	(segment
		(start 101.405886 148.964425)
		(end 101.570887 148.964425)
		(width 0.15)
		(layer "B.Cu")
		(net 14)
	)
	(segment
		(start 101.742962 133.758154)
		(end 106.697461 128.803655)
		(width 0.15)
		(layer "B.Cu")
		(net 14)
	)
	(segment
		(start 118.566307 159.751499)
		(end 120.072962 161.258154)
		(width 0.15)
		(layer "B.Cu")
		(net 14)
	)
	(segment
		(start 117.796308 165.3415)
		(end 110.289616 165.3415)
		(width 0.15)
		(layer "B.Cu")
		(net 14)
	)
	(segment
		(start 100.903811 147.79235)
		(end 100.903811 147.4665)
		(width 0.15)
		(layer "B.Cu")
		(net 14)
	)
	(segment
		(start 101.742962 138.792282)
		(end 101.742962 133.758154)
		(width 0.15)
		(layer "B.Cu")
		(net 14)
	)
	(segment
		(start 100.903811 143.79235)
		(end 100.903811 143.4665)
		(width 0.15)
		(layer "B.Cu")
		(net 14)
	)
	(segment
		(start 101.405886 140.964425)
		(end 101.570887 140.964425)
		(width 0.15)
		(layer "B.Cu")
		(net 14)
	)
	(segment
		(start 101.742962 142.79235)
		(end 101.742962 142.4665)
		(width 0.15)
		(layer "B.Cu")
		(net 14)
	)
	(segment
		(start 101.570887 148.294425)
		(end 101.405886 148.294425)
		(width 0.15)
		(layer "B.Cu")
		(net 14)
	)
	(segment
		(start 100.903811 149.79235)
		(end 100.903811 149.4665)
		(width 0.15)
		(layer "B.Cu")
		(net 14)
	)
	(segment
		(start 100.903811 141.79235)
		(end 100.903811 141.4665)
		(width 0.15)
		(layer "B.Cu")
		(net 14)
	)
	(segment
		(start 120.072962 161.258154)
		(end 120.072962 163.064846)
		(width 0.15)
		(layer "B.Cu")
		(net 14)
	)
	(segment
		(start 101.570853 140.294391)
		(end 101.405853 140.294391)
		(width 0.15)
		(layer "B.Cu")
		(net 14)
	)
	(segment
		(start 117.052961 159.751499)
		(end 118.566307 159.751499)
		(width 0.15)
		(layer "B.Cu")
		(net 14)
	)
	(segment
		(start 101.405886 144.964425)
		(end 101.570887 144.964425)
		(width 0.15)
		(layer "B.Cu")
		(net 14)
	)
	(segment
		(start 110.289616 165.3415)
		(end 101.742962 156.794846)
		(width 0.15)
		(layer "B.Cu")
		(net 14)
	)
	(segment
		(start 101.742962 144.79235)
		(end 101.742962 144.4665)
		(width 0.15)
		(layer "B.Cu")
		(net 14)
	)
	(segment
		(start 101.742962 156.794846)
		(end 101.742962 150.4665)
		(width 0.15)
		(layer "B.Cu")
		(net 14)
	)
	(segment
		(start 101.405886 142.964425)
		(end 101.570887 142.964425)
		(width 0.15)
		(layer "B.Cu")
		(net 14)
	)
	(segment
		(start 106.697461 128.803655)
		(end 106.697461 128.001499)
		(width 0.15)
		(layer "B.Cu")
		(net 14)
	)
	(segment
		(start 116.892962 159.5915)
		(end 117.052961 159.751499)
		(width 0.15)
		(layer "B.Cu")
		(net 14)
	)
	(segment
		(start 101.570887 142.294425)
		(end 101.405886 142.294425)
		(width 0.15)
		(layer "B.Cu")
		(net 14)
	)
	(segment
		(start 101.742962 140.79235)
		(end 101.742962 140.4665)
		(width 0.15)
		(layer "B.Cu")
		(net 14)
	)
	(segment
		(start 101.405853 138.964391)
		(end 101.570853 138.964391)
		(width 0.15)
		(layer "B.Cu")
		(net 14)
	)
	(segment
		(start 100.903744 139.792282)
		(end 100.903744 139.4665)
		(width 0.15)
		(layer "B.Cu")
		(net 14)
	)
	(segment
		(start 101.742962 148.79235)
		(end 101.742962 148.4665)
		(width 0.15)
		(layer "B.Cu")
		(net 14)
	)
	(segment
		(start 101.570887 150.294425)
		(end 101.405886 150.294425)
		(width 0.15)
		(layer "B.Cu")
		(net 14)
	)
	(segment
		(start 120.072962 163.064846)
		(end 117.796308 165.3415)
		(width 0.15)
		(layer "B.Cu")
		(net 14)
	)
	(segment
		(start 106.697461 128.001499)
		(end 106.537462 127.8415)
		(width 0.15)
		(layer "B.Cu")
		(net 14)
	)
	(segment
		(start 101.570887 144.294425)
		(end 101.405886 144.294425)
		(width 0.15)
		(layer "B.Cu")
		(net 14)
	)
	(arc
		(start 101.570853 138.964391)
		(mid 101.692552 138.913981)
		(end 101.742962 138.792282)
		(width 0.15)
		(layer "B.Cu")
		(net 14)
	)
	(arc
		(start 101.405886 146.294425)
		(mid 101.050865 146.147371)
		(end 100.903811 145.79235)
		(width 0.15)
		(layer "B.Cu")
		(net 14)
	)
	(arc
		(start 101.405853 140.294391)
		(mid 101.050808 140.147327)
		(end 100.903744 139.792282)
		(width 0.15)
		(layer "B.Cu")
		(net 14)
	)
	(arc
		(start 100.903811 147.4665)
		(mid 101.050865 147.111479)
		(end 101.405886 146.964425)
		(width 0.15)
		(layer "B.Cu")
		(net 14)
	)
	(arc
		(start 100.903811 141.4665)
		(mid 101.050865 141.111479)
		(end 101.405886 140.964425)
		(width 0.15)
		(layer "B.Cu")
		(net 14)
	)
	(arc
		(start 101.742962 142.4665)
		(mid 101.692562 142.344825)
		(end 101.570887 142.294425)
		(width 0.15)
		(layer "B.Cu")
		(net 14)
	)
	(arc
		(start 101.742962 140.4665)
		(mid 101.692552 140.344801)
		(end 101.570853 140.294391)
		(width 0.15)
		(layer "B.Cu")
		(net 14)
	)
	(arc
		(start 101.405886 150.294425)
		(mid 101.050865 150.147371)
		(end 100.903811 149.79235)
		(width 0.15)
		(layer "B.Cu")
		(net 14)
	)
	(arc
		(start 101.742962 150.4665)
		(mid 101.692562 150.344825)
		(end 101.570887 150.294425)
		(width 0.15)
		(layer "B.Cu")
		(net 14)
	)
	(arc
		(start 101.405886 144.294425)
		(mid 101.050865 144.147371)
		(end 100.903811 143.79235)
		(width 0.15)
		(layer "B.Cu")
		(net 14)
	)
	(arc
		(start 101.742962 148.4665)
		(mid 101.692562 148.344825)
		(end 101.570887 148.294425)
		(width 0.15)
		(layer "B.Cu")
		(net 14)
	)
	(arc
		(start 101.405886 142.294425)
		(mid 101.050865 142.147371)
		(end 100.903811 141.79235)
		(width 0.15)
		(layer "B.Cu")
		(net 14)
	)
	(arc
		(start 101.742962 146.4665)
		(mid 101.692562 146.344825)
		(end 101.570887 146.294425)
		(width 0.15)
		(layer "B.Cu")
		(net 14)
	)
	(arc
		(start 100.903811 143.4665)
		(mid 101.050865 143.111479)
		(end 101.405886 142.964425)
		(width 0.15)
		(layer "B.Cu")
		(net 14)
	)
	(arc
		(start 101.405886 148.294425)
		(mid 101.050865 148.147371)
		(end 100.903811 147.79235)
		(width 0.15)
		(layer "B.Cu")
		(net 14)
	)
	(arc
		(start 101.570887 142.964425)
		(mid 101.692562 142.914025)
		(end 101.742962 142.79235)
		(width 0.15)
		(layer "B.Cu")
		(net 14)
	)
	(arc
		(start 100.903744 139.4665)
		(mid 101.050808 139.111455)
		(end 101.405853 138.964391)
		(width 0.15)
		(layer "B.Cu")
		(net 14)
	)
	(arc
		(start 101.570887 146.964425)
		(mid 101.692562 146.914025)
		(end 101.742962 146.79235)
		(width 0.15)
		(layer "B.Cu")
		(net 14)
	)
	(arc
		(start 101.570887 144.964425)
		(mid 101.692562 144.914025)
		(end 101.742962 144.79235)
		(width 0.15)
		(layer "B.Cu")
		(net 14)
	)
	(arc
		(start 100.903811 145.4665)
		(mid 101.050865 145.111479)
		(end 101.405886 144.964425)
		(width 0.15)
		(layer "B.Cu")
		(net 14)
	)
	(arc
		(start 101.742962 144.4665)
		(mid 101.692562 144.344825)
		(end 101.570887 144.294425)
		(width 0.15)
		(layer "B.Cu")
		(net 14)
	)
	(arc
		(start 101.570887 148.964425)
		(mid 101.692562 148.914025)
		(end 101.742962 148.79235)
		(width 0.15)
		(layer "B.Cu")
		(net 14)
	)
	(arc
		(start 100.903811 149.4665)
		(mid 101.050865 149.111479)
		(end 101.405886 148.964425)
		(width 0.15)
		(layer "B.Cu")
		(net 14)
	)
	(arc
		(start 101.570887 140.964425)
		(mid 101.692562 140.914025)
		(end 101.742962 140.79235)
		(width 0.15)
		(layer "B.Cu")
		(net 14)
	)
	(segment
		(start 105.542962 126.162618)
		(end 105.542962 126.664014)
		(width 0.153)
		(layer "F.Cu")
		(net 15)
	)
	(segment
		(start 116.079962 158.917)
		(end 116.115462 158.8815)
		(width 0.15)
		(layer "F.Cu")
		(net 15)
	)
	(segment
		(start 115.554961 158.917)
		(end 116.079962 158.917)
		(width 0.15)
		(layer "F.Cu")
		(net 15)
	)
	(segment
		(start 105.539462 126.718)
		(end 105.687962 126.8665)
		(width 0.153)
		(layer "F.Cu")
		(net 15)
	)
	(segment
		(start 105.612462 126.093118)
		(end 105.542962 126.162618)
		(width 0.153)
		(layer "F.Cu")
		(net 15)
	)
	(segment
		(start 105.542962 126.664014)
		(end 105.539462 126.667514)
		(width 0.153)
		(layer "F.Cu")
		(net 15)
	)
	(segment
		(start 105.611462 124.603542)
		(end 105.866962 124.348042)
		(width 0.153)
		(layer "F.Cu")
		(net 15)
	)
	(segment
		(start 116.115462 158.8815)
		(end 117.453963 158.881501)
		(width 0.15)
		(layer "F.Cu")
		(net 15)
	)
	(segment
		(start 117.453963 158.881501)
		(end 117.617962 159.0455)
		(width 0.15)
		(layer "F.Cu")
		(net 15)
	)
	(segment
		(start 105.612462 125.736867)
		(end 105.612462 124.962867)
		(width 0.153)
		(layer "F.Cu")
		(net 15)
	)
	(segment
		(start 105.866962 124.348042)
		(end 105.866962 122.5605)
		(width 0.153)
		(layer "F.Cu")
		(net 15)
	)
	(segment
		(start 105.539462 126.667514)
		(end 105.539462 126.718)
		(width 0.153)
		(layer "F.Cu")
		(net 15)
	)
	(segment
		(start 105.612462 125.736867)
		(end 105.612462 126.093118)
		(width 0.153)
		(layer "F.Cu")
		(net 15)
	)
	(segment
		(start 105.611462 124.961867)
		(end 105.611462 124.603542)
		(width 0.153)
		(layer "F.Cu")
		(net 15)
	)
	(via
		(at 105.687962 126.8665)
		(size 0.45)
		(drill 0.1)
		(layers "F.Cu" "B.Cu")
		(net 15)
	)
	(via
		(at 117.617962 159.0455)
		(size 0.45)
		(drill 0.1)
		(layers "F.Cu" "B.Cu")
		(net 15)
	)
	(segment
		(start 120.085602 164.425511)
		(end 120.085602 164.42551)
		(width 0.15)
		(layer "B.Cu")
		(net 15)
	)
	(segment
		(start 118.95423 165.556883)
		(end 118.954231 165.556883)
		(width 0.15)
		(layer "B.Cu")
		(net 15)
	)
	(segment
		(start 120.084015 163.858239)
		(end 120.084016 163.858239)
		(width 0.15)
		(layer "B.Cu")
		(net 15)
	)
	(segment
		(start 119.519917 164.991199)
		(end 119.519916 164.991197)
		(width 0.15)
		(layer "B.Cu")
		(net 15)
	)
	(segment
		(start 118.229616 166.2815)
		(end 118.95423 165.556883)
		(width 0.15)
		(layer "B.Cu")
		(net 15)
	)
	(segment
		(start 105.523963 127.030499)
		(end 105.523963 128.443845)
		(width 0.15)
		(layer "B.Cu")
		(net 15)
	)
	(segment
		(start 118.95423 165.27404)
		(end 118.952598 165.272408)
		(width 0.15)
		(layer "B.Cu")
		(net 15)
	)
	(segment
		(start 121.032962 161.8265)
		(end 121.032962 161.124846)
		(width 0.15)
		(layer "B.Cu")
		(net 15)
	)
	(segment
		(start 117.781961 158.881501)
		(end 117.617962 159.0455)
		(width 0.15)
		(layer "B.Cu")
		(net 15)
	)
	(segment
		(start 120.085603 164.425513)
		(end 120.085602 164.425511)
		(width 0.15)
		(layer "B.Cu")
		(net 15)
	)
	(segment
		(start 119.519916 164.708354)
		(end 119.518291 164.706729)
		(width 0.15)
		(layer "B.Cu")
		(net 15)
	)
	(segment
		(start 119.518291 164.423887)
		(end 119.518292 164.423887)
		(width 0.15)
		(layer "B.Cu")
		(net 15)
	)
	(segment
		(start 120.368446 163.859827)
		(end 120.368445 163.859827)
		(width 0.15)
		(layer "B.Cu")
		(net 15)
	)
	(segment
		(start 120.732962 162.0265)
		(end 120.832962 162.0265)
		(width 0.15)
		(layer "B.Cu")
		(net 15)
	)
	(segment
		(start 105.523963 128.443845)
		(end 100.352962 133.614846)
		(width 0.15)
		(layer "B.Cu")
		(net 15)
	)
	(segment
		(start 100.352962 156.998154)
		(end 109.636308 166.2815)
		(width 0.15)
		(layer "B.Cu")
		(net 15)
	)
	(segment
		(start 100.352962 133.614846)
		(end 100.352962 156.998154)
		(width 0.15)
		(layer "B.Cu")
		(net 15)
	)
	(segment
		(start 119.519916 164.991197)
		(end 119.519916 164.991196)
		(width 0.15)
		(layer "B.Cu")
		(net 15)
	)
	(segment
		(start 109.636308 166.2815)
		(end 118.229616 166.2815)
		(width 0.15)
		(layer "B.Cu")
		(net 15)
	)
	(segment
		(start 119.856747 160.265)
		(end 118.473248 158.881501)
		(width 0.15)
		(layer "B.Cu")
		(net 15)
	)
	(segment
		(start 120.651289 163.859827)
		(end 121.032962 163.478154)
		(width 0.15)
		(layer "B.Cu")
		(net 15)
	)
	(segment
		(start 119.237074 164.991199)
		(end 119.237073 164.991199)
		(width 0.15)
		(layer "B.Cu")
		(net 15)
	)
	(segment
		(start 119.235441 164.989566)
		(end 119.237074 164.991199)
		(width 0.15)
		(layer "B.Cu")
		(net 15)
	)
	(segment
		(start 118.952598 164.989566)
		(end 118.952598 164.989565)
		(width 0.15)
		(layer "B.Cu")
		(net 15)
	)
	(segment
		(start 119.801134 164.423887)
		(end 119.80276 164.425513)
		(width 0.15)
		(layer "B.Cu")
		(net 15)
	)
	(segment
		(start 120.366858 163.858239)
		(end 120.368446 163.859827)
		(width 0.15)
		(layer "B.Cu")
		(net 15)
	)
	(segment
		(start 120.832962 162.4265)
		(end 120.732962 162.4265)
		(width 0.15)
		(layer "B.Cu")
		(net 15)
	)
	(segment
		(start 121.032962 163.478154)
		(end 121.032962 162.6265)
		(width 0.15)
		(layer "B.Cu")
		(net 15)
	)
	(segment
		(start 119.80276 164.425513)
		(end 119.802759 164.425513)
		(width 0.15)
		(layer "B.Cu")
		(net 15)
	)
	(segment
		(start 120.173116 160.265)
		(end 119.856747 160.265)
		(width 0.15)
		(layer "B.Cu")
		(net 15)
	)
	(segment
		(start 120.085602 164.142668)
		(end 120.084015 164.141081)
		(width 0.15)
		(layer "B.Cu")
		(net 15)
	)
	(segment
		(start 118.473248 158.881501)
		(end 117.781961 158.881501)
		(width 0.15)
		(layer "B.Cu")
		(net 15)
	)
	(segment
		(start 105.687962 126.8665)
		(end 105.523963 127.030499)
		(width 0.15)
		(layer "B.Cu")
		(net 15)
	)
	(segment
		(start 121.032962 161.124846)
		(end 120.173116 160.265)
		(width 0.15)
		(layer "B.Cu")
		(net 15)
	)
	(arc
		(start 118.952598 165.272408)
		(mid 118.89402 165.130987)
		(end 118.952598 164.989566)
		(width 0.15)
		(layer "B.Cu")
		(net 15)
	)
	(arc
		(start 119.518292 164.423887)
		(mid 119.659713 164.365309)
		(end 119.801134 164.423887)
		(width 0.15)
		(layer "B.Cu")
		(net 15)
	)
	(arc
		(start 119.237073 164.991199)
		(mid 119.378495 165.049778)
		(end 119.519917 164.991199)
		(width 0.15)
		(layer "B.Cu")
		(net 15)
	)
	(arc
		(start 119.519916 164.991196)
		(mid 119.578494 164.849775)
		(end 119.519916 164.708354)
		(width 0.15)
		(layer "B.Cu")
		(net 15)
	)
	(arc
		(start 120.368445 163.859827)
		(mid 120.509867 163.918406)
		(end 120.651289 163.859827)
		(width 0.15)
		(layer "B.Cu")
		(net 15)
	)
	(arc
		(start 118.954231 165.556883)
		(mid 119.012809 165.415461)
		(end 118.95423 165.27404)
		(width 0.15)
		(layer "B.Cu")
		(net 15)
	)
	(arc
		(start 118.952598 164.989565)
		(mid 119.09402 164.930987)
		(end 119.235441 164.989566)
		(width 0.15)
		(layer "B.Cu")
		(net 15)
	)
	(arc
		(start 120.832962 162.0265)
		(mid 120.974383 161.967921)
		(end 121.032962 161.8265)
		(width 0.15)
		(layer "B.Cu")
		(net 15)
	)
	(arc
		(start 119.518291 164.706729)
		(mid 119.459713 164.565308)
		(end 119.518291 164.423887)
		(width 0.15)
		(layer "B.Cu")
		(net 15)
	)
	(arc
		(start 119.802759 164.425513)
		(mid 119.944181 164.484092)
		(end 120.085603 164.425513)
		(width 0.15)
		(layer "B.Cu")
		(net 15)
	)
	(arc
		(start 120.084016 163.858239)
		(mid 120.225437 163.799661)
		(end 120.366858 163.858239)
		(width 0.15)
		(layer "B.Cu")
		(net 15)
	)
	(arc
		(start 121.032962 162.6265)
		(mid 120.974383 162.485079)
		(end 120.832962 162.4265)
		(width 0.15)
		(layer "B.Cu")
		(net 15)
	)
	(arc
		(start 120.732962 162.4265)
		(mid 120.591541 162.367921)
		(end 120.532962 162.2265)
		(width 0.15)
		(layer "B.Cu")
		(net 15)
	)
	(arc
		(start 120.532962 162.2265)
		(mid 120.591541 162.085079)
		(end 120.732962 162.0265)
		(width 0.15)
		(layer "B.Cu")
		(net 15)
	)
	(arc
		(start 120.084015 164.141081)
		(mid 120.025437 163.99966)
		(end 120.084015 163.858239)
		(width 0.15)
		(layer "B.Cu")
		(net 15)
	)
	(arc
		(start 120.085602 164.42551)
		(mid 120.14418 164.284089)
		(end 120.085602 164.142668)
		(width 0.15)
		(layer "B.Cu")
		(net 15)
	)
	(segment
		(start 117.453963 158.551499)
		(end 117.617962 158.3875)
		(width 0.15)
		(layer "F.Cu")
		(net 16)
	)
	(segment
		(start 104.868462 124.347542)
		(end 104.868462 124.167)
		(width 0.153)
		(layer "F.Cu")
		(net 16)
	)
	(segment
		(start 105.112462 124.591542)
		(end 104.868462 124.347542)
		(width 0.153)
		(layer "F.Cu")
		(net 16)
	)
	(segment
		(start 116.079962 158.516)
		(end 116.115462 158.5515)
		(width 0.15)
		(layer "F.Cu")
		(net 16)
	)
	(segment
		(start 105.112462 126.093118)
		(end 105.181962 126.162618)
		(width 0.153)
		(layer "F.Cu")
		(net 16)
	)
	(segment
		(start 104.867962 124.1665)
		(end 104.867962 122.5605)
		(width 0.153)
		(layer "F.Cu")
		(net 16)
	)
	(segment
		(start 105.112462 125.736867)
		(end 105.112462 124.961867)
		(width 0.153)
		(layer "F.Cu")
		(net 16)
	)
	(segment
		(start 105.181962 126.525867)
		(end 105.178462 126.529367)
		(width 0.153)
		(layer "F.Cu")
		(net 16)
	)
	(segment
		(start 104.868462 124.167)
		(end 104.867962 124.1665)
		(width 0.153)
		(layer "F.Cu")
		(net 16)
	)
	(segment
		(start 115.554961 158.516)
		(end 116.079962 158.516)
		(width 0.15)
		(layer "F.Cu")
		(net 16)
	)
	(segment
		(start 105.112462 125.736867)
		(end 105.112462 126.093118)
		(width 0.153)
		(layer "F.Cu")
		(net 16)
	)
	(segment
		(start 105.181962 126.162618)
		(end 105.181962 126.525867)
		(width 0.153)
		(layer "F.Cu")
		(net 16)
	)
	(segment
		(start 105.178462 126.529367)
		(end 105.178462 126.718)
		(width 0.153)
		(layer "F.Cu")
		(net 16)
	)
	(segment
		(start 105.178462 126.718)
		(end 105.029962 126.8665)
		(width 0.153)
		(layer "F.Cu")
		(net 16)
	)
	(segment
		(start 116.115462 158.5515)
		(end 117.453963 158.551499)
		(width 0.15)
		(layer "F.Cu")
		(net 16)
	)
	(segment
		(start 105.112462 125.367367)
		(end 105.112462 124.591542)
		(width 0.153)
		(layer "F.Cu")
		(net 16)
	)
	(via
		(at 105.029962 126.8665)
		(size 0.45)
		(drill 0.1)
		(layers "F.Cu" "B.Cu")
		(net 16)
	)
	(via
		(at 117.617962 158.3875)
		(size 0.45)
		(drill 0.1)
		(layers "F.Cu" "B.Cu")
		(net 16)
	)
	(segment
		(start 100.022962 157.134846)
		(end 109.499616 166.6115)
		(width 0.15)
		(layer "B.Cu")
		(net 16)
	)
	(segment
		(start 117.781961 158.551499)
		(end 117.617962 158.3875)
		(width 0.15)
		(layer "B.Cu")
		(net 16)
	)
	(segment
		(start 105.029962 126.8665)
		(end 105.193961 127.030499)
		(width 0.15)
		(layer "B.Cu")
		(net 16)
	)
	(segment
		(start 119.993439 159.935)
		(end 118.609938 158.551499)
		(width 0.15)
		(layer "B.Cu")
		(net 16)
	)
	(segment
		(start 120.309808 159.935)
		(end 119.993439 159.935)
		(width 0.15)
		(layer "B.Cu")
		(net 16)
	)
	(segment
		(start 121.362962 163.614846)
		(end 121.362962 160.988154)
		(width 0.15)
		(layer "B.Cu")
		(net 16)
	)
	(segment
		(start 105.193961 127.030499)
		(end 105.193961 128.307155)
		(width 0.15)
		(layer "B.Cu")
		(net 16)
	)
	(segment
		(start 109.499616 166.6115)
		(end 118.366308 166.6115)
		(width 0.15)
		(layer "B.Cu")
		(net 16)
	)
	(segment
		(start 100.022962 133.478154)
		(end 100.022962 157.134846)
		(width 0.15)
		(layer "B.Cu")
		(net 16)
	)
	(segment
		(start 118.609938 158.551499)
		(end 117.781961 158.551499)
		(width 0.15)
		(layer "B.Cu")
		(net 16)
	)
	(segment
		(start 105.193961 128.307155)
		(end 100.022962 133.478154)
		(width 0.15)
		(layer "B.Cu")
		(net 16)
	)
	(segment
		(start 121.362962 160.988154)
		(end 120.309808 159.935)
		(width 0.15)
		(layer "B.Cu")
		(net 16)
	)
	(segment
		(start 118.366308 166.6115)
		(end 121.362962 163.614846)
		(width 0.15)
		(layer "B.Cu")
		(net 16)
	)
	(segment
		(start 43.629962 158.3105)
		(end 43.629962 157.6025)
		(width 0.2)
		(layer "B.Cu")
		(net 17)
	)
	(segment
		(start 42.342962 157.6205)
		(end 43.611962 157.6205)
		(width 0.2)
		(layer "B.Cu")
		(net 17)
	)
	(segment
		(start 42.342962 157.6205)
		(end 42.342962 158.5865)
		(width 0.2)
		(layer "B.Cu")
		(net 17)
	)
	(segment
		(start 43.313962 158.6265)
		(end 42.354962 158.6265)
		(width 0.2)
		(layer "B.Cu")
		(net 17)
	)
	(segment
		(start 43.313962 158.6265)
		(end 43.629962 158.3105)
		(width 0.2)
		(layer "B.Cu")
		(net 17)
	)
	(segment
		(start 42.342962 158.5865)
		(end 42.342962 159.5345)
		(width 0.2)
		(layer "B.Cu")
		(net 17)
	)
	(segment
		(start 82.942962 153.08)
		(end 83.488462 153.6255)
		(width 0.2)
		(layer "F.Cu")
		(net 18)
	)
	(segment
		(start 79.488962 161.925264)
		(end 79.488962 160.857736)
		(width 0.127)
		(layer "F.Cu")
		(net 18)
	)
	(segment
		(start 84.657962 161.5165)
		(end 88.247962 157.9265)
		(width 0.2)
		(layer "F.Cu")
		(net 18)
	)
	(segment
		(start 83.542962 153.6255)
		(end 84.293184 153.6255)
		(width 0.2)
		(layer "F.Cu")
		(net 18)
	)
	(segment
		(start 86.933962 153.7505)
		(end 87.367962 153.7505)
		(width 0.2)
		(layer "F.Cu")
		(net 18)
	)
	(segment
		(start 88.247962 157.9265)
		(end 88.517962 157.9265)
		(width 0.2)
		(layer "F.Cu")
		(net 18)
	)
	(segment
		(start 84.293184 153.6255)
		(end 84.410073 153.508611)
		(width 0.2)
		(layer "F.Cu")
		(net 18)
	)
	(segment
		(start 88.247962 157.9265)
		(end 88.417962 157.7565)
		(width 0.2)
		(layer "F.Cu")
		(net 18)
	)
	(segment
		(start 88.389962 153.3695)
		(end 88.167962 153.5915)
		(width 0.15)
		(layer "F.Cu")
		(net 18)
	)
	(segment
		(start 88.517962 157.9265)
		(end 89.042962 157.9265)
		(width 0.2)
		(layer "F.Cu")
		(net 18)
	)
	(segment
		(start 88.008962 153.7505)
		(end 87.367962 153.7505)
		(width 0.15)
		(layer "F.Cu")
		(net 18)
	)
	(segment
		(start 88.417962 157.7565)
		(end 88.417962 156.1665)
		(width 0.2)
		(layer "F.Cu")
		(net 18)
	)
	(segment
		(start 88.008962 153.7505)
		(end 88.167962 153.5915)
		(width 0.2)
		(layer "F.Cu")
		(net 18)
	)
	(segment
		(start 74.77 153.5965)
		(end 74.792962 153.573538)
		(width 0.127)
		(layer "F.Cu")
		(net 18)
	)
	(segment
		(start 84.564962 152.8995)
		(end 84.564962 153.353722)
		(width 0.127)
		(layer "F.Cu")
		(net 18)
	)
	(segment
		(start 83.672962 161.5165)
		(end 84.657962 161.5165)
		(width 0.2)
		(layer "F.Cu")
		(net 18)
	)
	(segment
		(start 79.804462 162.240764)
		(end 79.488962 161.925264)
		(width 0.127)
		(layer "F.Cu")
		(net 18)
	)
	(segment
		(start 88.389962 152.9695)
		(end 88.389962 153.3695)
		(width 0.15)
		(layer "F.Cu")
		(net 18)
	)
	(segment
		(start 88.417962 157.7565)
		(end 88.587962 157.9265)
		(width 0.2)
		(layer "F.Cu")
		(net 18)
	)
	(segment
		(start 86.367962 155.0365)
		(end 86.367962 154.3165)
		(width 0.2)
		(layer "F.Cu")
		(net 18)
	)
	(segment
		(start 88.389962 152.3165)
		(end 88.389962 152.9695)
		(width 0.15)
		(layer "F.Cu")
		(net 18)
	)
	(segment
		(start 79.804462 163.143)
		(end 79.804462 162.240764)
		(width 0.127)
		(layer "F.Cu")
		(net 18)
	)
	(segment
		(start 88.517962 157.8565)
		(end 88.417962 157.7565)
		(width 0.2)
		(layer "F.Cu")
		(net 18)
	)
	(segment
		(start 86.367962 154.3165)
		(end 86.933962 153.7505)
		(width 0.2)
		(layer "F.Cu")
		(net 18)
	)
	(segment
		(start 88.587962 157.9265)
		(end 89.042962 157.9265)
		(width 0.2)
		(layer "F.Cu")
		(net 18)
	)
	(segment
		(start 86.933962 153.7505)
		(end 88.008962 153.7505)
		(width 0.2)
		(layer "F.Cu")
		(net 18)
	)
	(segment
		(start 83.187962 163.0665)
		(end 83.187962 162.9665)
		(width 0.127)
		(layer "F.Cu")
		(net 18)
	)
	(segment
		(start 80.229698 160.117)
		(end 81.554961 160.117)
		(width 0.127)
		(layer "F.Cu")
		(net 18)
	)
	(segment
		(start 84.564962 152.8995)
		(end 84.564962 152.2465)
		(width 0.127)
		(layer "F.Cu")
		(net 18)
	)
	(segment
		(start 88.517962 157.9265)
		(end 88.517962 157.8565)
		(width 0.2)
		(layer "F.Cu")
		(net 18)
	)
	(segment
		(start 83.187962 162.9665)
		(end 83.672962 162.4815)
		(width 0.127)
		(layer "F.Cu")
		(net 18)
	)
	(segment
		(start 83.672962 162.4815)
		(end 83.672962 161.5165)
		(width 0.2)
		(layer "F.Cu")
		(net 18)
	)
	(segment
		(start 79.488962 160.857736)
		(end 80.229698 160.117)
		(width 0.127)
		(layer "F.Cu")
		(net 18)
	)
	(segment
		(start 74.77 153.68)
		(end 74.77 153.5965)
		(width 0.127)
		(layer "F.Cu")
		(net 18)
	)
	(segment
		(start 84.564962 153.353722)
		(end 84.410073 153.508611)
		(width 0.127)
		(layer "F.Cu")
		(net 18)
	)
	(via
		(at 83.187962 163.0665)
		(size 0.45)
		(drill 0.1)
		(layers "F.Cu" "B.Cu")
		(net 18)
	)
	(via
		(at 88.417962 156.1665)
		(size 0.45)
		(drill 0.1)
		(layers "F.Cu" "B.Cu")
		(net 18)
	)
	(via
		(at 86.367962 155.0365)
		(size 0.45)
		(drill 0.1)
		(layers "F.Cu" "B.Cu")
		(net 18)
	)
	(via
		(at 79.804462 163.143)
		(size 0.45)
		(drill 0.1)
		(layers "F.Cu" "B.Cu")
		(net 18)
	)
	(via
		(at 82.942962 153.08)
		(size 0.45)
		(drill 0.1)
		(layers "F.Cu" "B.Cu")
		(net 18)
	)
	(via
		(at 74.792962 153.6165)
		(size 0.45)
		(drill 0.1)
		(layers "F.Cu" "B.Cu")
		(net 18)
	)
	(segment
		(start 79.442962 153.565118)
		(end 79.758648 153.880804)
		(width 0.127)
		(layer "B.Cu")
		(net 18)
	)
	(segment
		(start 80.00087 154.2145)
		(end 82.665962 154.2145)
		(width 0.127)
		(layer "B.Cu")
		(net 18)
	)
	(segment
		(start 86.081515 156.4895)
		(end 86.054515 156.5165)
		(width 0.2)
		(layer "B.Cu")
		(net 18)
	)
	(segment
		(start 83.575962 156.5165)
		(end 82.717962 155.6585)
		(width 0.2)
		(layer "B.Cu")
		(net 18)
	)
	(segment
		(start 79.758648 153.880804)
		(end 79.758648 153.972278)
		(width 0.127)
		(layer "B.Cu")
		(net 18)
	)
	(segment
		(start 86.054515 156.5165)
		(end 83.575962 156.5165)
		(width 0.2)
		(layer "B.Cu")
		(net 18)
	)
	(segment
		(start 74.792962 153.6165)
		(end 74.792962 153.057038)
		(width 0.15)
		(layer "B.Cu")
		(net 18)
	)
	(segment
		(start 86.367962 156.203053)
		(end 86.081515 156.4895)
		(width 0.127)
		(layer "B.Cu")
		(net 18)
	)
	(segment
		(start 78.282962 152.2165)
		(end 78.282962 151.2415)
		(width 0.127)
		(layer "B.Cu")
		(net 18)
	)
	(segment
		(start 79.758648 153.972278)
		(end 80.00087 154.2145)
		(width 0.127)
		(layer "B.Cu")
		(net 18)
	)
	(segment
		(start 82.942962 153.08)
		(end 82.717962 153.305)
		(width 0.2)
		(layer "B.Cu")
		(net 18)
	)
	(segment
		(start 78.352226 152.2165)
		(end 79.442962 153.307236)
		(width 0.127)
		(layer "B.Cu")
		(net 18)
	)
	(segment
		(start 86.367962 156.203053)
		(end 86.367962 155.0365)
		(width 0.2)
		(layer "B.Cu")
		(net 18)
	)
	(segment
		(start 88.417962 156.1665)
		(end 88.381409 156.203053)
		(width 0.127)
		(layer "B.Cu")
		(net 18)
	)
	(segment
		(start 79.442962 153.307236)
		(end 79.442962 153.565118)
		(width 0.127)
		(layer "B.Cu")
		(net 18)
	)
	(segment
		(start 88.381409 156.203053)
		(end 86.367962 156.203053)
		(width 0.127)
		(layer "B.Cu")
		(net 18)
	)
	(segment
		(start 74.792962 153.057038)
		(end 75.45 152.4)
		(width 0.15)
		(layer "B.Cu")
		(net 18)
	)
	(segment
		(start 86.331462 156.239553)
		(end 86.081515 156.4895)
		(width 0.2)
		(layer "B.Cu")
		(net 18)
	)
	(segment
		(start 76.45 151.75)
		(end 76.45 152.19)
		(width 0.127)
		(layer "B.Cu")
		(net 18)
	)
	(segment
		(start 76.45 152.19)
		(end 75.66 152.19)
		(width 0.127)
		(layer "B.Cu")
		(net 18)
	)
	(segment
		(start 75.66 152.19)
		(end 75.45 152.4)
		(width 0.127)
		(layer "B.Cu")
		(net 18)
	)
	(segment
		(start 88.417962 156.1665)
		(end 88.344909 156.239553)
		(width 0.2)
		(layer "B.Cu")
		(net 18)
	)
	(segment
		(start 88.344909 156.239553)
		(end 86.331462 156.239553)
		(width 0.2)
		(layer "B.Cu")
		(net 18)
	)
	(segment
		(start 82.717962 155.6585)
		(end 82.717962 154.5165)
		(width 0.2)
		(layer "B.Cu")
		(net 18)
	)
	(segment
		(start 74.75 153.604462)
		(end 74.75 153.6165)
		(width 0.127)
		(layer "B.Cu")
		(net 18)
	)
	(segment
		(start 82.717962 154.5165)
		(end 82.717962 154.2665)
		(width 0.2)
		(layer "B.Cu")
		(net 18)
	)
	(segment
		(start 76.9585 151.2415)
		(end 76.45 151.75)
		(width 0.127)
		(layer "B.Cu")
		(net 18)
	)
	(segment
		(start 82.665962 154.2145)
		(end 82.717962 154.2665)
		(width 0.127)
		(layer "B.Cu")
		(net 18)
	)
	(segment
		(start 82.717962 153.305)
		(end 82.717962 154.5165)
		(width 0.2)
		(layer "B.Cu")
		(net 18)
	)
	(segment
		(start 78.282962 151.2415)
		(end 76.9585 151.2415)
		(width 0.127)
		(layer "B.Cu")
		(net 18)
	)
	(segment
		(start 83.010462 162.889)
		(end 80.058462 162.889)
		(width 0.127)
		(layer "In2.Cu")
		(net 18)
	)
	(segment
		(start 80.058462 162.889)
		(end 79.804462 163.143)
		(width 0.127)
		(layer "In2.Cu")
		(net 18)
	)
	(segment
		(start 83.187962 163.0665)
		(end 83.010462 162.889)
		(width 0.127)
		(layer "In2.Cu")
		(net 18)
	)
	(segment
		(start 133.864962 157.3155)
		(end 133.864962 154.5745)
		(width 0.4)
		(layer "F.Cu")
		(net 19)
	)
	(segment
		(start 133.872962 153.816278)
		(end 134.045351 153.643889)
		(width 0.4)
		(layer "F.Cu")
		(net 19)
	)
	(segment
		(start 134.627962 153.6665)
		(end 134.02274 153.6665)
		(width 0.4)
		(layer "F.Cu")
		(net 19)
	)
	(segment
		(start 133.872962 154.5665)
		(end 133.872962 153.816278)
		(width 0.4)
		(layer "F.Cu")
		(net 19)
	)
	(segment
		(start 133.864962 154.5745)
		(end 133.872962 154.5665)
		(width 0.4)
		(layer "F.Cu")
		(net 19)
	)
	(segment
		(start 134.02274 153.6665)
		(end 133.872962 153.816278)
		(width 0.4)
		(layer "F.Cu")
		(net 19)
	)
	(via
		(at 134.627962 153.6665)
		(size 0.45)
		(drill 0.1)
		(layers "F.Cu" "B.Cu")
		(net 19)
	)
	(via
		(at 134.045351 153.643889)
		(size 0.45)
		(drill 0.1)
		(layers "F.Cu" "B.Cu")
		(net 19)
	)
	(segment
		(start 134.067962 153.6665)
		(end 134.045351 153.643889)
		(width 0.4)
		(layer "B.Cu")
		(net 19)
	)
	(segment
		(start 134.592962 146.9505)
		(end 135.700962 146.9505)
		(width 0.254)
		(layer "B.Cu")
		(net 19)
	)
	(segment
		(start 134.128962 146.9755)
		(end 134.567962 146.9755)
		(width 0.4)
		(layer "B.Cu")
		(net 19)
	)
	(segment
		(start 133.972962 147.1315)
		(end 134.128962 146.9755)
		(width 0.4)
		(layer "B.Cu")
		(net 19)
	)
	(segment
		(start 136.244962 146.4655)
		(end 135.767962 146.9425)
		(width 0.2)
		(layer "B.Cu")
		(net 19)
	)
	(segment
		(start 137.467962 146.4655)
		(end 136.244962 146.4655)
		(width 0.2)
		(layer "B.Cu")
		(net 19)
	)
	(segment
		(start 135.767962 146.9425)
		(end 134.600962 146.9425)
		(width 0.4)
		(layer "B.Cu")
		(net 19)
	)
	(segment
		(start 137.467962 146.9655)
		(end 135.719962 146.9655)
		(width 0.254)
		(layer "B.Cu")
		(net 19)
	)
	(segment
		(start 134.045351 153.643889)
		(end 133.972962 153.5715)
		(width 0.4)
		(layer "B.Cu")
		(net 19)
	)
	(segment
		(start 134.600962 146.9425)
		(end 134.567962 146.9755)
		(width 0.4)
		(layer "B.Cu")
		(net 19)
	)
	(segment
		(start 134.627962 153.6665)
		(end 134.067962 153.6665)
		(width 0.4)
		(layer "B.Cu")
		(net 19)
	)
	(segment
		(start 133.972962 153.5715)
		(end 133.972962 147.1315)
		(width 0.4)
		(layer "B.Cu")
		(net 19)
	)
	(segment
		(start 138.264962 153.480359)
		(end 137.637962 152.853359)
		(width 0.254)
		(layer "F.Cu")
		(net 20)
	)
	(segment
		(start 138.272962 157.3075)
		(end 138.264962 157.3155)
		(width 0.4)
		(layer "F.Cu")
		(net 20)
	)
	(segment
		(start 139.5345 157.3155)
		(end 138.264962 157.3155)
		(width 0.254)
		(layer "F.Cu")
		(net 20)
	)
	(segment
		(start 138.272962 154.8665)
		(end 138.272962 157.3075)
		(width 0.4)
		(layer "F.Cu")
		(net 20)
	)
	(segment
		(start 138.264962 157.3155)
		(end 138.264962 153.480359)
		(width 0.254)
		(layer "F.Cu")
		(net 20)
	)
	(segment
		(start 139.55 157.3)
		(end 139.5345 157.3155)
		(width 0.254)
		(layer "F.Cu")
		(net 20)
	)
	(segment
		(start 138.272962 153.488359)
		(end 137.567143 152.78254)
		(width 0.4)
		(layer "F.Cu")
		(net 20)
	)
	(segment
		(start 137.567962 152.123889)
		(end 137.567962 152.78911)
		(width 0.4)
		(layer "F.Cu")
		(net 20)
	)
	(segment
		(start 138.272962 154.8665)
		(end 138.272962 153.488359)
		(width 0.4)
		(layer "F.Cu")
		(net 20)
	)
	(via
		(at 137.567962 152.1165)
		(size 0.45)
		(drill 0.1)
		(layers "F.Cu" "B.Cu")
		(net 20)
	)
	(via
		(at 137.567143 152.78254)
		(size 0.45)
		(drill 0.1)
		(layers "F.Cu" "B.Cu")
		(net 20)
	)
	(segment
		(start 136.342962 150.8915)
		(end 137.567962 152.1165)
		(width 0.4)
		(layer "B.Cu")
		(net 20)
	)
	(segment
		(start 135.691962 147.9915)
		(end 134.674962 147.9915)
		(width 0.254)
		(layer "B.Cu")
		(net 20)
	)
	(segment
		(start 137.567962 152.1165)
		(end 137.567962 152.781721)
		(width 0.4)
		(layer "B.Cu")
		(net 20)
	)
	(segment
		(start 136.217962 147.4655)
		(end 137.467962 147.4655)
		(width 0.2)
		(layer "B.Cu")
		(net 20)
	)
	(segment
		(start 134.625962 147.9655)
		(end 134.617962 147.9575)
		(width 0.4)
		(layer "B.Cu")
		(net 20)
	)
	(segment
		(start 136.342962 149.05064)
		(end 136.342962 150.8915)
		(width 0.4)
		(layer "B.Cu")
		(net 20)
	)
	(segment
		(start 135.717962 148.42564)
		(end 136.342962 149.05064)
		(width 0.4)
		(layer "B.Cu")
		(net 20)
	)
	(segment
		(start 135.717962 148.3165)
		(end 135.717962 147.9655)
		(width 0.254)
		(layer "B.Cu")
		(net 20)
	)
	(segment
		(start 137.467962 147.9655)
		(end 135.767962 147.9655)
		(width 0.254)
		(layer "B.Cu")
		(net 20)
	)
	(segment
		(start 135.717962 147.9655)
		(end 135.717962 148.42564)
		(width 0.4)
		(layer "B.Cu")
		(net 20)
	)
	(segment
		(start 137.567962 152.781721)
		(end 137.567143 152.78254)
		(width 0.4)
		(layer "B.Cu")
		(net 20)
	)
	(segment
		(start 135.717962 147.9655)
		(end 134.625962 147.9655)
		(width 0.4)
		(layer "B.Cu")
		(net 20)
	)
	(segment
		(start 136.217962 147.4655)
		(end 135.717962 147.9655)
		(width 0.2)
		(layer "B.Cu")
		(net 20)
	)
	(segment
		(start 39.3 160.4)
		(end 39.35 160.4)
		(width 0.254)
		(layer "F.Cu")
		(net 21)
	)
	(segment
		(start 39.35 160.4)
		(end 40.1 161.15)
		(width 0.254)
		(layer "F.Cu")
		(net 21)
	)
	(via
		(at 40.1 161.15)
		(size 0.45)
		(drill 0.1)
		(layers "F.Cu" "B.Cu")
		(net 21)
	)
	(segment
		(start 47.217962 156.7165)
		(end 47.217962 157.4825)
		(width 0.5)
		(layer "B.Cu")
		(net 21)
	)
	(segment
		(start 82.338462 162.117)
		(end 81.554961 162.117)
		(width 0.127)
		(layer "F.Cu")
		(net 22)
	)
	(segment
		(start 81.077961 162.516)
		(end 81.554961 162.516)
		(width 0.127)
		(layer "F.Cu")
		(net 22)
	)
	(segment
		(start 80.173962 164.223264)
		(end 80.721962 163.675264)
		(width 0.127)
		(layer "F.Cu")
		(net 22)
	)
	(segment
		(start 80.721962 163.675264)
		(end 80.721962 162.871999)
		(width 0.127)
		(layer "F.Cu")
		(net 22)
	)
	(segment
		(start 82.668462 162.516)
		(end 81.554961 162.516)
		(width 0.127)
		(layer "F.Cu")
		(net 22)
	)
	(segment
		(start 79.997962 165.030042)
		(end 80.173962 164.854042)
		(width 0.127)
		(layer "F.Cu")
		(net 22)
	)
	(segment
		(start 79.997962 166.0265)
		(end 79.997962 165.030042)
		(width 0.127)
		(layer "F.Cu")
		(net 22)
	)
	(segment
		(start 82.702962 162.4815)
		(end 82.338462 162.117)
		(width 0.127)
		(layer "F.Cu")
		(net 22)
	)
	(segment
		(start 80.173962 164.854042)
		(end 80.173962 164.223264)
		(width 0.127)
		(layer "F.Cu")
		(net 22)
	)
	(segment
		(start 80.721962 162.871999)
		(end 81.077961 162.516)
		(width 0.127)
		(layer "F.Cu")
		(net 22)
	)
	(via
		(at 74.9 151.45)
		(size 0.45)
		(drill 0.1)
		(layers "F.Cu" "B.Cu")
		(net 22)
	)
	(via
		(at 79.997962 166.0265)
		(size 0.45)
		(drill 0.1)
		(layers "F.Cu" "B.Cu")
		(net 22)
	)
	(segment
		(start 75.306462 161.619893)
		(end 75.306462 156.65)
		(width 0.127)
		(layer "B.Cu")
		(net 22)
	)
	(segment
		(start 73.692962 151.1165)
		(end 72.55 151.1165)
		(width 0.15)
		(layer "B.Cu")
		(net 22)
	)
	(segment
		(start 79.713069 166.0265)
		(end 75.306462 161.619893)
		(width 0.127)
		(layer "B.Cu")
		(net 22)
	)
	(segment
		(start 75.306462 156.65)
		(end 72.55 153.893538)
		(width 0.127)
		(layer "B.Cu")
		(net 22)
	)
	(segment
		(start 74.9 151.43)
		(end 74.5865 151.1165)
		(width 0.15)
		(layer "B.Cu")
		(net 22)
	)
	(segment
		(start 79.997962 166.0265)
		(end 79.713069 166.0265)
		(width 0.127)
		(layer "B.Cu")
		(net 22)
	)
	(segment
		(start 74.5865 151.1165)
		(end 73.692962 151.1165)
		(width 0.15)
		(layer "B.Cu")
		(net 22)
	)
	(segment
		(start 72.55 153.893538)
		(end 72.55 151.1165)
		(width 0.127)
		(layer "B.Cu")
		(net 22)
	)
	(segment
		(start 107.645423 129.402389)
		(end 107.64542 129.402388)
		(width 0.15)
		(layer "F.Cu")
		(net 23)
	)
	(segment
		(start 110.027462 127.020346)
		(end 109.059635 127.988173)
		(width 0.15)
		(layer "F.Cu")
		(net 23)
	)
	(segment
		(start 107.64542 129.87615)
		(end 108.600531 130.831261)
		(width 0.15)
		(layer "F.Cu")
		(net 23)
	)
	(segment
		(start 110.112462 124.980325)
		(end 110.112462 124.622)
		(width 0.153)
		(layer "F.Cu")
		(net 23)
	)
	(segment
		(start 116.114462 162.4815)
		(end 116.732963 162.481501)
		(width 0.15)
		(layer "F.Cu")
		(net 23)
	)
	(segment
		(start 110.112462 125.729)
		(end 110.112462 126.085251)
		(width 0.15)
		(layer "F.Cu")
		(net 23)
	)
	(segment
		(start 104.842962 132.204846)
		(end 104.842962 133.968154)
		(width 0.15)
		(layer "F.Cu")
		(net 23)
	)
	(segment
		(start 105.524098 131.523707)
		(end 105.524098 131.523708)
		(width 0.15)
		(layer "F.Cu")
		(net 23)
	)
	(segment
		(start 110.112462 124.622)
		(end 110.367962 124.3665)
		(width 0.153)
		(layer "F.Cu")
		(net 23)
	)
	(segment
		(start 105.276307 134.401499)
		(end 105.432963 134.401499)
		(width 0.15)
		(layer "F.Cu")
		(net 23)
	)
	(segment
		(start 107.645421 129.40239)
		(end 107.645423 129.402389)
		(width 0.15)
		(layer "F.Cu")
		(net 23)
	)
	(segment
		(start 109.059635 128.461935)
		(end 110.014746 129.417046)
		(width 0.15)
		(layer "F.Cu")
		(net 23)
	)
	(segment
		(start 104.842962 133.968154)
		(end 105.276307 134.401499)
		(width 0.15)
		(layer "F.Cu")
		(net 23)
	)
	(segment
		(start 110.014746 130.357498)
		(end 110.014745 130.3575)
		(width 0.15)
		(layer "F.Cu")
		(net 23)
	)
	(segment
		(start 116.732963 162.481501)
		(end 116.892962 162.6415)
		(width 0.15)
		(layer "F.Cu")
		(net 23)
	)
	(segment
		(start 115.554961 162.516)
		(end 116.079962 162.516)
		(width 0.15)
		(layer "F.Cu")
		(net 23)
	)
	(segment
		(start 110.027462 126.170251)
		(end 110.027462 127.020346)
		(width 0.15)
		(layer "F.Cu")
		(net 23)
	)
	(segment
		(start 110.112462 126.085251)
		(end 110.027462 126.170251)
		(width 0.15)
		(layer "F.Cu")
		(net 23)
	)
	(segment
		(start 105.524098 131.523708)
		(end 104.842962 132.204846)
		(width 0.15)
		(layer "F.Cu")
		(net 23)
	)
	(segment
		(start 116.079962 162.516)
		(end 116.114462 162.4815)
		(width 0.15)
		(layer "F.Cu")
		(net 23)
	)
	(segment
		(start 104.993234 129.578631)
		(end 104.993235 129.578631)
		(width 0.15)
		(layer "F.Cu")
		(net 23)
	)
	(segment
		(start 110.113462 125.755325)
		(end 110.113462 124.981325)
		(width 0.153)
		(layer "F.Cu")
		(net 23)
	)
	(segment
		(start 108.600531 131.771713)
		(end 108.60053 131.771715)
		(width 0.15)
		(layer "F.Cu")
		(net 23)
	)
	(segment
		(start 110.367962 124.3665)
		(end 110.367962 122.578958)
		(width 0.153)
		(layer "F.Cu")
		(net 23)
	)
	(segment
		(start 104.993235 130.052392)
		(end 105.524098 130.583255)
		(width 0.15)
		(layer "F.Cu")
		(net 23)
	)
	(segment
		(start 105.466996 129.578631)
		(end 107.660078 131.771715)
		(width 0.15)
		(layer "F.Cu")
		(net 23)
	)
	(segment
		(start 104.993235 130.052391)
		(end 104.993235 130.052392)
		(width 0.15)
		(layer "F.Cu")
		(net 23)
	)
	(segment
		(start 109.074293 130.3575)
		(end 108.119183 129.40239)
		(width 0.15)
		(layer "F.Cu")
		(net 23)
	)
	(segment
		(start 105.432963 134.401499)
		(end 105.592962 134.2415)
		(width 0.15)
		(layer "F.Cu")
		(net 23)
	)
	(via
		(at 116.892962 162.6415)
		(size 0.45)
		(drill 0.1)
		(layers "F.Cu" "B.Cu")
		(net 23)
	)
	(via
		(at 105.592962 134.2415)
		(size 0.45)
		(drill 0.1)
		(layers "F.Cu" "B.Cu")
		(net 23)
	)
	(arc
		(start 108.119183 129.40239)
		(mid 107.882302 129.304271)
		(end 107.645421 129.40239)
		(width 0.15)
		(layer "F.Cu")
		(net 23)
	)
	(arc
		(start 110.014746 129.417046)
		(mid 110.20952 129.887272)
		(end 110.014746 130.357498)
		(width 0.15)
		(layer "F.Cu")
		(net 23)
	)
	(arc
		(start 108.60053 131.771715)
		(mid 108.130304 131.966489)
		(end 107.660078 131.771715)
		(width 0.15)
		(layer "F.Cu")
		(net 23)
	)
	(arc
		(start 108.600531 130.831261)
		(mid 108.795305 131.301487)
		(end 108.600531 131.771713)
		(width 0.15)
		(layer "F.Cu")
		(net 23)
	)
	(arc
		(start 105.466996 129.578631)
		(mid 105.230115 129.480512)
		(end 104.993234 129.578631)
		(width 0.15)
		(layer "F.Cu")
		(net 23)
	)
	(arc
		(start 110.014745 130.3575)
		(mid 109.544519 130.552274)
		(end 109.074293 130.3575)
		(width 0.15)
		(layer "F.Cu")
		(net 23)
	)
	(arc
		(start 105.524098 130.583255)
		(mid 105.718872 131.053481)
		(end 105.524098 131.523707)
		(width 0.15)
		(layer "F.Cu")
		(net 23)
	)
	(arc
		(start 109.059635 127.988173)
		(mid 108.961516 128.225054)
		(end 109.059635 128.461935)
		(width 0.15)
		(layer "F.Cu")
		(net 23)
	)
	(arc
		(start 107.64542 129.402388)
		(mid 107.547301 129.639269)
		(end 107.64542 129.87615)
		(width 0.15)
		(layer "F.Cu")
		(net 23)
	)
	(arc
		(start 104.993235 129.578631)
		(mid 104.895116 129.815511)
		(end 104.993235 130.052391)
		(width 0.15)
		(layer "F.Cu")
		(net 23)
	)
	(segment
		(start 115.447962 156.504)
		(end 115.447962 159.9065)
		(width 0.15)
		(layer "B.Cu")
		(net 23)
	)
	(segment
		(start 114.797962 156.2165)
		(end 114.800462 156.219)
		(width 0.15)
		(layer "B.Cu")
		(net 23)
	)
	(segment
		(start 116.732963 162.481501)
		(end 116.892962 162.6415)
		(width 0.15)
		(layer "B.Cu")
		(net 23)
	)
	(segment
		(start 114.800462 156.219)
		(end 115.162962 156.219)
		(width 0.15)
		(layer "B.Cu")
		(net 23)
	)
	(segment
		(start 105.432963 134.401499)
		(end 105.239617 134.401499)
		(width 0.15)
		(layer "B.Cu")
		(net 23)
	)
	(segment
		(start 115.999617 162.481501)
		(end 116.732963 162.481501)
		(width 0.15)
		(layer "B.Cu")
		(net 23)
	)
	(segment
		(start 107.679616 158.8815)
		(end 113.897962 158.8815)
		(width 0.15)
		(layer "B.Cu")
		(net 23)
	)
	(segment
		(start 115.447962 161.929846)
		(end 115.999617 162.481501)
		(width 0.15)
		(layer "B.Cu")
		(net 23)
	)
	(segment
		(start 105.592962 134.2415)
		(end 105.432963 134.401499)
		(width 0.15)
		(layer "B.Cu")
		(net 23)
	)
	(segment
		(start 115.447962 161.7065)
		(end 115.447962 161.929846)
		(width 0.15)
		(layer "B.Cu")
		(net 23)
	)
	(segment
		(start 105.239617 134.401499)
		(end 104.822962 134.818154)
		(width 0.15)
		(layer "B.Cu")
		(net 23)
	)
	(segment
		(start 114.197962 161.4215)
		(end 115.162962 161.4215)
		(width 0.15)
		(layer "B.Cu")
		(net 23)
	)
	(segment
		(start 104.822962 156.024846)
		(end 107.679616 158.8815)
		(width 0.15)
		(layer "B.Cu")
		(net 23)
	)
	(segment
		(start 104.822962 134.818154)
		(end 104.822962 156.024846)
		(width 0.15)
		(layer "B.Cu")
		(net 23)
	)
	(segment
		(start 114.512962 158.2665)
		(end 114.512962 156.5015)
		(width 0.15)
		(layer "B.Cu")
		(net 23)
	)
	(segment
		(start 115.162962 160.1915)
		(end 114.197962 160.1915)
		(width 0.15)
		(layer "B.Cu")
		(net 23)
	)
	(arc
		(start 114.197962 160.1915)
		(mid 113.763091 160.371629)
		(end 113.582962 160.8065)
		(width 0.15)
		(layer "B.Cu")
		(net 23)
	)
	(arc
		(start 113.897962 158.8815)
		(mid 114.332833 158.701371)
		(end 114.512962 158.2665)
		(width 0.15)
		(layer "B.Cu")
		(net 23)
	)
	(arc
		(start 113.582962 160.8065)
		(mid 113.763091 161.241371)
		(end 114.197962 161.4215)
		(width 0.15)
		(layer "B.Cu")
		(net 23)
	)
	(arc
		(start 115.162962 161.4215)
		(mid 115.364487 161.504975)
		(end 115.447962 161.7065)
		(width 0.15)
		(layer "B.Cu")
		(net 23)
	)
	(arc
		(start 114.512962 156.5015)
		(mid 114.596437 156.299975)
		(end 114.797962 156.2165)
		(width 0.15)
		(layer "B.Cu")
		(net 23)
	)
	(arc
		(start 115.447962 159.9065)
		(mid 115.364487 160.108025)
		(end 115.162962 160.1915)
		(width 0.15)
		(layer "B.Cu")
		(net 23)
	)
	(arc
		(start 115.162962 156.219)
		(mid 115.364487 156.302475)
		(end 115.447962 156.504)
		(width 0.15)
		(layer "B.Cu")
		(net 23)
	)
	(segment
		(start 95.417962 119.1165)
		(end 95.417962 118.6415)
		(width 0.254)
		(layer "F.Cu")
		(net 24)
	)
	(segment
		(start 83.068962 156.0665)
		(end 83.767962 156.0665)
		(width 0.2)
		(layer "F.Cu")
		(net 24)
	)
	(segment
		(start 95.413962 121.7165)
		(end 94.767962 121.7165)
		(width 0.254)
		(layer "F.Cu")
		(net 24)
	)
	(segment
		(start 83.907962 154.8915)
		(end 83.018962 155.7805)
		(width 0.2)
		(layer "F.Cu")
		(net 24)
	)
	(segment
		(start 93.962962 117.1865)
		(end 92.159436 117.1865)
		(width 0.254)
		(layer "F.Cu")
		(net 24)
	)
	(segment
		(start 95.413962 122.6565)
		(end 95.413962 119.1205)
		(width 0.4)
		(layer "F.Cu")
		(net 24)
	)
	(segment
		(start 95.411292 126.0695)
		(end 95.411292 122.65917)
		(width 0.5)
		(layer "F.Cu")
		(net 24)
	)
	(segment
		(start 90.75 121.65)
		(end 90.2835 122.1165)
		(width 0.15)
		(layer "F.Cu")
		(net 24)
	)
	(segment
		(start 92.159436 117.1865)
		(end 90.619962 118.725974)
		(width 0.254)
		(layer "F.Cu")
		(net 24)
	)
	(segment
		(start 90.619962 120.6165)
		(end 90.619962 119.1165)
		(width 0.15)
		(layer "F.Cu")
		(net 24)
	)
	(segment
		(start 98.8 117.514462)
		(end 98.8 118.17)
		(width 0.254)
		(layer "F.Cu")
		(net 24)
	)
	(segment
		(start 95.417962 118.6415)
		(end 93.962962 117.1865)
		(width 0.254)
		(layer "F.Cu")
		(net 24)
	)
	(segment
		(start 90.75 120.746538)
		(end 90.619962 120.6165)
		(width 0.15)
		(layer "F.Cu")
		(net 24)
	)
	(segment
		(start 98.847962 117.4665)
		(end 98.8 117.514462)
		(width 0.254)
		(layer "F.Cu")
		(net 24)
	)
	(segment
		(start 90.75 121.65)
		(end 90.75 120.746538)
		(width 0.15)
		(layer "F.Cu")
		(net 24)
	)
	(segment
		(start 90.2835 122.1165)
		(end 89.277962 122.1165)
		(width 0.15)
		(layer "F.Cu")
		(net 24)
	)
	(segment
		(start 94.442962 126.0415)
		(end 95.383292 126.0415)
		(width 0.127)
		(layer "F.Cu")
		(net 24)
	)
	(via
		(at 83.767962 156.0665)
		(size 0.45)
		(drill 0.1)
		(layers "F.Cu" "B.Cu")
		(net 24)
	)
	(via
		(at 94.767962 121.7165)
		(size 0.45)
		(drill 0.1)
		(layers "F.Cu" "B.Cu")
		(net 24)
	)
	(via
		(at 94.442962 126.0415)
		(size 0.45)
		(drill 0.1)
		(layers "F.Cu" "B.Cu")
		(net 24)
	)
	(via
		(at 98.847962 117.4665)
		(size 0.45)
		(drill 0.1)
		(layers "F.Cu" "B.Cu")
		(net 24)
	)
	(segment
		(start 83.767962 150.865972)
		(end 83.767962 156.0665)
		(width 0.127)
		(layer "B.Cu")
		(net 24)
	)
	(segment
		(start 95.067962 131.226278)
		(end 94.441962 131.852278)
		(width 0.127)
		(layer "B.Cu")
		(net 24)
	)
	(segment
		(start 98.847962 119.3115)
		(end 96.442962 121.7165)
		(width 0.254)
		(layer "B.Cu")
		(net 24)
	)
	(segment
		(start 94.693962 138.5175)
		(end 95.563962 139.3875)
		(width 0.127)
		(layer "B.Cu")
		(net 24)
	)
	(segment
		(start 85.209962 148.048972)
		(end 85.209962 149.423972)
		(width 0.127)
		(layer "B.Cu")
		(net 24)
	)
	(segment
		(start 89.475962 145.5085)
		(end 87.750434 145.5085)
		(width 0.127)
		(layer "B.Cu")
		(net 24)
	)
	(segment
		(start 94.442962 126.0415)
		(end 93.755462 126.729)
		(width 0.127)
		(layer "B.Cu")
		(net 24)
	)
	(segment
		(start 94.441962 138.275278)
		(end 94.684184 138.5175)
		(width 0.127)
		(layer "B.Cu")
		(net 24)
	)
	(segment
		(start 98.847962 117.4665)
		(end 98.847962 119.3115)
		(width 0.254)
		(layer "B.Cu")
		(net 24)
	)
	(segment
		(start 87.750434 145.5085)
		(end 85.209962 148.048972)
		(width 0.127)
		(layer "B.Cu")
		(net 24)
	)
	(segment
		(start 93.755462 129.913778)
		(end 95.067962 131.226278)
		(width 0.127)
		(layer "B.Cu")
		(net 24)
	)
	(segment
		(start 85.209962 149.423972)
		(end 83.767962 150.865972)
		(width 0.127)
		(layer "B.Cu")
		(net 24)
	)
	(segment
		(start 93.755462 126.729)
		(end 93.755462 129.913778)
		(width 0.127)
		(layer "B.Cu")
		(net 24)
	)
	(segment
		(start 95.563962 139.3875)
		(end 95.563962 139.9705)
		(width 0.127)
		(layer "B.Cu")
		(net 24)
	)
	(segment
		(start 94.817962 140.7165)
		(end 94.267962 140.7165)
		(width 0.127)
		(layer "B.Cu")
		(net 24)
	)
	(segment
		(start 94.267962 140.7165)
		(end 89.475962 145.5085)
		(width 0.127)
		(layer "B.Cu")
		(net 24)
	)
	(segment
		(start 94.684184 138.5175)
		(end 94.693962 138.5175)
		(width 0.127)
		(layer "B.Cu")
		(net 24)
	)
	(segment
		(start 94.441962 131.852278)
		(end 94.441962 138.275278)
		(width 0.127)
		(layer "B.Cu")
		(net 24)
	)
	(segment
		(start 96.442962 121.7165)
		(end 94.767962 121.7165)
		(width 0.254)
		(layer "B.Cu")
		(net 24)
	)
	(segment
		(start 95.563962 139.9705)
		(end 94.817962 140.7165)
		(width 0.127)
		(layer "B.Cu")
		(net 24)
	)
	(segment
		(start 109.307639 130.124153)
		(end 108.352529 129.169043)
		(width 0.15)
		(layer "F.Cu")
		(net 25)
	)
	(segment
		(start 107.412075 130.109495)
		(end 108.367186 131.064606)
		(width 0.15)
		(layer "F.Cu")
		(net 25)
	)
	(segment
		(start 105.139617 134.731501)
		(end 105.432963 134.731501)
		(width 0.15)
		(layer "F.Cu")
		(net 25)
	)
	(segment
		(start 116.079962 162.117)
		(end 116.114462 162.1515)
		(width 0.15)
		(layer "F.Cu")
		(net 25)
	)
	(segment
		(start 105.290752 131.290363)
		(end 105.290752 131.290362)
		(width 0.15)
		(layer "F.Cu")
		(net 25)
	)
	(segment
		(start 109.369462 124.366)
		(end 109.369462 124.185458)
		(width 0.153)
		(layer "F.Cu")
		(net 25)
	)
	(segment
		(start 116.114462 162.1515)
		(end 116.732963 162.151499)
		(width 0.15)
		(layer "F.Cu")
		(net 25)
	)
	(segment
		(start 104.512962 134.104846)
		(end 105.139617 134.731501)
		(width 0.15)
		(layer "F.Cu")
		(net 25)
	)
	(segment
		(start 109.368962 124.184958)
		(end 109.368962 122.578958)
		(width 0.153)
		(layer "F.Cu")
		(net 25)
	)
	(segment
		(start 109.613462 125.385825)
		(end 109.613462 124.61)
		(width 0.153)
		(layer "F.Cu")
		(net 25)
	)
	(segment
		(start 109.612462 125.729)
		(end 109.612462 126.085251)
		(width 0.15)
		(layer "F.Cu")
		(net 25)
	)
	(segment
		(start 109.697462 126.883654)
		(end 108.82629 127.754828)
		(width 0.15)
		(layer "F.Cu")
		(net 25)
	)
	(segment
		(start 104.759889 130.285738)
		(end 105.290752 130.816601)
		(width 0.15)
		(layer "F.Cu")
		(net 25)
	)
	(segment
		(start 105.432963 134.731501)
		(end 105.592962 134.8915)
		(width 0.15)
		(layer "F.Cu")
		(net 25)
	)
	(segment
		(start 116.732963 162.151499)
		(end 116.892962 161.9915)
		(width 0.15)
		(layer "F.Cu")
		(net 25)
	)
	(segment
		(start 109.613462 125.755325)
		(end 109.613462 124.980325)
		(width 0.153)
		(layer "F.Cu")
		(net 25)
	)
	(segment
		(start 107.412077 129.169043)
		(end 107.412075 129.169042)
		(width 0.15)
		(layer "F.Cu")
		(net 25)
	)
	(segment
		(start 109.697462 126.170251)
		(end 109.697462 126.883654)
		(width 0.15)
		(layer "F.Cu")
		(net 25)
	)
	(segment
		(start 104.512962 132.068154)
		(end 104.512962 134.104846)
		(width 0.15)
		(layer "F.Cu")
		(net 25)
	)
	(segment
		(start 115.554961 162.117)
		(end 116.079962 162.117)
		(width 0.15)
		(layer "F.Cu")
		(net 25)
	)
	(segment
		(start 105.290752 131.290362)
		(end 104.512962 132.068154)
		(width 0.15)
		(layer "F.Cu")
		(net 25)
	)
	(segment
		(start 109.612462 126.085251)
		(end 109.697462 126.170251)
		(width 0.15)
		(layer "F.Cu")
		(net 25)
	)
	(segment
		(start 109.369462 124.185458)
		(end 109.368962 124.184958)
		(width 0.153)
		(layer "F.Cu")
		(net 25)
	)
	(segment
		(start 105.700341 129.345286)
		(end 107.893424 131.538368)
		(width 0.15)
		(layer "F.Cu")
		(net 25)
	)
	(segment
		(start 108.82629 128.69528)
		(end 109.781401 129.650391)
		(width 0.15)
		(layer "F.Cu")
		(net 25)
	)
	(segment
		(start 109.613462 124.61)
		(end 109.369462 124.366)
		(width 0.153)
		(layer "F.Cu")
		(net 25)
	)
	(segment
		(start 107.412075 129.169042)
		(end 107.412075 129.169043)
		(width 0.15)
		(layer "F.Cu")
		(net 25)
	)
	(via
		(at 105.592962 134.8915)
		(size 0.45)
		(drill 0.1)
		(layers "F.Cu" "B.Cu")
		(net 25)
	)
	(via
		(at 116.892962 161.9915)
		(size 0.45)
		(drill 0.1)
		(layers "F.Cu" "B.Cu")
		(net 25)
	)
	(arc
		(start 108.82629 127.754828)
		(mid 108.631516 128.225054)
		(end 108.82629 128.69528)
		(width 0.15)
		(layer "F.Cu")
		(net 25)
	)
	(arc
		(start 108.367186 131.538368)
		(mid 108.130305 131.636487)
		(end 107.893424 131.538368)
		(width 0.15)
		(layer "F.Cu")
		(net 25)
	)
	(arc
		(start 107.412075 129.169043)
		(mid 107.217301 129.639269)
		(end 107.412075 130.109495)
		(width 0.15)
		(layer "F.Cu")
		(net 25)
	)
	(arc
		(start 105.700341 129.345286)
		(mid 105.230115 129.150512)
		(end 104.759889 129.345286)
		(width 0.15)
		(layer "F.Cu")
		(net 25)
	)
	(arc
		(start 105.290752 130.816601)
		(mid 105.388871 131.053482)
		(end 105.290752 131.290363)
		(width 0.15)
		(layer "F.Cu")
		(net 25)
	)
	(arc
		(start 108.367186 131.064606)
		(mid 108.465305 131.301487)
		(end 108.367186 131.538368)
		(width 0.15)
		(layer "F.Cu")
		(net 25)
	)
	(arc
		(start 108.352529 129.169043)
		(mid 107.882303 128.974269)
		(end 107.412077 129.169043)
		(width 0.15)
		(layer "F.Cu")
		(net 25)
	)
	(arc
		(start 109.781401 130.124153)
		(mid 109.54452 130.222272)
		(end 109.307639 130.124153)
		(width 0.15)
		(layer "F.Cu")
		(net 25)
	)
	(arc
		(start 109.781401 129.650391)
		(mid 109.87952 129.887272)
		(end 109.781401 130.124153)
		(width 0.15)
		(layer "F.Cu")
		(net 25)
	)
	(arc
		(start 104.759889 129.345286)
		(mid 104.565115 129.815512)
		(end 104.759889 130.285738)
		(width 0.15)
		(layer "F.Cu")
		(net 25)
	)
	(segment
		(start 105.376307 134.731501)
		(end 105.152962 134.954846)
		(width 0.15)
		(layer "B.Cu")
		(net 25)
	)
	(segment
		(start 116.136307 162.151499)
		(end 116.732963 162.151499)
		(width 0.15)
		(layer "B.Cu")
		(net 25)
	)
	(segment
		(start 115.777962 156.504)
		(end 115.777962 159.9065)
		(width 0.15)
		(layer "B.Cu")
		(net 25)
	)
	(segment
		(start 114.182962 158.2665)
		(end 114.182962 156.5015)
		(width 0.15)
		(layer "B.Cu")
		(net 25)
	)
	(segment
		(start 105.152962 155.888154)
		(end 107.816308 158.5515)
		(width 0.15)
		(layer "B.Cu")
		(net 25)
	)
	(segment
		(start 115.777962 161.793154)
		(end 116.136307 162.151499)
		(width 0.15)
		(layer "B.Cu")
		(net 25)
	)
	(segment
		(start 108.627962 158.5515)
		(end 113.897962 158.5515)
		(width 0.15)
		(layer "B.Cu")
		(net 25)
	)
	(segment
		(start 105.152962 134.954846)
		(end 105.152962 155.888154)
		(width 0.15)
		(layer "B.Cu")
		(net 25)
	)
	(segment
		(start 108.227962 158.4015)
		(end 108.477962 158.4015)
		(width 0.15)
		(layer "B.Cu")
		(net 25)
	)
	(segment
		(start 105.592962 134.8915)
		(end 105.432963 134.731501)
		(width 0.15)
		(layer "B.Cu")
		(net 25)
	)
	(segment
		(start 116.732963 162.151499)
		(end 116.892962 161.9915)
		(width 0.15)
		(layer "B.Cu")
		(net 25)
	)
	(segment
		(start 115.777962 161.7065)
		(end 115.777962 161.793154)
		(width 0.15)
		(layer "B.Cu")
		(net 25)
	)
	(segment
		(start 115.162962 160.5215)
		(end 114.197962 160.5215)
		(width 0.15)
		(layer "B.Cu")
		(net 25)
	)
	(segment
		(start 107.816308 158.5515)
		(end 108.077962 158.5515)
		(width 0.15)
		(layer "B.Cu")
		(net 25)
	)
	(segment
		(start 114.197962 161.0915)
		(end 115.162962 161.0915)
		(width 0.15)
		(layer "B.Cu")
		(net 25)
	)
	(segment
		(start 114.797962 155.8865)
		(end 114.800462 155.889)
		(width 0.15)
		(layer "B.Cu")
		(net 25)
	)
	(segment
		(start 105.432963 134.731501)
		(end 105.376307 134.731501)
		(width 0.15)
		(layer "B.Cu")
		(net 25)
	)
	(segment
		(start 114.800462 155.889)
		(end 115.162962 155.889)
		(width 0.15)
		(layer "B.Cu")
		(net 25)
	)
	(arc
		(start 115.162962 161.0915)
		(mid 115.597833 161.271629)
		(end 115.777962 161.7065)
		(width 0.15)
		(layer "B.Cu")
		(net 25)
	)
	(arc
		(start 115.777962 159.9065)
		(mid 115.597833 160.341371)
		(end 115.162962 160.5215)
		(width 0.15)
		(layer "B.Cu")
		(net 25)
	)
	(arc
		(start 108.152962 158.4765)
		(mid 108.174929 158.423467)
		(end 108.227962 158.4015)
		(width 0.15)
		(layer "B.Cu")
		(net 25)
	)
	(arc
		(start 113.897962 158.5515)
		(mid 114.099487 158.468025)
		(end 114.182962 158.2665)
		(width 0.15)
		(layer "B.Cu")
		(net 25)
	)
	(arc
		(start 114.182962 156.5015)
		(mid 114.363091 156.066629)
		(end 114.797962 155.8865)
		(width 0.15)
		(layer "B.Cu")
		(net 25)
	)
	(arc
		(start 108.077962 158.5515)
		(mid 108.130995 158.529533)
		(end 108.152962 158.4765)
		(width 0.15)
		(layer "B.Cu")
		(net 25)
	)
	(arc
		(start 114.197962 160.5215)
		(mid 113.996437 160.604975)
		(end 113.912962 160.8065)
		(width 0.15)
		(layer "B.Cu")
		(net 25)
	)
	(arc
		(start 108.552962 158.4765)
		(mid 108.574929 158.529533)
		(end 108.627962 158.5515)
		(width 0.15)
		(layer "B.Cu")
		(net 25)
	)
	(arc
		(start 113.912962 160.8065)
		(mid 113.996437 161.008025)
		(end 114.197962 161.0915)
		(width 0.15)
		(layer "B.Cu")
		(net 25)
	)
	(arc
		(start 108.477962 158.4015)
		(mid 108.530995 158.423467)
		(end 108.552962 158.4765)
		(width 0.15)
		(layer "B.Cu")
		(net 25)
	)
	(arc
		(start 115.162962 155.889)
		(mid 115.597833 156.069129)
		(end 115.777962 156.504)
		(width 0.15)
		(layer "B.Cu")
		(net 25)
	)
	(segment
		(start 76.977962 125.5565)
		(end 76.417962 126.1165)
		(width 1)
		(layer "F.Cu")
		(net 26)
	)
	(segment
		(start 77.287962 121.3065)
		(end 77.287962 122.8565)
		(width 1)
		(layer "F.Cu")
		(net 26)
	)
	(segment
		(start 76.332962 127.4865)
		(end 76.332962 126.2015)
		(width 0.4)
		(layer "F.Cu")
		(net 26)
	)
	(segment
		(start 75.667962 126.6555)
		(end 75.774962 126.5485)
		(width 0.4)
		(layer "F.Cu")
		(net 26)
	)
	(segment
		(start 77.197962 121.2165)
		(end 77.287962 121.3065)
		(width 1)
		(layer "F.Cu")
		(net 26)
	)
	(segment
		(start 77.287962 124.2465)
		(end 77.357962 124.2465)
		(width 1)
		(layer "F.Cu")
		(net 26)
	)
	(segment
		(start 76.361962 122.8265)
		(end 77.257962 122.8265)
		(width 0.35)
		(layer "F.Cu")
		(net 26)
	)
	(segment
		(start 76.332962 127.4865)
		(end 76.332962 128.2555)
		(width 0.4)
		(layer "F.Cu")
		(net 26)
	)
	(segment
		(start 75.774962 126.5485)
		(end 76.332962 127.1065)
		(width 0.4)
		(layer "F.Cu")
		(net 26)
	)
	(segment
		(start 80.917962 117.3415)
		(end 78.649698 117.3415)
		(width 0.4)
		(layer "F.Cu")
		(net 26)
	)
	(segment
		(start 77.287962 124.2465)
		(end 77.287962 125.2465)
		(width 1)
		(layer "F.Cu")
		(net 26)
	)
	(segment
		(start 77.357962 124.2465)
		(end 77.367962 124.2365)
		(width 1)
		(layer "F.Cu")
		(net 26)
	)
	(segment
		(start 82.180962 119.635538)
		(end 81.4 120.4165)
		(width 0.4)
		(layer "F.Cu")
		(net 26)
	)
	(segment
		(start 76.332962 127.1065)
		(end 76.332962 127.4865)
		(width 0.4)
		(layer "F.Cu")
		(net 26)
	)
	(segment
		(start 75.667962 128.0485)
		(end 75.667962 126.6555)
		(width 0.4)
		(layer "F.Cu")
		(net 26)
	)
	(segment
		(start 82.180962 119.102)
		(end 82.180962 119.635538)
		(width 0.4)
		(layer "F.Cu")
		(net 26)
	)
	(segment
		(start 77.287962 125.2465)
		(end 76.977962 125.5565)
		(width 1)
		(layer "F.Cu")
		(net 26)
	)
	(segment
		(start 82.180962 118.6045)
		(end 80.917962 117.3415)
		(width 0.4)
		(layer "F.Cu")
		(net 26)
	)
	(segment
		(start 77.287962 122.8565)
		(end 77.287962 124.2465)
		(width 1)
		(layer "F.Cu")
		(net 26)
	)
	(segment
		(start 75.012962 127.3015)
		(end 75.774962 126.5395)
		(width 0.4)
		(layer "F.Cu")
		(net 26)
	)
	(segment
		(start 77.257962 122.8265)
		(end 77.287962 122.8565)
		(width 0.35)
		(layer "F.Cu")
		(net 26)
	)
	(segment
		(start 75.012962 128.2555)
		(end 75.012962 127.3015)
		(width 0.4)
		(layer "F.Cu")
		(net 26)
	)
	(segment
		(start 76.417962 126.1165)
		(end 75.985962 126.5485)
		(width 1)
		(layer "F.Cu")
		(net 26)
	)
	(segment
		(start 77.382962 119.102)
		(end 77.382962 120.7015)
		(width 0.5)
		(layer "F.Cu")
		(net 26)
	)
	(segment
		(start 77.382962 118.608236)
		(end 77.382962 119.102)
		(width 0.4)
		(layer "F.Cu")
		(net 26)
	)
	(segment
		(start 78.649698 117.3415)
		(end 77.382962 118.608236)
		(width 0.4)
		(layer "F.Cu")
		(net 26)
	)
	(segment
		(start 82.180962 119.102)
		(end 82.180962 118.6045)
		(width 0.4)
		(layer "F.Cu")
		(net 26)
	)
	(segment
		(start 76.332962 126.2015)
		(end 76.417962 126.1165)
		(width 0.4)
		(layer "F.Cu")
		(net 26)
	)
	(via
		(at 76.977962 125.5565)
		(size 0.45)
		(drill 0.1)
		(layers "F.Cu" "B.Cu")
		(net 26)
	)
	(via
		(at 80.9 117.35)
		(size 0.45)
		(drill 0.1)
		(layers "F.Cu" "B.Cu")
		(net 26)
	)
	(segment
		(start 86.363962 126.4125)
		(end 86.363962 126.9175)
		(width 0.35)
		(layer "B.Cu")
		(net 26)
	)
	(segment
		(start 82.38 124.828538)
		(end 82.531962 124.9805)
		(width 0.2)
		(layer "B.Cu")
		(net 26)
	)
	(segment
		(start 77.614462 124.92)
		(end 76.977962 125.5565)
		(width 0.4)
		(layer "B.Cu")
		(net 26)
	)
	(segment
		(start 86 116.47)
		(end 81.78 116.47)
		(width 0.254)
		(layer "B.Cu")
		(net 26)
	)
	(segment
		(start 86.017962 126.0665)
		(end 86.363962 126.4125)
		(width 0.35)
		(layer "B.Cu")
		(net 26)
	)
	(segment
		(start 82.38 123.604462)
		(end 82.38 124.828538)
		(width 0.2)
		(layer "B.Cu")
		(net 26)
	)
	(segment
		(start 76.627962 131.8565)
		(end 74.862962 133.6215)
		(width 0.15)
		(layer "B.Cu")
		(net 26)
	)
	(segment
		(start 81.78 116.47)
		(end 80.9 117.35)
		(width 0.254)
		(layer "B.Cu")
		(net 26)
	)
	(segment
		(start 84.667962 126.0665)
		(end 83.617962 126.0665)
		(width 0.4)
		(layer "B.Cu")
		(net 26)
	)
	(segment
		(start 76.977962 125.5565)
		(end 76.627962 125.9065)
		(width 0.15)
		(layer "B.Cu")
		(net 26)
	)
	(segment
		(start 86.357962 122.1665)
		(end 83.817962 122.1665)
		(width 0.2)
		(layer "B.Cu")
		(net 26)
	)
	(segment
		(start 74.862962 133.6215)
		(end 74.862962 135.0565)
		(width 0.15)
		(layer "B.Cu")
		(net 26)
	)
	(segment
		(start 82.531962 124.9805)
		(end 82.471462 124.92)
		(width 0.4)
		(layer "B.Cu")
		(net 26)
	)
	(segment
		(start 83.817962 122.1665)
		(end 82.38 123.604462)
		(width 0.2)
		(layer "B.Cu")
		(net 26)
	)
	(segment
		(start 83.617962 126.0665)
		(end 82.531962 124.9805)
		(width 0.4)
		(layer "B.Cu")
		(net 26)
	)
	(segment
		(start 76.627962 125.9065)
		(end 76.627962 131.8565)
		(width 0.15)
		(layer "B.Cu")
		(net 26)
	)
	(segment
		(start 84.667962 126.0665)
		(end 86.017962 126.0665)
		(width 0.35)
		(layer "B.Cu")
		(net 26)
	)
	(segment
		(start 82.471462 124.92)
		(end 77.614462 124.92)
		(width 0.4)
		(layer "B.Cu")
		(net 26)
	)
	(segment
		(start 85.317962 139.107236)
		(end 84.692962 139.107236)
		(width 0.15)
		(layer "F.Cu")
		(net 27)
	)
	(segment
		(start 89.076962 143.907236)
		(end 89.076962 143.4075)
		(width 0.15)
		(layer "F.Cu")
		(net 27)
	)
	(segment
		(start 86.567962 131.2415)
		(end 86.567962 130.172038)
		(width 0.2)
		(layer "F.Cu")
		(net 27)
	)
	(segment
		(start 86.567962 131.2415)
		(end 86.217962 131.5915)
		(width 0.2)
		(layer "F.Cu")
		(net 27)
	)
	(segment
		(start 92.763072 146.1304)
		(end 92.763072 146.14639)
		(width 0.254)
		(layer "F.Cu")
		(net 27)
	)
	(segment
		(start 101.587962 142.6415)
		(end 101.092962 142.6415)
		(width 0.2)
		(layer "F.Cu")
		(net 27)
	)
	(segment
		(start 75.692962 132.2265)
		(end 75.692962 133.8565)
		(width 0.2)
		(layer "F.Cu")
		(net 27)
	)
	(segment
		(start 87.0735 129.6665)
		(end 87.993962 129.6665)
		(width 0.2)
		(layer "F.Cu")
		(net 27)
	)
	(segment
		(start 94.017962 135.907236)
		(end 94.592962 135.907236)
		(width 0.15)
		(layer "F.Cu")
		(net 27)
	)
	(segment
		(start 81.940698 135.089236)
		(end 81.917962 135.0665)
		(width 0.2)
		(layer "F.Cu")
		(net 27)
	)
	(segment
		(start 92.791305 130.293157)
		(end 92.817962 130.319814)
		(width 0.254)
		(layer "F.Cu")
		(net 27)
	)
	(segment
		(start 101.092962 142.6415)
		(end 99.617962 141.1665)
		(width 0.2)
		(layer "F.Cu")
		(net 27)
	)
	(segment
		(start 89.076962 143.4075)
		(end 89.267962 143.2165)
		(width 0.15)
		(layer "F.Cu")
		(net 27)
	)
	(segment
		(start 84.467962 139.332236)
		(end 84.692962 139.107236)
		(width 0.15)
		(layer "F.Cu")
		(net 27)
	)
	(segment
		(start 96.467962 142.8365)
		(end 96.347962 142.7165)
		(width 0.2)
		(layer "F.Cu")
		(net 27)
	)
	(segment
		(start 88.210698 145.08)
		(end 88.681462 144.609236)
		(width 0.127)
		(layer "F.Cu")
		(net 27)
	)
	(segment
		(start 84.051962 140.307236)
		(end 84.051962 139.332236)
		(width 0.254)
		(layer "F.Cu")
		(net 27)
	)
	(segment
		(start 88.815962 144.609236)
		(end 89.076962 144.348236)
		(width 0.254)
		(layer "F.Cu")
		(net 27)
	)
	(segment
		(start 94.833962 135.907236)
		(end 94.592962 135.907236)
		(width 0.2)
		(layer "F.Cu")
		(net 27)
	)
	(segment
		(start 88.681462 144.609236)
		(end 88.815962 144.609236)
		(width 0.254)
		(layer "F.Cu")
		(net 27)
	)
	(segment
		(start 96.467962 143.7665)
		(end 96.467962 142.8365)
		(width 0.2)
		(layer "F.Cu")
		(net 27)
	)
	(segment
		(start 94.017962 141.107236)
		(end 95.099698 141.107236)
		(width 0.15)
		(layer "F.Cu")
		(net 27)
	)
	(segment
		(start 84.051962 140.307236)
		(end 84.051962 141.1075)
		(width 0.254)
		(layer "F.Cu")
		(net 27)
	)
	(segment
		(start 95.117962 136.191236)
		(end 95.117962 136.907236)
		(width 0.254)
		(layer "F.Cu")
		(net 27)
	)
	(segment
		(start 75.692962 133.8565)
		(end 73.532962 136.0165)
		(width 0.2)
		(layer "F.Cu")
		(net 27)
	)
	(segment
		(start 89.267962 143.2165)
		(end 89.267962 142.657236)
		(width 0.15)
		(layer "F.Cu")
		(net 27)
	)
	(segment
		(start 86.320962 145.9635)
		(end 86.320962 145.3435)
		(width 0.127)
		(layer "F.Cu")
		(net 27)
	)
	(segment
		(start 99.617962 141.1665)
		(end 97.917962 141.1665)
		(width 0.2)
		(layer "F.Cu")
		(net 27)
	)
	(segment
		(start 87.517962 145.08)
		(end 88.210698 145.08)
		(width 0.127)
		(layer "F.Cu")
		(net 27)
	)
	(segment
		(start 95.538698 141.907236)
		(end 95.117962 141.907236)
		(width 0.2)
		(layer "F.Cu")
		(net 27)
	)
	(segment
		(start 97.917962 141.1665)
		(end 96.367962 142.7165)
		(width 0.2)
		(layer "F.Cu")
		(net 27)
	)
	(segment
		(start 84.051962 139.332236)
		(end 84.467962 139.332236)
		(width 0.15)
		(layer "F.Cu")
		(net 27)
	)
	(segment
		(start 82.378698 132.002236)
		(end 76.842962 132.002236)
		(width 0.2)
		(layer "F.Cu")
		(net 27)
	)
	(segment
		(start 89.076962 144.348236)
		(end 89.076962 143.907236)
		(width 0.254)
		(layer "F.Cu")
		(net 27)
	)
	(segment
		(start 76.653698 132.1915)
		(end 75.727962 132.1915)
		(width 0.2)
		(layer "F.Cu")
		(net 27)
	)
	(segment
		(start 84.051962 141.1075)
		(end 84.017962 141.1415)
		(width 0.254)
		(layer "F.Cu")
		(net 27)
	)
	(segment
		(start 84.758962 132.5915)
		(end 83.369226 132.5915)
		(width 0.2)
		(layer "F.Cu")
		(net 27)
	)
	(segment
		(start 96.347962 142.7165)
		(end 95.538698 141.907236)
		(width 0.2)
		(layer "F.Cu")
		(net 27)
	)
	(segment
		(start 86.217962 131.5915)
		(end 85.751962 131.5915)
		(width 0.2)
		(layer "F.Cu")
		(net 27)
	)
	(segment
		(start 96.367962 142.7165)
		(end 96.347962 142.7165)
		(width 0.2)
		(layer "F.Cu")
		(net 27)
	)
	(segment
		(start 76.842962 132.002236)
		(end 76.653698 132.1915)
		(width 0.2)
		(layer "F.Cu")
		(net 27)
	)
	(segment
		(start 92.817962 130.319814)
		(end 92.817962 131.0315)
		(width 0.254)
		(layer "F.Cu")
		(net 27)
	)
	(segment
		(start 85.751962 131.5985)
		(end 84.758962 132.5915)
		(width 0.2)
		(layer "F.Cu")
		(net 27)
	)
	(segment
		(start 95.108962 141.898236)
		(end 95.117962 141.907236)
		(width 0.254)
		(layer "F.Cu")
		(net 27)
	)
	(segment
		(start 86.567962 130.172038)
		(end 87.0735 129.6665)
		(width 0.2)
		(layer "F.Cu")
		(net 27)
	)
	(segment
		(start 83.329962 135.089236)
		(end 81.940698 135.089236)
		(width 0.2)
		(layer "F.Cu")
		(net 27)
	)
	(segment
		(start 101.587962 143.6165)
		(end 101.587962 142.6415)
		(width 0.254)
		(layer "F.Cu")
		(net 27)
	)
	(segment
		(start 95.108962 141.1165)
		(end 95.108962 141.898236)
		(width 0.254)
		(layer "F.Cu")
		(net 27)
	)
	(segment
		(start 95.117962 136.191236)
		(end 94.833962 135.907236)
		(width 0.2)
		(layer "F.Cu")
		(net 27)
	)
	(segment
		(start 86.320962 145.3435)
		(end 86.647962 145.0165)
		(width 0.127)
		(layer "F.Cu")
		(net 27)
	)
	(segment
		(start 82.928698 132.552236)
		(end 82.378698 132.002236)
		(width 0.2)
		(layer "F.Cu")
		(net 27)
	)
	(segment
		(start 87.454462 145.0165)
		(end 87.517962 145.08)
		(width 0.127)
		(layer "F.Cu")
		(net 27)
	)
	(segment
		(start 86.647962 145.0165)
		(end 87.454462 145.0165)
		(width 0.127)
		(layer "F.Cu")
		(net 27)
	)
	(segment
		(start 92.763072 146.14639)
		(end 92.323698 146.585764)
		(width 0.254)
		(layer "F.Cu")
		(net 27)
	)
	(via
		(at 84.017962 141.1415)
		(size 0.45)
		(drill 0.1)
		(layers "F.Cu" "B.Cu")
		(net 27)
	)
	(via
		(at 92.763072 146.1304)
		(size 0.45)
		(drill 0.1)
		(layers "F.Cu" "B.Cu")
		(net 27)
	)
	(via
		(at 86.567962 131.2415)
		(size 0.45)
		(drill 0.1)
		(layers "F.Cu" "B.Cu")
		(net 27)
	)
	(via
		(at 95.117962 136.8915)
		(size 0.45)
		(drill 0.1)
		(layers "F.Cu" "B.Cu")
		(net 27)
	)
	(via
		(at 95.117962 141.907236)
		(size 0.45)
		(drill 0.1)
		(layers "F.Cu" "B.Cu")
		(net 27)
	)
	(via
		(at 88.681462 144.609236)
		(size 0.45)
		(drill 0.1)
		(layers "F.Cu" "B.Cu")
		(net 27)
	)
	(via
		(at 81.917962 135.0665)
		(size 0.45)
		(drill 0.1)
		(layers "F.Cu" "B.Cu")
		(net 27)
	)
	(via
		(at 92.017962 130.6415)
		(size 0.45)
		(drill 0.1)
		(layers "F.Cu" "B.Cu")
		(net 27)
	)
	(via
		(at 92.791305 130.293157)
		(size 0.45)
		(drill 0.1)
		(layers "F.Cu" "B.Cu")
		(net 27)
	)
	(segment
		(start 92.502962 129.8265)
		(end 92.791305 130.114843)
		(width 0.254)
		(layer "B.Cu")
		(net 27)
	)
	(segment
		(start 92.067962 129.8265)
		(end 92.502962 129.8265)
		(width 0.254)
		(layer "B.Cu")
		(net 27)
	)
	(segment
		(start 81.907962 135.0565)
		(end 81.917962 135.0665)
		(width 0.2)
		(layer "B.Cu")
		(net 27)
	)
	(segment
		(start 92.791305 130.114843)
		(end 92.791305 130.293157)
		(width 0.254)
		(layer "B.Cu")
		(net 27)
	)
	(segment
		(start 81.342962 135.0565)
		(end 81.907962 135.0565)
		(width 0.2)
		(layer "B.Cu")
		(net 27)
	)
	(segment
		(start 81.917962 135.0665)
		(end 82.457962 135.0665)
		(width 0.2)
		(layer "B.Cu")
		(net 27)
	)
	(segment
		(start 92.017962 129.8765)
		(end 92.017962 130.6415)
		(width 0.254)
		(layer "B.Cu")
		(net 27)
	)
	(segment
		(start 92.067962 129.8265)
		(end 92.017962 129.8765)
		(width 0.254)
		(layer "B.Cu")
		(net 27)
	)
	(segment
		(start 81.302962 135.0465)
		(end 81.302962 133.7915)
		(width 0.2)
		(layer "B.Cu")
		(net 27)
	)
	(segment
		(start 81.317962 132.5315)
		(end 81.317962 133.7565)
		(width 0.2)
		(layer "B.Cu")
		(net 27)
	)
	(segment
		(start 89.399198 143.8915)
		(end 91.083698 143.8915)
		(width 0.2)
		(layer "In3.Cu")
		(net 27)
	)
	(segment
		(start 92.655384 130.157236)
		(end 87.568342 130.157236)
		(width 0.4)
		(layer "In3.Cu")
		(net 27)
	)
	(segment
		(start 91.083698 143.8915)
		(end 91.533698 143.4415)
		(width 0.2)
		(layer "In3.Cu")
		(net 27)
	)
	(segment
		(start 84.017962 141.1415)
		(end 85.105462 140.054)
		(width 0.4)
		(layer "In3.Cu")
		(net 27)
	)
	(segment
		(start 92.763072 146.1304)
		(end 91.533698 144.901026)
		(width 0.4)
		(layer "In3.Cu")
		(net 27)
	)
	(segment
		(start 86.667962 131.057616)
		(end 86.667962 131.2415)
		(width 0.4)
		(layer "In3.Cu")
		(net 27)
	)
	(segment
		(start 86.667962 131.2415)
		(end 86.642962 131.2665)
		(width 0.4)
		(layer "In3.Cu")
		(net 27)
	)
	(segment
		(start 86.642962 131.2665)
		(end 86.642962 133.4415)
		(width 0.4)
		(layer "In3.Cu")
		(net 27)
	)
	(segment
		(start 92.791305 130.293157)
		(end 92.655384 130.157236)
		(width 0.4)
		(layer "In3.Cu")
		(net 27)
	)
	(segment
		(start 86.138726 142.0665)
		(end 84.942962 142.0665)
		(width 0.2)
		(layer "In3.Cu")
		(net 27)
	)
	(segment
		(start 85.155462 135.204)
		(end 85.155462 140.004)
		(width 0.2)
		(layer "In3.Cu")
		(net 27)
	)
	(segment
		(start 88.681462 144.609236)
		(end 86.138726 142.0665)
		(width 0.2)
		(layer "In3.Cu")
		(net 27)
	)
	(segment
		(start 91.533698 144.901026)
		(end 91.533698 143.4415)
		(width 0.4)
		(layer "In3.Cu")
		(net 27)
	)
	(segment
		(start 85.155462 140.004)
		(end 85.105462 140.054)
		(width 0.2)
		(layer "In3.Cu")
		(net 27)
	)
	(segment
		(start 94.517962 136.907236)
		(end 94.267964 137.157234)
		(width 0.2)
		(layer "In3.Cu")
		(net 27)
	)
	(segment
		(start 91.292962 133.682236)
		(end 94.517962 136.907236)
		(width 0.2)
		(layer "In3.Cu")
		(net 27)
	)
	(segment
		(start 88.681462 144.609236)
		(end 89.399198 143.8915)
		(width 0.2)
		(layer "In3.Cu")
		(net 27)
	)
	(segment
		(start 84.942962 142.0665)
		(end 84.017962 141.1415)
		(width 0.2)
		(layer "In3.Cu")
		(net 27)
	)
	(segment
		(start 94.267964 140.741498)
		(end 94.110094 140.899368)
		(width 0.2)
		(layer "In3.Cu")
		(net 27)
	)
	(segment
		(start 81.917962 135.0665)
		(end 85.017962 135.0665)
		(width 0.4)
		(layer "In3.Cu")
		(net 27)
	)
	(segment
		(start 95.117962 136.907236)
		(end 94.517962 136.907236)
		(width 0.4)
		(layer "In3.Cu")
		(net 27)
	)
	(segment
		(start 85.017962 135.0665)
		(end 85.155462 135.204)
		(width 0.2)
		(layer "In3.Cu")
		(net 27)
	)
	(segment
		(start 87.568342 130.157236)
		(end 86.667962 131.057616)
		(width 0.4)
		(layer "In3.Cu")
		(net 27)
	)
	(segment
		(start 95.117962 141.907236)
		(end 94.110094 140.899368)
		(width 0.4)
		(layer "In3.Cu")
		(net 27)
	)
	(segment
		(start 85.017962 135.0665)
		(end 86.642962 133.4415)
		(width 0.4)
		(layer "In3.Cu")
		(net 27)
	)
	(segment
		(start 86.642962 133.4415)
		(end 86.883698 133.682236)
		(width 0.2)
		(layer "In3.Cu")
		(net 27)
	)
	(segment
		(start 91.567962 143.4415)
		(end 91.533698 143.4415)
		(width 0.2)
		(layer "In3.Cu")
		(net 27)
	)
	(segment
		(start 86.883698 133.682236)
		(end 91.292962 133.682236)
		(width 0.2)
		(layer "In3.Cu")
		(net 27)
	)
	(segment
		(start 94.110094 140.899368)
		(end 91.567962 143.4415)
		(width 0.2)
		(layer "In3.Cu")
		(net 27)
	)
	(segment
		(start 95.117962 136.907236)
		(end 95.117962 136.9165)
		(width 0.4)
		(layer "In3.Cu")
		(net 27)
	)
	(segment
		(start 94.267964 137.157234)
		(end 94.267964 140.741498)
		(width 0.2)
		(layer "In3.Cu")
		(net 27)
	)
	(segment
		(start 101.467462 128.4165)
		(end 101.667462 128.6165)
		(width 0.4)
		(layer "F.Cu")
		(net 28)
	)
	(segment
		(start 102.487962 128.6165)
		(end 102.717962 128.3865)
		(width 0.2)
		(layer "F.Cu")
		(net 28)
	)
	(segment
		(start 98.011292 125.40983)
		(end 98.011292 126.0695)
		(width 0.2)
		(layer "F.Cu")
		(net 28)
	)
	(segment
		(start 100.726962 128.4165)
		(end 101.467462 128.4165)
		(width 0.4)
		(layer "F.Cu")
		(net 28)
	)
	(segment
		(start 100.226962 126.063)
		(end 100.226962 124.4115)
		(width 0.4)
		(layer "F.Cu")
		(net 28)
	)
	(segment
		(start 100.726962 128.4165)
		(end 100.726962 127.8255)
		(width 0.4)
		(layer "F.Cu")
		(net 28)
	)
	(segment
		(start 100.167962 122.275)
		(end 100.167962 124.3525)
		(width 0.15)
		(layer "F.Cu")
		(net 28)
	)
	(segment
		(start 100.726962 127.8255)
		(end 100.226962 127.3255)
		(width 0.4)
		(layer "F.Cu")
		(net 28)
	)
	(segment
		(start 100.226962 127.3255)
		(end 100.226962 126.063)
		(width 0.4)
		(layer "F.Cu")
		(net 28)
	)
	(segment
		(start 99.527962 131.6165)
		(end 99.527962 129.8015)
		(width 0.15)
		(layer "F.Cu")
		(net 28)
	)
	(segment
		(start 100.226962 124.4115)
		(end 100.181962 124.3665)
		(width 0.4)
		(layer "F.Cu")
		(net 28)
	)
	(segment
		(start 100.167962 124.3525)
		(end 100.181962 124.3665)
		(width 0.15)
		(layer "F.Cu")
		(net 28)
	)
	(segment
		(start 103.787962 128.3865)
		(end 102.717962 128.3865)
		(width 0.2)
		(layer "F.Cu")
		(net 28)
	)
	(segment
		(start 103.782962 129.3115)
		(end 103.782962 128.3915)
		(width 0.127)
		(layer "F.Cu")
		(net 28)
	)
	(segment
		(start 98.011292 126.0695)
		(end 100.220462 126.0695)
		(width 0.5)
		(layer "F.Cu")
		(net 28)
	)
	(segment
		(start 99.242962 127.5665)
		(end 100.117962 126.6915)
		(width 0.15)
		(layer "F.Cu")
		(net 28)
	)
	(segment
		(start 100.767962 117.8415)
		(end 100.767962 118.594)
		(width 0.15)
		(layer "F.Cu")
		(net 28)
	)
	(segment
		(start 103.817962 129.3065)
		(end 103.817962 128.4165)
		(width 0.2)
		(layer "F.Cu")
		(net 28)
	)
	(segment
		(start 99.242962 129.5165)
		(end 99.242962 127.5665)
		(width 0.15)
		(layer "F.Cu")
		(net 28)
	)
	(segment
		(start 99.527962 129.8015)
		(end 99.242962 129.5165)
		(width 0.15)
		(layer "F.Cu")
		(net 28)
	)
	(segment
		(start 97.451962 124.8505)
		(end 98.011292 125.40983)
		(width 0.2)
		(layer "F.Cu")
		(net 28)
	)
	(segment
		(start 101.667462 128.6165)
		(end 102.487962 128.6165)
		(width 0.2)
		(layer "F.Cu")
		(net 28)
	)
	(via
		(at 100.181962 124.3665)
		(size 0.45)
		(drill 0.1)
		(layers "F.Cu" "B.Cu")
		(net 28)
	)
	(via
		(at 100.767962 117.8415)
		(size 0.45)
		(drill 0.1)
		(layers "F.Cu" "B.Cu")
		(net 28)
	)
	(segment
		(start 100.217962 124.3305)
		(end 100.217962 118.3915)
		(width 0.15)
		(layer "In2.Cu")
		(net 28)
	)
	(segment
		(start 100.217962 118.3915)
		(end 100.767962 117.8415)
		(width 0.15)
		(layer "In2.Cu")
		(net 28)
	)
	(segment
		(start 100.181962 124.3665)
		(end 100.217962 124.3305)
		(width 0.15)
		(layer "In2.Cu")
		(net 28)
	)
	(segment
		(start 100.181962 124.3665)
		(end 100.217962 124.4025)
		(width 0.15)
		(layer "In2.Cu")
		(net 28)
	)
	(segment
		(start 89.267962 133.402236)
		(end 89.097962 133.232236)
		(width 0.127)
		(layer "F.Cu")
		(net 29)
	)
	(segment
		(start 89.267962 133.957236)
		(end 89.267962 133.402236)
		(width 0.127)
		(layer "F.Cu")
		(net 29)
	)
	(via
		(at 89.097962 133.232236)
		(size 0.45)
		(drill 0.1)
		(layers "F.Cu" "B.Cu")
		(net 29)
	)
	(segment
		(start 81.56158 131.9415)
		(end 79.192962 131.9415)
		(width 0.127)
		(layer "B.Cu")
		(net 29)
	)
	(segment
		(start 79.192962 131.9415)
		(end 76.792962 134.3415)
		(width 0.127)
		(layer "B.Cu")
		(net 29)
	)
	(segment
		(start 83.83658 134.2165)
		(end 81.56158 131.9415)
		(width 0.127)
		(layer "B.Cu")
		(net 29)
	)
	(segment
		(start 87.807962 134.2165)
		(end 83.83658 134.2165)
		(width 0.127)
		(layer "B.Cu")
		(net 29)
	)
	(segment
		(start 75.827962 135.0565)
		(end 76.777962 135.0565)
		(width 0.15)
		(layer "B.Cu")
		(net 29)
	)
	(segment
		(start 88.113698 134.2165)
		(end 89.097962 133.232236)
		(width 0.127)
		(layer "B.Cu")
		(net 29)
	)
	(segment
		(start 75.827962 136.0165)
		(end 75.827962 136.9905)
		(width 0.15)
		(layer "B.Cu")
		(net 29)
	)
	(segment
		(start 87.807962 134.2165)
		(end 88.113698 134.2165)
		(width 0.127)
		(layer "B.Cu")
		(net 29)
	)
	(segment
		(start 75.827962 135.0565)
		(end 75.827962 136.0165)
		(width 0.15)
		(layer "B.Cu")
		(net 29)
	)
	(segment
		(start 76.792962 134.3415)
		(end 76.792962 135.0415)
		(width 0.127)
		(layer "B.Cu")
		(net 29)
	)
	(segment
		(start 92.008962 143.798236)
		(end 91.585094 143.374368)
		(width 0.2)
		(layer "F.Cu")
		(net 30)
	)
	(segment
		(start 95.917962 137.973236)
		(end 95.108962 138.782236)
		(width 0.254)
		(layer "F.Cu")
		(net 30)
	)
	(segment
		(start 92.542962 144.2325)
		(end 92.142962 143.8325)
		(width 0.2)
		(layer "F.Cu")
		(net 30)
	)
	(segment
		(start 94.108698 143.6665)
		(end 93.542698 144.2325)
		(width 0.2)
		(layer "F.Cu")
		(net 30)
	)
	(segment
		(start 95.108962 138.782236)
		(end 94.617962 138.782236)
		(width 0.15)
		(layer "F.Cu")
		(net 30)
	)
	(segment
		(start 91.267962 143.057236)
		(end 91.585094 143.374368)
		(width 0.15)
		(layer "F.Cu")
		(net 30)
	)
	(segment
		(start 87.126962 143.557236)
		(end 87.520962 143.557236)
		(width 0.2)
		(layer "F.Cu")
		(net 30)
	)
	(segment
		(start 96.117962 137.6665)
		(end 96.917962 137.6665)
		(width 0.254)
		(layer "F.Cu")
		(net 30)
	)
	(segment
		(start 88.739962 143.335236)
		(end 88.517962 143.335236)
		(width 0.15)
		(layer "F.Cu")
		(net 30)
	)
	(segment
		(start 84.442962 138.157236)
		(end 83.926962 138.157236)
		(width 0.15)
		(layer "F.Cu")
		(net 30)
	)
	(segment
		(start 88.867962 142.657236)
		(end 88.867962 143.207236)
		(width 0.15)
		(layer "F.Cu")
		(net 30)
	)
	(segment
		(start 95.917962 137.8665)
		(end 95.917962 137.973236)
		(width 0.254)
		(layer "F.Cu")
		(net 30)
	)
	(segment
		(start 88.867962 143.207236)
		(end 88.739962 143.335236)
		(width 0.15)
		(layer "F.Cu")
		(net 30)
	)
	(segment
		(start 86.274696 133.0255)
		(end 86.742962 133.0255)
		(width 0.254)
		(layer "F.Cu")
		(net 30)
	)
	(segment
		(start 86.742962 133.3915)
		(end 86.867962 133.5165)
		(width 0.15)
		(layer "F.Cu")
		(net 30)
	)
	(segment
		(start 94.617962 138.782236)
		(end 94.542962 138.707236)
		(width 0.15)
		(layer "F.Cu")
		(net 30)
	)
	(segment
		(start 87.117962 144.282236)
		(end 87.117962 143.566236)
		(width 0.254)
		(layer "F.Cu")
		(net 30)
	)
	(segment
		(start 93.542698 144.2325)
		(end 92.542962 144.2325)
		(width 0.2)
		(layer "F.Cu")
		(net 30)
	)
	(segment
		(start 88.517962 143.335236)
		(end 87.742962 143.335236)
		(width 0.2)
		(layer "F.Cu")
		(net 30)
	)
	(segment
		(start 94.017962 138.707236)
		(end 94.542962 138.707236)
		(width 0.15)
		(layer "F.Cu")
		(net 30)
	)
	(segment
		(start 94.167962 143.6665)
		(end 94.108698 143.6665)
		(width 0.2)
		(layer "F.Cu")
		(net 30)
	)
	(segment
		(start 95.917962 137.8665)
		(end 96.117962 137.6665)
		(width 0.254)
		(layer "F.Cu")
		(net 30)
	)
	(segment
		(start 85.317962 138.307236)
		(end 84.592962 138.307236)
		(width 0.15)
		(layer "F.Cu")
		(net 30)
	)
	(segment
		(start 84.542962 138.257236)
		(end 84.442962 138.157236)
		(width 0.15)
		(layer "F.Cu")
		(net 30)
	)
	(segment
		(start 87.742962 143.335236)
		(end 87.520962 143.557236)
		(width 0.2)
		(layer "F.Cu")
		(net 30)
	)
	(segment
		(start 84.592962 138.307236)
		(end 84.542962 138.257236)
		(width 0.15)
		(layer "F.Cu")
		(net 30)
	)
	(segment
		(start 86.042962 133.257234)
		(end 86.274696 133.0255)
		(width 0.254)
		(layer "F.Cu")
		(net 30)
	)
	(segment
		(start 86.742962 133.0255)
		(end 86.742962 133.3915)
		(width 0.15)
		(layer "F.Cu")
		(net 30)
	)
	(segment
		(start 91.267962 142.657236)
		(end 91.267962 143.057236)
		(width 0.15)
		(layer "F.Cu")
		(net 30)
	)
	(segment
		(start 86.867962 133.5165)
		(end 86.867962 133.957236)
		(width 0.15)
		(layer "F.Cu")
		(net 30)
	)
	(via
		(at 87.117962 144.282236)
		(size 0.45)
		(drill 0.1)
		(layers "F.Cu" "B.Cu")
		(net 30)
	)
	(via
		(at 94.167962 143.6665)
		(size 0.45)
		(drill 0.1)
		(layers "F.Cu" "B.Cu")
		(net 30)
	)
	(via
		(at 95.917962 137.8665)
		(size 0.45)
		(drill 0.1)
		(layers "F.Cu" "B.Cu")
		(net 30)
	)
	(via
		(at 84.542962 138.257236)
		(size 0.45)
		(drill 0.1)
		(layers "F.Cu" "B.Cu")
		(net 30)
	)
	(via
		(at 86.042962 133.257234)
		(size 0.45)
		(drill 0.1)
		(layers "F.Cu" "B.Cu")
		(net 30)
	)
	(segment
		(start 95.917962 137.8665)
		(end 94.067962 139.7165)
		(width 0.254)
		(layer "In2.Cu")
		(net 30)
	)
	(segment
		(start 94.167962 143.6665)
		(end 93.702226 144.132236)
		(width 0.254)
		(layer "In2.Cu")
		(net 30)
	)
	(segment
		(start 94.167962 142.5965)
		(end 94.037962 142.4665)
		(width 0.254)
		(layer "In2.Cu")
		(net 30)
	)
	(segment
		(start 87.267962 144.132236)
		(end 87.117962 144.282236)
		(width 0.254)
		(layer "In2.Cu")
		(net 30)
	)
	(segment
		(start 94.067962 139.7165)
		(end 94.067962 143.7165)
		(width 0.254)
		(layer "In2.Cu")
		(net 30)
	)
	(segment
		(start 86.042962 133.257234)
		(end 86.042962 139.757236)
		(width 0.254)
		(layer "In2.Cu")
		(net 30)
	)
	(segment
		(start 86.808698 139.757236)
		(end 88.892962 141.8415)
		(width 0.254)
		(layer "In2.Cu")
		(net 30)
	)
	(segment
		(start 94.067962 143.7165)
		(end 94.167962 143.8165)
		(width 0.254)
		(layer "In2.Cu")
		(net 30)
	)
	(segment
		(start 88.892962 142.4665)
		(end 88.752226 142.4665)
		(width 0.254)
		(layer "In2.Cu")
		(net 30)
	)
	(segment
		(start 86.042962 139.757236)
		(end 86.808698 139.757236)
		(width 0.254)
		(layer "In2.Cu")
		(net 30)
	)
	(segment
		(start 93.702226 144.132236)
		(end 87.267962 144.132236)
		(width 0.254)
		(layer "In2.Cu")
		(net 30)
	)
	(segment
		(start 84.542962 138.257236)
		(end 86.042962 139.757236)
		(width 0.254)
		(layer "In2.Cu")
		(net 30)
	)
	(segment
		(start 94.037962 142.4665)
		(end 88.892962 142.4665)
		(width 0.254)
		(layer "In2.Cu")
		(net 30)
	)
	(segment
		(start 88.892962 141.8415)
		(end 88.892962 142.4665)
		(width 0.254)
		(layer "In2.Cu")
		(net 30)
	)
	(segment
		(start 94.167962 143.8165)
		(end 94.167962 142.5965)
		(width 0.254)
		(layer "In2.Cu")
		(net 30)
	)
	(segment
		(start 91.587962 145.1615)
		(end 92.142962 145.7165)
		(width 0.2)
		(layer "F.Cu")
		(net 31)
	)
	(segment
		(start 91.042962 143.798236)
		(end 91.042962 143.3665)
		(width 0.15)
		(layer "F.Cu")
		(net 31)
	)
	(segment
		(start 91.042962 143.798236)
		(end 91.587962 144.343236)
		(width 0.2)
		(layer "F.Cu")
		(net 31)
	)
	(segment
		(start 90.867962 142.657236)
		(end 90.867962 143.1915)
		(width 0.15)
		(layer "F.Cu")
		(net 31)
	)
	(segment
		(start 91.042962 143.3665)
		(end 90.867962 143.1915)
		(width 0.15)
		(layer "F.Cu")
		(net 31)
	)
	(segment
		(start 91.587962 144.343236)
		(end 91.587962 145.1615)
		(width 0.2)
		(layer "F.Cu")
		(net 31)
	)
	(segment
		(start 91.667962 133.957236)
		(end 91.667962 133.5165)
		(width 0.15)
		(layer "F.Cu")
		(net 32)
	)
	(segment
		(start 92.782962 132.0015)
		(end 91.868226 132.916236)
		(width 0.2)
		(layer "F.Cu")
		(net 32)
	)
	(segment
		(start 91.867962 132.916236)
		(end 91.867962 133.3165)
		(width 0.15)
		(layer "F.Cu")
		(net 32)
	)
	(segment
		(start 91.867962 133.3165)
		(end 91.667962 133.5165)
		(width 0.15)
		(layer "F.Cu")
		(net 32)
	)
	(segment
		(start 54.431462 127.45)
		(end 55.312962 128.3315)
		(width 0.2)
		(layer "F.Cu")
		(net 33)
	)
	(segment
		(start 55.887962 132.7765)
		(end 56.392962 133.2815)
		(width 0.2)
		(layer "F.Cu")
		(net 33)
	)
	(segment
		(start 53.4 127.45)
		(end 53.3865 127.4365)
		(width 0.254)
		(layer "F.Cu")
		(net 33)
	)
	(segment
		(start 53.3865 127.4365)
		(end 51.967962 127.4365)
		(width 0.254)
		(layer "F.Cu")
		(net 33)
	)
	(segment
		(start 56.392962 133.2815)
		(end 56.392962 133.8815)
		(width 0.2)
		(layer "F.Cu")
		(net 33)
	)
	(segment
		(start 51.862962 129.0895)
		(end 51.862962 127.5415)
		(width 0.2)
		(layer "F.Cu")
		(net 33)
	)
	(segment
		(start 55.312962 132.7765)
		(end 55.887962 132.7765)
		(width 0.2)
		(layer "F.Cu")
		(net 33)
	)
	(segment
		(start 55.312962 128.3315)
		(end 55.312962 132.7765)
		(width 0.2)
		(layer "F.Cu")
		(net 33)
	)
	(segment
		(start 53.4 127.45)
		(end 54.431462 127.45)
		(width 0.2)
		(layer "F.Cu")
		(net 33)
	)
	(segment
		(start 56.392962 133.8815)
		(end 57.342962 133.8815)
		(width 0.2)
		(layer "F.Cu")
		(net 33)
	)
	(via
		(at 53.4 127.45)
		(size 0.5)
		(drill 0.15)
		(layers "F.Cu" "B.Cu")
		(net 33)
	)
	(segment
		(start 55.360962 116.5675)
		(end 56.761962 116.5675)
		(width 0.5)
		(layer "B.Cu")
		(net 33)
	)
	(segment
		(start 54.611962 117.3165)
		(end 54.611962 127.3165)
		(width 0.5)
		(layer "B.Cu")
		(net 33)
	)
	(segment
		(start 54.478462 127.45)
		(end 54.611962 127.3165)
		(width 0.254)
		(layer "B.Cu")
		(net 33)
	)
	(segment
		(start 59.916962 142.1455)
		(end 58.955962 143.1065)
		(width 1)
		(layer "B.Cu")
		(net 33)
	)
	(segment
		(start 55.287962 142.7665)
		(end 55.287962 141.5665)
		(width 0.5)
		(layer "B.Cu")
		(net 33)
	)
	(segment
		(start 54.927962 142.1565)
		(end 54.927962 143.1065)
		(width 0.5)
		(layer "B.Cu")
		(net 33)
	)
	(segment
		(start 55.577962 142.1565)
		(end 55.577962 143.1065)
		(width 0.5)
		(layer "B.Cu")
		(net 33)
	)
	(segment
		(start 58.152962 143.1065)
		(end 60.877962 143.1065)
		(width 1)
		(layer "B.Cu")
		(net 33)
	)
	(segment
		(start 55.252962 142.0815)
		(end 55.252962 143.0315)
		(width 0.5)
		(layer "B.Cu")
		(net 33)
	)
	(segment
		(start 55.287962 141.5665)
		(end 55.292962 141.5615)
		(width 0.5)
		(layer "B.Cu")
		(net 33)
	)
	(segment
		(start 53.4 127.45)
		(end 54.478462 127.45)
		(width 0.254)
		(layer "B.Cu")
		(net 33)
	)
	(segment
		(start 49.427962 143.6065)
		(end 60.377962 143.6065)
		(width 0.5)
		(layer "B.Cu")
		(net 33)
	)
	(segment
		(start 59.956962 142.1855)
		(end 60.877962 143.1065)
		(width 1)
		(layer "B.Cu")
		(net 33)
	)
	(segment
		(start 55.287962 141.8165)
		(end 54.962962 142.1415)
		(width 0.5)
		(layer "B.Cu")
		(net 33)
	)
	(segment
		(start 55.292962 141.5615)
		(end 55.292962 127.9975)
		(width 0.5)
		(layer "B.Cu")
		(net 33)
	)
	(segment
		(start 55.360962 116.5675)
		(end 54.611962 117.3165)
		(width 0.5)
		(layer "B.Cu")
		(net 33)
	)
	(segment
		(start 59.956962 139.8165)
		(end 59.956962 142.1855)
		(width 1)
		(layer "B.Cu")
		(net 33)
	)
	(segment
		(start 55.287962 141.8165)
		(end 55.612962 142.1415)
		(width 0.5)
		(layer "B.Cu")
		(net 33)
	)
	(segment
		(start 55.292962 127.9975)
		(end 54.611962 127.3165)
		(width 0.5)
		(layer "B.Cu")
		(net 33)
	)
	(segment
		(start 58.955962 143.1065)
		(end 58.152962 143.1065)
		(width 1)
		(layer "B.Cu")
		(net 33)
	)
	(segment
		(start 56.893962 116.4665)
		(end 58.379962 116.4665)
		(width 0.5)
		(layer "B.Cu")
		(net 33)
	)
	(segment
		(start 55.287962 141.5665)
		(end 55.287962 141.8165)
		(width 0.5)
		(layer "B.Cu")
		(net 33)
	)
	(segment
		(start 43.102962 143.1065)
		(end 58.152962 143.1065)
		(width 1)
		(layer "B.Cu")
		(net 33)
	)
	(segment
		(start 60.877962 143.1065)
		(end 59.916962 142.1455)
		(width 1)
		(layer "B.Cu")
		(net 33)
	)
	(segment
		(start 108.612462 124.612)
		(end 108.867962 124.3565)
		(width 0.153)
		(layer "F.Cu")
		(net 34)
	)
	(segment
		(start 108.692212 126.86575)
		(end 108.542962 126.7165)
		(width 0.153)
		(layer "F.Cu")
		(net 34)
	)
	(segment
		(start 108.612462 125.729)
		(end 108.612462 126.085251)
		(width 0.153)
		(layer "F.Cu")
		(net 34)
	)
	(segment
		(start 108.542962 126.7165)
		(end 108.542962 126.154751)
		(width 0.153)
		(layer "F.Cu")
		(net 34)
	)
	(segment
		(start 116.079962 161.316)
		(end 116.114462 161.2815)
		(width 0.15)
		(layer "F.Cu")
		(net 34)
	)
	(segment
		(start 108.867962 124.3565)
		(end 108.867962 122.568958)
		(width 0.153)
		(layer "F.Cu")
		(net 34)
	)
	(segment
		(start 115.554961 161.316)
		(end 116.079962 161.316)
		(width 0.15)
		(layer "F.Cu")
		(net 34)
	)
	(segment
		(start 117.403963 161.281501)
		(end 117.567962 161.4455)
		(width 0.15)
		(layer "F.Cu")
		(net 34)
	)
	(segment
		(start 108.612462 124.970325)
		(end 108.612462 124.612)
		(width 0.153)
		(layer "F.Cu")
		(net 34)
	)
	(segment
		(start 116.114462 161.2815)
		(end 117.403963 161.281501)
		(width 0.15)
		(layer "F.Cu")
		(net 34)
	)
	(segment
		(start 108.613462 125.745325)
		(end 108.613462 124.971325)
		(width 0.153)
		(layer "F.Cu")
		(net 34)
	)
	(segment
		(start 108.612462 126.085251)
		(end 108.542962 126.154751)
		(width 0.153)
		(layer "F.Cu")
		(net 34)
	)
	(via
		(at 117.567962 161.4455)
		(size 0.45)
		(drill 0.1)
		(layers "F.Cu" "B.Cu")
		(net 34)
	)
	(via
		(at 108.692212 126.86575)
		(size 0.45)
		(drill 0.1)
		(layers "F.Cu" "B.Cu")
		(net 34)
	)
	(segment
		(start 110.836513 160.86328)
		(end 109.65918 162.040612)
		(width 0.15)
		(layer "B.Cu")
		(net 34)
	)
	(segment
		(start 114.307962 163.5515)
		(end 112.967962 163.5515)
		(width 0.15)
		(layer "B.Cu")
		(net 34)
	)
	(segment
		(start 109.18542 161.566851)
		(end 110.362752 160.389518)
		(width 0.15)
		(layer "B.Cu")
		(net 34)
	)
	(segment
		(start 112.367962 163.3515)
		(end 112.367962 163.1715)
		(width 0.15)
		(layer "B.Cu")
		(net 34)
	)
	(segment
		(start 109.422299 159.449066)
		(end 108.244966 160.626398)
		(width 0.15)
		(layer "B.Cu")
		(net 34)
	)
	(segment
		(start 108.528213 127.2065)
		(end 108.528213 127.029749)
		(width 0.15)
		(layer "B.Cu")
		(net 34)
	)
	(segment
		(start 108.813212 128.821501)
		(end 108.978213 128.821501)
		(width 0.15)
		(layer "B.Cu")
		(net 34)
	)
	(segment
		(start 118.462962 161.614846)
		(end 118.462962 162.448154)
		(width 0.15)
		(layer "B.Cu")
		(net 34)
	)
	(segment
		(start 118.052738 162.434116)
		(end 118.05274 162.434115)
		(width 0.15)
		(layer "B.Cu")
		(net 34)
	)
	(segment
		(start 117.769895 162.716959)
		(end 117.840605 162.787669)
		(width 0.15)
		(layer "B.Cu")
		(net 34)
	)
	(segment
		(start 112.767962 163.3515)
		(end 112.767962 163.1715)
		(width 0.15)
		(layer "B.Cu")
		(net 34)
	)
	(segment
		(start 118.129616 161.2815)
		(end 118.462962 161.614846)
		(width 0.15)
		(layer "B.Cu")
		(net 34)
	)
	(segment
		(start 108.978213 127.491499)
		(end 108.813212 127.491499)
		(width 0.15)
		(layer "B.Cu")
		(net 34)
	)
	(segment
		(start 110.836513 160.863279)
		(end 110.836513 160.86328)
		(width 0.15)
		(layer "B.Cu")
		(net 34)
	)
	(segment
		(start 108.528213 129.409595)
		(end 108.528213 129.1065)
		(width 0.15)
		(layer "B.Cu")
		(net 34)
	)
	(segment
		(start 110.696308 163.5515)
		(end 112.167962 163.5515)
		(width 0.15)
		(layer "B.Cu")
		(net 34)
	)
	(segment
		(start 107.771204 160.626398)
		(end 107.709634 160.564828)
		(width 0.15)
		(layer "B.Cu")
		(net 34)
	)
	(segment
		(start 103.482962 134.454846)
		(end 108.528213 129.409595)
		(width 0.15)
		(layer "B.Cu")
		(net 34)
	)
	(segment
		(start 118.462962 162.448154)
		(end 118.406292 162.504828)
		(width 0.15)
		(layer "B.Cu")
		(net 34)
	)
	(segment
		(start 109.593214 128.2065)
		(end 109.593214 128.1065)
		(width 0.15)
		(layer "B.Cu")
		(net 34)
	)
	(segment
		(start 118.123449 162.504827)
		(end 118.052738 162.434116)
		(width 0.15)
		(layer "B.Cu")
		(net 34)
	)
	(segment
		(start 115.672962 163.3165)
		(end 115.672962 163.1515)
		(width 0.15)
		(layer "B.Cu")
		(net 34)
	)
	(segment
		(start 107.771205 160.626399)
		(end 107.771204 160.626398)
		(width 0.15)
		(layer "B.Cu")
		(net 34)
	)
	(segment
		(start 108.528213 127.029749)
		(end 108.692212 126.86575)
		(width 0.15)
		(layer "B.Cu")
		(net 34)
	)
	(segment
		(start 107.027275 159.316783)
		(end 107.027275 159.316784)
		(width 0.15)
		(layer "B.Cu")
		(net 34)
	)
	(segment
		(start 107.709634 160.232488)
		(end 107.826306 160.115815)
		(width 0.15)
		(layer "B.Cu")
		(net 34)
	)
	(segment
		(start 117.840602 163.070511)
		(end 117.359616 163.5515)
		(width 0.15)
		(layer "B.Cu")
		(net 34)
	)
	(segment
		(start 116.759616 163.3015)
		(end 116.759616 163.3515)
		(width 0.15)
		(layer "B.Cu")
		(net 34)
	)
	(segment
		(start 103.482962 156.338154)
		(end 103.482962 134.454846)
		(width 0.15)
		(layer "B.Cu")
		(net 34)
	)
	(segment
		(start 107.027275 159.316784)
		(end 106.910602 159.433456)
		(width 0.15)
		(layer "B.Cu")
		(net 34)
	)
	(segment
		(start 117.159616 163.3515)
		(end 117.159616 163.3015)
		(width 0.15)
		(layer "B.Cu")
		(net 34)
	)
	(segment
		(start 106.578263 159.433457)
		(end 103.482962 156.338154)
		(width 0.15)
		(layer "B.Cu")
		(net 34)
	)
	(segment
		(start 117.840605 163.070511)
		(end 117.840602 163.070511)
		(width 0.15)
		(layer "B.Cu")
		(net 34)
	)
	(segment
		(start 106.578262 159.433456)
		(end 106.578263 159.433457)
		(width 0.15)
		(layer "B.Cu")
		(net 34)
	)
	(segment
		(start 117.769896 162.434115)
		(end 117.769894 162.434116)
		(width 0.15)
		(layer "B.Cu")
		(net 34)
	)
	(segment
		(start 107.826306 159.316785)
		(end 107.826306 159.316784)
		(width 0.15)
		(layer "B.Cu")
		(net 34)
	)
	(segment
		(start 110.599634 162.981065)
		(end 111.776966 161.803732)
		(width 0.15)
		(layer "B.Cu")
		(net 34)
	)
	(segment
		(start 109.422299 159.449065)
		(end 109.422299 159.449066)
		(width 0.15)
		(layer "B.Cu")
		(net 34)
	)
	(segment
		(start 110.696308 163.5515)
		(end 110.599634 163.454827)
		(width 0.15)
		(layer "B.Cu")
		(net 34)
	)
	(segment
		(start 114.542962 163.1515)
		(end 114.542962 163.3165)
		(width 0.15)
		(layer "B.Cu")
		(net 34)
	)
	(segment
		(start 117.731962 161.2815)
		(end 118.129616 161.2815)
		(width 0.15)
		(layer "B.Cu")
		(net 34)
	)
	(segment
		(start 117.567962 161.4455)
		(end 117.731962 161.2815)
		(width 0.15)
		(layer "B.Cu")
		(net 34)
	)
	(segment
		(start 116.559616 163.5515)
		(end 115.907962 163.5515)
		(width 0.15)
		(layer "B.Cu")
		(net 34)
	)
	(arc
		(start 112.567962 162.9715)
		(mid 112.426541 163.030079)
		(end 112.367962 163.1715)
		(width 0.15)
		(layer "B.Cu")
		(net 34)
	)
	(arc
		(start 115.672962 163.1515)
		(mid 115.507477 162.751985)
		(end 115.107962 162.5865)
		(width 0.15)
		(layer "B.Cu")
		(net 34)
	)
	(arc
		(start 108.528213 129.1065)
		(mid 108.611687 128.904975)
		(end 108.813212 128.821501)
		(width 0.15)
		(layer "B.Cu")
		(net 34)
	)
	(arc
		(start 107.826306 160.115815)
		(mid 107.991791 159.7163)
		(end 107.826306 159.316785)
		(width 0.15)
		(layer "B.Cu")
		(net 34)
	)
	(arc
		(start 118.406292 162.504828)
		(mid 118.26487 162.563406)
		(end 118.123449 162.504827)
		(width 0.15)
		(layer "B.Cu")
		(net 34)
	)
	(arc
		(start 112.767962 163.1715)
		(mid 112.709383 163.030079)
		(end 112.567962 162.9715)
		(width 0.15)
		(layer "B.Cu")
		(net 34)
	)
	(arc
		(start 108.244966 160.626398)
		(mid 108.008086 160.724518)
		(end 107.771205 160.626399)
		(width 0.15)
		(layer "B.Cu")
		(net 34)
	)
	(arc
		(start 111.776966 161.803732)
		(mid 111.97174 161.333506)
		(end 111.776966 160.86328)
		(width 0.15)
		(layer "B.Cu")
		(net 34)
	)
	(arc
		(start 116.759616 163.3515)
		(mid 116.701037 163.492921)
		(end 116.559616 163.5515)
		(width 0.15)
		(layer "B.Cu")
		(net 34)
	)
	(arc
		(start 108.978213 128.821501)
		(mid 109.413084 128.641371)
		(end 109.593214 128.2065)
		(width 0.15)
		(layer "B.Cu")
		(net 34)
	)
	(arc
		(start 112.967962 163.5515)
		(mid 112.826541 163.492921)
		(end 112.767962 163.3515)
		(width 0.15)
		(layer "B.Cu")
		(net 34)
	)
	(arc
		(start 117.769894 162.434116)
		(mid 117.711316 162.575538)
		(end 117.769895 162.716959)
		(width 0.15)
		(layer "B.Cu")
		(net 34)
	)
	(arc
		(start 109.593214 128.1065)
		(mid 109.413084 127.671629)
		(end 108.978213 127.491499)
		(width 0.15)
		(layer "B.Cu")
		(net 34)
	)
	(arc
		(start 110.362752 160.389518)
		(mid 110.557526 159.919292)
		(end 110.362752 159.449066)
		(width 0.15)
		(layer "B.Cu")
		(net 34)
	)
	(arc
		(start 110.362752 159.449066)
		(mid 109.892526 159.254291)
		(end 109.422299 159.449065)
		(width 0.15)
		(layer "B.Cu")
		(net 34)
	)
	(arc
		(start 114.542962 163.3165)
		(mid 114.474132 163.48267)
		(end 114.307962 163.5515)
		(width 0.15)
		(layer "B.Cu")
		(net 34)
	)
	(arc
		(start 107.709634 160.564828)
		(mid 107.640804 160.398658)
		(end 107.709634 160.232488)
		(width 0.15)
		(layer "B.Cu")
		(net 34)
	)
	(arc
		(start 117.359616 163.5515)
		(mid 117.218195 163.492921)
		(end 117.159616 163.3515)
		(width 0.15)
		(layer "B.Cu")
		(net 34)
	)
	(arc
		(start 109.65918 162.040612)
		(mid 109.4223 162.138732)
		(end 109.185419 162.040613)
		(width 0.15)
		(layer "B.Cu")
		(net 34)
	)
	(arc
		(start 117.159616 163.3015)
		(mid 117.101037 163.160079)
		(end 116.959616 163.1015)
		(width 0.15)
		(layer "B.Cu")
		(net 34)
	)
	(arc
		(start 115.907962 163.5515)
		(mid 115.741792 163.48267)
		(end 115.672962 163.3165)
		(width 0.15)
		(layer "B.Cu")
		(net 34)
	)
	(arc
		(start 109.18542 162.040613)
		(mid 109.087301 161.803732)
		(end 109.18542 161.566851)
		(width 0.15)
		(layer "B.Cu")
		(net 34)
	)
	(arc
		(start 108.813212 127.491499)
		(mid 108.611687 127.408025)
		(end 108.528213 127.2065)
		(width 0.15)
		(layer "B.Cu")
		(net 34)
	)
	(arc
		(start 110.599634 163.454827)
		(mid 110.501515 163.217946)
		(end 110.599634 162.981065)
		(width 0.15)
		(layer "B.Cu")
		(net 34)
	)
	(arc
		(start 106.910602 159.433456)
		(mid 106.744432 159.502286)
		(end 106.578262 159.433456)
		(width 0.15)
		(layer "B.Cu")
		(net 34)
	)
	(arc
		(start 115.107962 162.5865)
		(mid 114.708447 162.751985)
		(end 114.542962 163.1515)
		(width 0.15)
		(layer "B.Cu")
		(net 34)
	)
	(arc
		(start 118.05274 162.434115)
		(mid 117.911317 162.375537)
		(end 117.769896 162.434115)
		(width 0.15)
		(layer "B.Cu")
		(net 34)
	)
	(arc
		(start 112.367962 163.3515)
		(mid 112.309383 163.492921)
		(end 112.167962 163.5515)
		(width 0.15)
		(layer "B.Cu")
		(net 34)
	)
	(arc
		(start 116.959616 163.1015)
		(mid 116.818195 163.160079)
		(end 116.759616 163.3015)
		(width 0.15)
		(layer "B.Cu")
		(net 34)
	)
	(arc
		(start 117.840605 162.787669)
		(mid 117.899184 162.929089)
		(end 117.840605 163.070511)
		(width 0.15)
		(layer "B.Cu")
		(net 34)
	)
	(arc
		(start 107.826306 159.316784)
		(mid 107.426791 159.151299)
		(end 107.027275 159.316783)
		(width 0.15)
		(layer "B.Cu")
		(net 34)
	)
	(arc
		(start 111.776966 160.86328)
		(mid 111.30674 160.668505)
		(end 110.836513 160.863279)
		(width 0.15)
		(layer "B.Cu")
		(net 34)
	)
	(segment
		(start 108.112462 126.085251)
		(end 108.181962 126.154751)
		(width 0.153)
		(layer "F.Cu")
		(net 35)
	)
	(segment
		(start 107.869462 124.175458)
		(end 107.868962 124.174958)
		(width 0.153)
		(layer "F.Cu")
		(net 35)
	)
	(segment
		(start 108.034212 126.86575)
		(end 108.181962 126.718)
		(width 0.153)
		(layer "F.Cu")
		(net 35)
	)
	(segment
		(start 117.403963 160.951499)
		(end 117.567962 160.7875)
		(width 0.15)
		(layer "F.Cu")
		(net 35)
	)
	(segment
		(start 108.113462 125.375825)
		(end 108.113462 124.6)
		(width 0.153)
		(layer "F.Cu")
		(net 35)
	)
	(segment
		(start 116.114462 160.9515)
		(end 117.403963 160.951499)
		(width 0.15)
		(layer "F.Cu")
		(net 35)
	)
	(segment
		(start 116.079962 160.917)
		(end 116.114462 160.9515)
		(width 0.15)
		(layer "F.Cu")
		(net 35)
	)
	(segment
		(start 107.868962 124.174958)
		(end 107.868962 122.568958)
		(width 0.153)
		(layer "F.Cu")
		(net 35)
	)
	(segment
		(start 108.113462 125.745325)
		(end 108.113462 124.970325)
		(width 0.153)
		(layer "F.Cu")
		(net 35)
	)
	(segment
		(start 108.113462 124.6)
		(end 107.869462 124.356)
		(width 0.153)
		(layer "F.Cu")
		(net 35)
	)
	(segment
		(start 107.869462 124.356)
		(end 107.869462 124.175458)
		(width 0.153)
		(layer "F.Cu")
		(net 35)
	)
	(segment
		(start 115.554961 160.917)
		(end 116.079962 160.917)
		(width 0.15)
		(layer "F.Cu")
		(net 35)
	)
	(segment
		(start 108.112462 125.729)
		(end 108.112462 126.085251)
		(width 0.153)
		(layer "F.Cu")
		(net 35)
	)
	(segment
		(start 108.181962 126.718)
		(end 108.181962 126.154751)
		(width 0.153)
		(layer "F.Cu")
		(net 35)
	)
	(via
		(at 117.567962 160.7875)
		(size 0.45)
		(drill 0.1)
		(layers "F.Cu" "B.Cu")
		(net 35)
	)
	(via
		(at 108.034212 126.86575)
		(size 0.45)
		(drill 0.1)
		(layers "F.Cu" "B.Cu")
		(net 35)
	)
	(segment
		(start 108.198211 127.2065)
		(end 108.198211 127.029749)
		(width 0.15)
		(layer "B.Cu")
		(net 35)
	)
	(segment
		(start 107.476289 159.999143)
		(end 107.476289 159.999142)
		(width 0.15)
		(layer "B.Cu")
		(net 35)
	)
	(segment
		(start 111.06986 161.096624)
		(end 111.069859 161.096625)
		(width 0.15)
		(layer "B.Cu")
		(net 35)
	)
	(segment
		(start 111.543622 161.096626)
		(end 111.543621 161.096625)
		(width 0.15)
		(layer "B.Cu")
		(net 35)
	)
	(segment
		(start 110.559616 163.8815)
		(end 110.366289 163.688172)
		(width 0.15)
		(layer "B.Cu")
		(net 35)
	)
	(segment
		(start 103.152962 134.318154)
		(end 108.198211 129.272905)
		(width 0.15)
		(layer "B.Cu")
		(net 35)
	)
	(segment
		(start 117.496308 163.8815)
		(end 115.907962 163.8815)
		(width 0.15)
		(layer "B.Cu")
		(net 35)
	)
	(segment
		(start 118.266308 160.9515)
		(end 118.792962 161.478154)
		(width 0.15)
		(layer "B.Cu")
		(net 35)
	)
	(segment
		(start 118.792962 161.478154)
		(end 118.792962 162.584846)
		(width 0.15)
		(layer "B.Cu")
		(net 35)
	)
	(segment
		(start 107.476289 159.999142)
		(end 107.592961 159.882469)
		(width 0.15)
		(layer "B.Cu")
		(net 35)
	)
	(segment
		(start 114.872962 163.1515)
		(end 114.872962 163.3165)
		(width 0.15)
		(layer "B.Cu")
		(net 35)
	)
	(segment
		(start 107.26062 159.550128)
		(end 107.26062 159.550129)
		(width 0.15)
		(layer "B.Cu")
		(net 35)
	)
	(segment
		(start 118.792962 162.584846)
		(end 117.496308 163.8815)
		(width 0.15)
		(layer "B.Cu")
		(net 35)
	)
	(segment
		(start 103.152962 156.474846)
		(end 103.152962 134.318154)
		(width 0.15)
		(layer "B.Cu")
		(net 35)
	)
	(segment
		(start 108.813212 128.491499)
		(end 108.978213 128.491499)
		(width 0.15)
		(layer "B.Cu")
		(net 35)
	)
	(segment
		(start 107.26062 159.550129)
		(end 107.143947 159.666801)
		(width 0.15)
		(layer "B.Cu")
		(net 35)
	)
	(segment
		(start 108.198211 129.272905)
		(end 108.198211 129.1065)
		(width 0.15)
		(layer "B.Cu")
		(net 35)
	)
	(segment
		(start 111.069859 161.096625)
		(end 109.892526 162.273957)
		(width 0.15)
		(layer "B.Cu")
		(net 35)
	)
	(segment
		(start 114.307962 163.8815)
		(end 110.559616 163.8815)
		(width 0.15)
		(layer "B.Cu")
		(net 35)
	)
	(segment
		(start 107.537861 160.859745)
		(end 107.476289 160.798173)
		(width 0.15)
		(layer "B.Cu")
		(net 35)
	)
	(segment
		(start 117.567962 160.7875)
		(end 117.731962 160.9515)
		(width 0.15)
		(layer "B.Cu")
		(net 35)
	)
	(segment
		(start 110.129408 159.682412)
		(end 110.129407 159.682411)
		(width 0.15)
		(layer "B.Cu")
		(net 35)
	)
	(segment
		(start 109.655645 159.682411)
		(end 108.478312 160.859743)
		(width 0.15)
		(layer "B.Cu")
		(net 35)
	)
	(segment
		(start 108.952075 162.273959)
		(end 108.952075 162.273958)
		(width 0.15)
		(layer "B.Cu")
		(net 35)
	)
	(segment
		(start 108.952075 161.333506)
		(end 110.129407 160.156173)
		(width 0.15)
		(layer "B.Cu")
		(net 35)
	)
	(segment
		(start 108.978213 127.821501)
		(end 108.813212 127.821501)
		(width 0.15)
		(layer "B.Cu")
		(net 35)
	)
	(segment
		(start 106.344917 159.666801)
		(end 106.344916 159.666801)
		(width 0.15)
		(layer "B.Cu")
		(net 35)
	)
	(segment
		(start 107.53786 160.859743)
		(end 107.537861 160.859745)
		(width 0.15)
		(layer "B.Cu")
		(net 35)
	)
	(segment
		(start 108.198211 127.029749)
		(end 108.034212 126.86575)
		(width 0.15)
		(layer "B.Cu")
		(net 35)
	)
	(segment
		(start 110.366289 162.74772)
		(end 111.543621 161.570387)
		(width 0.15)
		(layer "B.Cu")
		(net 35)
	)
	(segment
		(start 117.731962 160.9515)
		(end 118.266308 160.9515)
		(width 0.15)
		(layer "B.Cu")
		(net 35)
	)
	(segment
		(start 115.342962 163.3165)
		(end 115.342962 163.1515)
		(width 0.15)
		(layer "B.Cu")
		(net 35)
	)
	(segment
		(start 106.344916 159.666801)
		(end 103.152962 156.474846)
		(width 0.15)
		(layer "B.Cu")
		(net 35)
	)
	(segment
		(start 109.263212 128.2065)
		(end 109.263212 128.1065)
		(width 0.15)
		(layer "B.Cu")
		(net 35)
	)
	(segment
		(start 108.952074 162.273957)
		(end 108.952075 162.273959)
		(width 0.15)
		(layer "B.Cu")
		(net 35)
	)
	(segment
		(start 109.655646 159.68241)
		(end 109.655645 159.682411)
		(width 0.15)
		(layer "B.Cu")
		(net 35)
	)
	(arc
		(start 107.592961 159.882469)
		(mid 107.661791 159.716299)
		(end 107.592961 159.550129)
		(width 0.15)
		(layer "B.Cu")
		(net 35)
	)
	(arc
		(start 109.263212 128.1065)
		(mid 109.179738 127.904975)
		(end 108.978213 127.821501)
		(width 0.15)
		(layer "B.Cu")
		(net 35)
	)
	(arc
		(start 114.872962 163.3165)
		(mid 114.707477 163.716015)
		(end 114.307962 163.8815)
		(width 0.15)
		(layer "B.Cu")
		(net 35)
	)
	(arc
		(start 108.198211 129.1065)
		(mid 108.378341 128.671629)
		(end 108.813212 128.491499)
		(width 0.15)
		(layer "B.Cu")
		(net 35)
	)
	(arc
		(start 108.952075 162.273958)
		(mid 108.757301 161.803732)
		(end 108.952075 161.333506)
		(width 0.15)
		(layer "B.Cu")
		(net 35)
	)
	(arc
		(start 110.129407 159.682411)
		(mid 109.892527 159.584291)
		(end 109.655646 159.68241)
		(width 0.15)
		(layer "B.Cu")
		(net 35)
	)
	(arc
		(start 115.342962 163.1515)
		(mid 115.274132 162.98533)
		(end 115.107962 162.9165)
		(width 0.15)
		(layer "B.Cu")
		(net 35)
	)
	(arc
		(start 109.892526 162.273957)
		(mid 109.4223 162.468731)
		(end 108.952074 162.273957)
		(width 0.15)
		(layer "B.Cu")
		(net 35)
	)
	(arc
		(start 108.978213 128.491499)
		(mid 109.179738 128.408025)
		(end 109.263212 128.2065)
		(width 0.15)
		(layer "B.Cu")
		(net 35)
	)
	(arc
		(start 107.476289 160.798173)
		(mid 107.310804 160.398658)
		(end 107.476289 159.999143)
		(width 0.15)
		(layer "B.Cu")
		(net 35)
	)
	(arc
		(start 111.543621 161.570387)
		(mid 111.641741 161.333507)
		(end 111.543622 161.096626)
		(width 0.15)
		(layer "B.Cu")
		(net 35)
	)
	(arc
		(start 107.592961 159.550129)
		(mid 107.426791 159.481298)
		(end 107.26062 159.550128)
		(width 0.15)
		(layer "B.Cu")
		(net 35)
	)
	(arc
		(start 111.543621 161.096625)
		(mid 111.306741 160.998505)
		(end 111.06986 161.096624)
		(width 0.15)
		(layer "B.Cu")
		(net 35)
	)
	(arc
		(start 110.129407 160.156173)
		(mid 110.227527 159.919293)
		(end 110.129408 159.682412)
		(width 0.15)
		(layer "B.Cu")
		(net 35)
	)
	(arc
		(start 110.366289 163.688172)
		(mid 110.171515 163.217946)
		(end 110.366289 162.74772)
		(width 0.15)
		(layer "B.Cu")
		(net 35)
	)
	(arc
		(start 115.907962 163.8815)
		(mid 115.508447 163.716015)
		(end 115.342962 163.3165)
		(width 0.15)
		(layer "B.Cu")
		(net 35)
	)
	(arc
		(start 108.478312 160.859743)
		(mid 108.008086 161.054517)
		(end 107.53786 160.859743)
		(width 0.15)
		(layer "B.Cu")
		(net 35)
	)
	(arc
		(start 107.143947 159.666801)
		(mid 106.744432 159.832286)
		(end 106.344917 159.666801)
		(width 0.15)
		(layer "B.Cu")
		(net 35)
	)
	(arc
		(start 115.107962 162.9165)
		(mid 114.941792 162.98533)
		(end 114.872962 163.1515)
		(width 0.15)
		(layer "B.Cu")
		(net 35)
	)
	(arc
		(start 108.813212 127.821501)
		(mid 108.378341 127.641371)
		(end 108.198211 127.2065)
		(width 0.15)
		(layer "B.Cu")
		(net 35)
	)
	(segment
		(start 88.789962 151.0885)
		(end 88.604462 150.903)
		(width 0.127)
		(layer "F.Cu")
		(net 36)
	)
	(segment
		(start 83.477462 147.645146)
		(end 83.477462 146.150618)
		(width 0.127)
		(layer "F.Cu")
		(net 36)
	)
	(segment
		(start 84.717962 137.396736)
		(end 84.828462 137.507236)
		(width 0.127)
		(layer "F.Cu")
		(net 36)
	)
	(segment
		(start 81.840962 140.4145)
		(end 81.840962 137.997108)
		(width 0.127)
		(layer "F.Cu")
		(net 36)
	)
	(segment
		(start 83.477462 146.150618)
		(end 83.765962 145.862118)
		(width 0.127)
		(layer "F.Cu")
		(net 36)
	)
	(segment
		(start 86.858726 149.553)
		(end 85.385316 149.553)
		(width 0.127)
		(layer "F.Cu")
		(net 36)
	)
	(segment
		(start 83.765962 145.862118)
		(end 83.765962 142.3395)
		(width 0.127)
		(layer "F.Cu")
		(net 36)
	)
	(segment
		(start 84.828462 137.507236)
		(end 85.317962 137.507236)
		(width 0.127)
		(layer "F.Cu")
		(net 36)
	)
	(segment
		(start 88.208726 150.903)
		(end 86.858726 149.553)
		(width 0.127)
		(layer "F.Cu")
		(net 36)
	)
	(segment
		(start 85.385316 149.553)
		(end 83.477462 147.645146)
		(width 0.127)
		(layer "F.Cu")
		(net 36)
	)
	(segment
		(start 88.789962 151.6665)
		(end 88.789962 151.0885)
		(width 0.127)
		(layer "F.Cu")
		(net 36)
	)
	(segment
		(start 83.765962 142.3395)
		(end 81.840962 140.4145)
		(width 0.127)
		(layer "F.Cu")
		(net 36)
	)
	(segment
		(start 81.840962 137.997108)
		(end 82.441334 137.396736)
		(width 0.127)
		(layer "F.Cu")
		(net 36)
	)
	(segment
		(start 88.604462 150.903)
		(end 88.208726 150.903)
		(width 0.127)
		(layer "F.Cu")
		(net 36)
	)
	(segment
		(start 82.441334 137.396736)
		(end 84.717962 137.396736)
		(width 0.127)
		(layer "F.Cu")
		(net 36)
	)
	(segment
		(start 82.092962 140.310118)
		(end 82.092962 138.10149)
		(width 0.127)
		(layer "F.Cu")
		(net 37)
	)
	(segment
		(start 86.963108 149.301)
		(end 85.489698 149.301)
		(width 0.127)
		(layer "F.Cu")
		(net 37)
	)
	(segment
		(start 89.192962 151.135118)
		(end 88.708844 150.651)
		(width 0.127)
		(layer "F.Cu")
		(net 37)
	)
	(segment
		(start 82.092962 138.10149)
		(end 82.545716 137.648736)
		(width 0.127)
		(layer "F.Cu")
		(net 37)
	)
	(segment
		(start 88.708844 150.651)
		(end 88.313108 150.651)
		(width 0.127)
		(layer "F.Cu")
		(net 37)
	)
	(segment
		(start 85.489698 149.301)
		(end 83.729462 147.540764)
		(width 0.127)
		(layer "F.Cu")
		(net 37)
	)
	(segment
		(start 89.192962 151.6665)
		(end 89.192962 151.135118)
		(width 0.127)
		(layer "F.Cu")
		(net 37)
	)
	(segment
		(start 83.729462 146.255)
		(end 84.017962 145.9665)
		(width 0.127)
		(layer "F.Cu")
		(net 37)
	)
	(segment
		(start 84.808806 137.907236)
		(end 85.317962 137.907236)
		(width 0.127)
		(layer "F.Cu")
		(net 37)
	)
	(segment
		(start 84.550306 137.648736)
		(end 84.808806 137.907236)
		(width 0.127)
		(layer "F.Cu")
		(net 37)
	)
	(segment
		(start 84.017962 142.235118)
		(end 82.092962 140.310118)
		(width 0.127)
		(layer "F.Cu")
		(net 37)
	)
	(segment
		(start 83.729462 147.540764)
		(end 83.729462 146.255)
		(width 0.127)
		(layer "F.Cu")
		(net 37)
	)
	(segment
		(start 88.313108 150.651)
		(end 86.963108 149.301)
		(width 0.127)
		(layer "F.Cu")
		(net 37)
	)
	(segment
		(start 82.545716 137.648736)
		(end 84.550306 137.648736)
		(width 0.127)
		(layer "F.Cu")
		(net 37)
	)
	(segment
		(start 84.017962 145.9665)
		(end 84.017962 142.235118)
		(width 0.127)
		(layer "F.Cu")
		(net 37)
	)
	(segment
		(start 112.473961 145.316)
		(end 111.941961 145.316)
		(width 0.182)
		(layer "F.Cu")
		(net 38)
	)
	(segment
		(start 108.49625 145.3275)
		(end 108.151606 144.982856)
		(width 0.182)
		(layer "F.Cu")
		(net 38)
	)
	(segment
		(start 107.727341 144.170629)
		(end 107.72734 144.170629)
		(width 0.182)
		(layer "F.Cu")
		(net 38)
	)
	(segment
		(start 93.707962 125.89)
		(end 93.918962 125.679)
		(width 0.182)
		(layer "F.Cu")
		(net 38)
	)
	(segment
		(start 112.473961 145.316)
		(end 111.94896 145.316)
		(width 0.182)
		(layer "F.Cu")
		(net 38)
	)
	(segment
		(start 93.707962 128.589216)
		(end 93.707962 125.89)
		(width 0.182)
		(layer "F.Cu")
		(net 38)
	)
	(segment
		(start 111.94896 145.316)
		(end 111.93746 145.3275)
		(width 0.182)
		(layer "F.Cu")
		(net 38)
	)
	(segment
		(start 108.151605 144.594895)
		(end 108.151606 144.594894)
		(width 0.182)
		(layer "F.Cu")
		(net 38)
	)
	(segment
		(start 107.339379 144.17063)
		(end 107.339379 144.170629)
		(width 0.182)
		(layer "F.Cu")
		(net 38)
	)
	(segment
		(start 111.941961 145.316)
		(end 111.930461 145.3275)
		(width 0.182)
		(layer "F.Cu")
		(net 38)
	)
	(segment
		(start 97.995962 134.827212)
		(end 97.995962 132.877216)
		(width 0.182)
		(layer "F.Cu")
		(net 38)
	)
	(segment
		(start 107.727342 144.170628)
		(end 107.727341 144.170629)
		(width 0.182)
		(layer "F.Cu")
		(net 38)
	)
	(segment
		(start 93.918962 125.679)
		(end 93.918962 125.003999)
		(width 0.182)
		(layer "F.Cu")
		(net 38)
	)
	(segment
		(start 107.339379 144.170629)
		(end 97.995962 134.827212)
		(width 0.182)
		(layer "F.Cu")
		(net 38)
	)
	(segment
		(start 111.93746 145.3275)
		(end 108.49625 145.3275)
		(width 0.182)
		(layer "F.Cu")
		(net 38)
	)
	(segment
		(start 108.151606 144.594894)
		(end 108.151606 144.594893)
		(width 0.182)
		(layer "F.Cu")
		(net 38)
	)
	(segment
		(start 97.995962 132.877216)
		(end 93.707962 128.589216)
		(width 0.182)
		(layer "F.Cu")
		(net 38)
	)
	(segment
		(start 108.151607 144.206932)
		(end 108.151606 144.206932)
		(width 0.182)
		(layer "F.Cu")
		(net 38)
	)
	(segment
		(start 108.151606 144.206932)
		(end 108.115303 144.170629)
		(width 0.182)
		(layer "F.Cu")
		(net 38)
	)
	(arc
		(start 108.151606 144.982856)
		(mid 108.071256 144.788876)
		(end 108.151605 144.594895)
		(width 0.182)
		(layer "F.Cu")
		(net 38)
	)
	(arc
		(start 107.72734 144.170629)
		(mid 107.53336 144.250979)
		(end 107.339379 144.17063)
		(width 0.182)
		(layer "F.Cu")
		(net 38)
	)
	(arc
		(start 108.151606 144.594893)
		(mid 108.231956 144.400913)
		(end 108.151607 144.206932)
		(width 0.182)
		(layer "F.Cu")
		(net 38)
	)
	(arc
		(start 108.115303 144.170629)
		(mid 107.921323 144.090279)
		(end 107.727342 144.170628)
		(width 0.182)
		(layer "F.Cu")
		(net 38)
	)
	(segment
		(start 97.617962 134.983788)
		(end 97.617962 133.033788)
		(width 0.182)
		(layer "F.Cu")
		(net 39)
	)
	(segment
		(start 93.329962 128.745788)
		(end 93.329962 125.89)
		(width 0.182)
		(layer "F.Cu")
		(net 39)
	)
	(segment
		(start 93.118962 125.679)
		(end 93.118962 125.003999)
		(width 0.182)
		(layer "F.Cu")
		(net 39)
	)
	(segment
		(start 93.329962 125.89)
		(end 93.118962 125.679)
		(width 0.182)
		(layer "F.Cu")
		(net 39)
	)
	(segment
		(start 112.473961 145.717)
		(end 111.94896 145.717)
		(width 0.182)
		(layer "F.Cu")
		(net 39)
	)
	(segment
		(start 108.339674 145.7055)
		(end 97.617962 134.983788)
		(width 0.182)
		(layer "F.Cu")
		(net 39)
	)
	(segment
		(start 111.93746 145.7055)
		(end 108.339674 145.7055)
		(width 0.182)
		(layer "F.Cu")
		(net 39)
	)
	(segment
		(start 97.617962 133.033788)
		(end 93.329962 128.745788)
		(width 0.182)
		(layer "F.Cu")
		(net 39)
	)
	(segment
		(start 111.94896 145.717)
		(end 111.93746 145.7055)
		(width 0.182)
		(layer "F.Cu")
		(net 39)
	)
	(segment
		(start 119.947962 143.580224)
		(end 119.947962 124.650763)
		(width 0.17)
		(layer "F.Cu")
		(net 40)
	)
	(segment
		(start 119.947962 124.650763)
		(end 123.111103 121.487622)
		(width 0.17)
		(layer "F.Cu")
		(net 40)
	)
	(segment
		(start 116.970686 146.5575)
		(end 119.947962 143.580224)
		(width 0.17)
		(layer "F.Cu")
		(net 40)
	)
	(segment
		(start 115.554961 146.518)
		(end 116.079962 146.518)
		(width 0.17)
		(layer "F.Cu")
		(net 40)
	)
	(segment
		(start 116.079962 146.518)
		(end 116.119462 146.5575)
		(width 0.17)
		(layer "F.Cu")
		(net 40)
	)
	(segment
		(start 116.119462 146.5575)
		(end 116.970686 146.5575)
		(width 0.17)
		(layer "F.Cu")
		(net 40)
	)
	(segment
		(start 123.111103 121.487622)
		(end 123.111103 121.254277)
		(width 0.17)
		(layer "F.Cu")
		(net 40)
	)
	(via
		(at 123.111103 121.254277)
		(size 0.5)
		(drill 0.15)
		(layers "F.Cu" "B.Cu")
		(net 40)
	)
	(segment
		(start 123.344448 121.254277)
		(end 123.111103 121.254277)
		(width 0.17)
		(layer "B.Cu")
		(net 40)
	)
	(segment
		(start 127.005461 120.519)
		(end 126.915961 120.6085)
		(width 0.17)
		(layer "B.Cu")
		(net 40)
	)
	(segment
		(start 126.915961 120.6085)
		(end 123.990224 120.6085)
		(width 0.17)
		(layer "B.Cu")
		(net 40)
	)
	(segment
		(start 128.167962 120.519)
		(end 127.005461 120.519)
		(width 0.17)
		(layer "B.Cu")
		(net 40)
	)
	(segment
		(start 123.990224 120.6085)
		(end 123.411862 121.186862)
		(width 0.17)
		(layer "B.Cu")
		(net 40)
	)
	(segment
		(start 123.411862 121.186863)
		(end 123.344448 121.254277)
		(width 0.17)
		(layer "B.Cu")
		(net 40)
	)
	(segment
		(start 123.411862 121.186862)
		(end 123.411862 121.186863)
		(width 0.17)
		(layer "B.Cu")
		(net 40)
	)
	(segment
		(start 117.103238 146.8775)
		(end 120.267962 143.712776)
		(width 0.17)
		(layer "F.Cu")
		(net 41)
	)
	(segment
		(start 115.554961 146.917)
		(end 116.079962 146.917)
		(width 0.17)
		(layer "F.Cu")
		(net 41)
	)
	(segment
		(start 116.079962 146.917)
		(end 116.119462 146.8775)
		(width 0.17)
		(layer "F.Cu")
		(net 41)
	)
	(segment
		(start 116.119462 146.8775)
		(end 117.103238 146.8775)
		(width 0.17)
		(layer "F.Cu")
		(net 41)
	)
	(segment
		(start 120.267962 143.712776)
		(end 120.267962 124.783313)
		(width 0.17)
		(layer "F.Cu")
		(net 41)
	)
	(segment
		(start 123.337378 121.713897)
		(end 123.570723 121.713897)
		(width 0.17)
		(layer "F.Cu")
		(net 41)
	)
	(segment
		(start 120.267962 124.783313)
		(end 123.337378 121.713897)
		(width 0.17)
		(layer "F.Cu")
		(net 41)
	)
	(via
		(at 123.570723 121.713897)
		(size 0.5)
		(drill 0.15)
		(layers "F.Cu" "B.Cu")
		(net 41)
	)
	(segment
		(start 127.005461 121.018)
		(end 126.915961 120.9285)
		(width 0.17)
		(layer "B.Cu")
		(net 41)
	)
	(segment
		(start 128.167962 121.018)
		(end 127.005461 121.018)
		(width 0.17)
		(layer "B.Cu")
		(net 41)
	)
	(segment
		(start 126.915961 120.9285)
		(end 124.122776 120.9285)
		(width 0.17)
		(layer "B.Cu")
		(net 41)
	)
	(segment
		(start 123.570723 121.480552)
		(end 123.570723 121.713897)
		(width 0.17)
		(layer "B.Cu")
		(net 41)
	)
	(segment
		(start 123.638138 121.413138)
		(end 123.638137 121.413138)
		(width 0.17)
		(layer "B.Cu")
		(net 41)
	)
	(segment
		(start 123.638137 121.413138)
		(end 123.570723 121.480552)
		(width 0.17)
		(layer "B.Cu")
		(net 41)
	)
	(segment
		(start 124.122776 120.9285)
		(end 123.638138 121.413138)
		(width 0.17)
		(layer "B.Cu")
		(net 41)
	)
	(segment
		(start 112.998962 147.717)
		(end 113.034462 147.7525)
		(width 0.15)
		(layer "F.Cu")
		(net 42)
	)
	(segment
		(start 113.532963 147.752499)
		(end 113.692962 147.5925)
		(width 0.15)
		(layer "F.Cu")
		(net 42)
	)
	(segment
		(start 112.473961 147.717)
		(end 112.998962 147.717)
		(width 0.15)
		(layer "F.Cu")
		(net 42)
	)
	(segment
		(start 113.034462 147.7525)
		(end 113.532963 147.752499)
		(width 0.15)
		(layer "F.Cu")
		(net 42)
	)
	(via
		(at 113.692962 147.5925)
		(size 0.45)
		(drill 0.1)
		(layers "F.Cu" "B.Cu")
		(net 42)
	)
	(segment
		(start 118.852962 149.6165)
		(end 118.852962 150.437101)
		(width 0.15)
		(layer "B.Cu")
		(net 42)
	)
	(segment
		(start 113.692962 147.5925)
		(end 113.850461 147.749999)
		(width 0.135)
		(layer "B.Cu")
		(net 42)
	)
	(segment
		(start 113.692962 147.5925)
		(end 113.852961 147.752499)
		(width 0.15)
		(layer "B.Cu")
		(net 42)
	)
	(segment
		(start 134.352962 137.738154)
		(end 134.352962 136.558154)
		(width 0.15)
		(layer "B.Cu")
		(net 42)
	)
	(segment
		(start 136.567961 135.4665)
		(end 137.467962 135.4665)
		(width 0.15)
		(layer "B.Cu")
		(net 42)
	)
	(segment
		(start 113.852961 147.752499)
		(end 114.337307 147.752499)
		(width 0.15)
		(layer "B.Cu")
		(net 42)
	)
	(segment
		(start 121.522962 150.437101)
		(end 121.522962 149.6165)
		(width 0.15)
		(layer "B.Cu")
		(net 42)
	)
	(segment
		(start 135.360616 135.5505)
		(end 136.483961 135.5505)
		(width 0.15)
		(layer "B.Cu")
		(net 42)
	)
	(segment
		(start 124.187962 148.9515)
		(end 124.909616 148.9515)
		(width 0.15)
		(layer "B.Cu")
		(net 42)
	)
	(segment
		(start 123.522962 150.437078)
		(end 123.522962 149.6165)
		(width 0.15)
		(layer "B.Cu")
		(net 42)
	)
	(segment
		(start 114.337307 147.752499)
		(end 115.536308 148.9515)
		(width 0.15)
		(layer "B.Cu")
		(net 42)
	)
	(segment
		(start 124.909616 148.9515)
		(end 129.572962 144.288154)
		(width 0.15)
		(layer "B.Cu")
		(net 42)
	)
	(segment
		(start 119.522962 150.437101)
		(end 119.522962 149.6165)
		(width 0.15)
		(layer "B.Cu")
		(net 42)
	)
	(segment
		(start 120.852962 149.6165)
		(end 120.852962 150.437101)
		(width 0.15)
		(layer "B.Cu")
		(net 42)
	)
	(segment
		(start 122.852962 149.6165)
		(end 122.852962 150.437078)
		(width 0.15)
		(layer "B.Cu")
		(net 42)
	)
	(segment
		(start 134.352962 136.558154)
		(end 135.360616 135.5505)
		(width 0.15)
		(layer "B.Cu")
		(net 42)
	)
	(segment
		(start 136.483961 135.5505)
		(end 136.567961 135.4665)
		(width 0.15)
		(layer "B.Cu")
		(net 42)
	)
	(segment
		(start 129.572962 144.288154)
		(end 129.572962 142.518154)
		(width 0.15)
		(layer "B.Cu")
		(net 42)
	)
	(segment
		(start 115.536308 148.9515)
		(end 118.187962 148.9515)
		(width 0.15)
		(layer "B.Cu")
		(net 42)
	)
	(segment
		(start 129.572962 142.518154)
		(end 134.352962 137.738154)
		(width 0.15)
		(layer "B.Cu")
		(net 42)
	)
	(arc
		(start 123.187962 150.772078)
		(mid 123.424843 150.673959)
		(end 123.522962 150.437078)
		(width 0.15)
		(layer "B.Cu")
		(net 42)
	)
	(arc
		(start 122.852962 150.437078)
		(mid 122.951081 150.673959)
		(end 123.187962 150.772078)
		(width 0.15)
		(layer "B.Cu")
		(net 42)
	)
	(arc
		(start 121.187962 150.772101)
		(mid 121.424843 150.673982)
		(end 121.522962 150.437101)
		(width 0.15)
		(layer "B.Cu")
		(net 42)
	)
	(arc
		(start 119.522962 149.6165)
		(mid 119.717736 149.146274)
		(end 120.187962 148.9515)
		(width 0.15)
		(layer "B.Cu")
		(net 42)
	)
	(arc
		(start 118.852962 150.437101)
		(mid 118.951081 150.673982)
		(end 119.187962 150.772101)
		(width 0.15)
		(layer "B.Cu")
		(net 42)
	)
	(arc
		(start 120.187962 148.9515)
		(mid 120.658188 149.146274)
		(end 120.852962 149.6165)
		(width 0.15)
		(layer "B.Cu")
		(net 42)
	)
	(arc
		(start 121.522962 149.6165)
		(mid 121.717736 149.146274)
		(end 122.187962 148.9515)
		(width 0.15)
		(layer "B.Cu")
		(net 42)
	)
	(arc
		(start 123.522962 149.6165)
		(mid 123.717736 149.146274)
		(end 124.187962 148.9515)
		(width 0.15)
		(layer "B.Cu")
		(net 42)
	)
	(arc
		(start 118.187962 148.9515)
		(mid 118.658188 149.146274)
		(end 118.852962 149.6165)
		(width 0.15)
		(layer "B.Cu")
		(net 42)
	)
	(arc
		(start 122.187962 148.9515)
		(mid 122.658188 149.146274)
		(end 122.852962 149.6165)
		(width 0.15)
		(layer "B.Cu")
		(net 42)
	)
	(arc
		(start 120.852962 150.437101)
		(mid 120.951081 150.673982)
		(end 121.187962 150.772101)
		(width 0.15)
		(layer "B.Cu")
		(net 42)
	)
	(arc
		(start 119.187962 150.772101)
		(mid 119.424843 150.673982)
		(end 119.522962 150.437101)
		(width 0.15)
		(layer "B.Cu")
		(net 42)
	)
	(segment
		(start 73.997962 157.2915)
		(end 74.842962 157.2915)
		(width 0.2)
		(layer "F.Cu")
		(net 43)
	)
	(via
		(at 74.842962 157.2915)
		(size 0.5)
		(drill 0.15)
		(layers "F.Cu" "B.Cu")
		(net 43)
	)
	(via
		(at 62.432962 164.1365)
		(size 0.45)
		(drill 0.1)
		(layers "F.Cu" "B.Cu")
		(net 43)
	)
	(via
		(at 43.717962 153.7765)
		(size 0.5)
		(drill 0.15)
		(layers "F.Cu" "B.Cu")
		(net 43)
	)
	(via
		(at 46.247962 155.9565)
		(size 0.5)
		(drill 0.15)
		(layers "F.Cu" "B.Cu")
		(net 43)
	)
	(via
		(at 48.837962 154.3865)
		(size 0.45)
		(drill 0.1)
		(layers "F.Cu" "B.Cu")
		(net 43)
	)
	(via
		(at 42.877962 155.9065)
		(size 0.5)
		(drill 0.15)
		(layers "F.Cu" "B.Cu")
		(net 43)
	)
	(via
		(at 52.717962 154.5665)
		(size 0.45)
		(drill 0.1)
		(layers "F.Cu" "B.Cu")
		(free yes)
		(net 43)
	)
	(via
		(at 108.567962 134.8875)
		(size 0.45)
		(drill 0.1)
		(layers "F.Cu" "B.Cu")
		(net 43)
	)
	(via
		(at 106.417962 134.8865)
		(size 0.45)
		(drill 0.1)
		(layers "F.Cu" "B.Cu")
		(net 43)
	)
	(via
		(at 50.727962 154.3565)
		(size 0.45)
		(drill 0.1)
		(layers "F.Cu" "B.Cu")
		(net 43)
	)
	(via
		(at 45.317962 153.7765)
		(size 0.5)
		(drill 0.15)
		(layers "F.Cu" "B.Cu")
		(net 43)
	)
	(via
		(at 47.197962 154.6765)
		(size 0.45)
		(drill 0.1)
		(layers "F.Cu" "B.Cu")
		(net 43)
	)
	(via
		(at 62.432962 164.9715)
		(size 0.45)
		(drill 0.1)
		(layers "F.Cu" "B.Cu")
		(net 43)
	)
	(via
		(at 44.517962 153.7765)
		(size 0.5)
		(drill 0.15)
		(layers "F.Cu" "B.Cu")
		(net 43)
	)
	(via
		(at 46.187962 153.7865)
		(size 0.5)
		(drill 0.15)
		(layers "F.Cu" "B.Cu")
		(net 43)
	)
	(segment
		(start 44.617962 155.6095)
		(end 45.592962 154.6345)
		(width 0.35)
		(layer "B.Cu")
		(net 43)
	)
	(segment
		(start 43.110962 155.6095)
		(end 44.617962 155.6095)
		(width 0.35)
		(layer "B.Cu")
		(net 43)
	)
	(segment
		(start 44.942962 155.2845)
		(end 44.942962 153.8665)
		(width 0.35)
		(layer "B.Cu")
		(net 43)
	)
	(segment
		(start 109.313962 134.8875)
		(end 107.618962 134.8875)
		(width 0.6)
		(layer "B.Cu")
		(net 43)
	)
	(segment
		(start 65.157962 164.9965)
		(end 63.517962 164.9965)
		(width 0.5)
		(layer "B.Cu")
		(net 43)
	)
	(segment
		(start 43.617962 154.6095)
		(end 43.617962 153.9165)
		(width 0.35)
		(layer "B.Cu")
		(net 43)
	)
	(segment
		(start 44.292962 155.2845)
		(end 44.292962 153.8915)
		(width 0.35)
		(layer "B.Cu")
		(net 43)
	)
	(segment
		(start 44.617962 155.6095)
		(end 43.617962 154.6095)
		(width 0.35)
		(layer "B.Cu")
		(net 43)
	)
	(segment
		(start 52.543272 155.3165)
		(end 52.146694 154.919922)
		(width 0.254)
		(layer "B.Cu")
		(net 43)
	)
	(segment
		(start 108.567962 134.8875)
		(end 109.313962 134.8875)
		(width 0.6)
		(layer "B.Cu")
		(net 43)
	)
	(segment
		(start 53.615962 155.3165)
		(end 52.543272 155.3165)
		(width 0.254)
		(layer "B.Cu")
		(net 43)
	)
	(segment
		(start 44.617962 155.6095)
		(end 46.200962 155.6095)
		(width 0.35)
		(layer "B.Cu")
		(net 43)
	)
	(segment
		(start 108.567962 134.8875)
		(end 106.418962 134.8875)
		(width 0.6)
		(layer "B.Cu")
		(net 43)
	)
	(segment
		(start 63.167962 164.9915)
		(end 62.427962 164.9915)
		(width 0.75)
		(layer "B.Cu")
		(net 43)
	)
	(segment
		(start 44.617962 155.6095)
		(end 44.617962 156.6665)
		(width 0.35)
		(layer "B.Cu")
		(net 43)
	)
	(segment
		(start 44.617962 155.6095)
		(end 45.617962 154.6095)
		(width 0.35)
		(layer "B.Cu")
		(net 43)
	)
	(segment
		(start 50.742962 155.3165)
		(end 48.867962 155.3165)
		(width 1)
		(layer "B.Cu")
		(net 43)
	)
	(segment
		(start 62.432962 164.9715)
		(end 62.432962 163.7665)
		(width 0.254)
		(layer "B.Cu")
		(net 43)
	)
	(segment
		(start 106.418962 134.8875)
		(end 106.417962 134.8865)
		(width 0.6)
		(layer "B.Cu")
		(net 43)
	)
	(segment
		(start 62.432962 163.7665)
		(end 63.007962 163.1915)
		(width 0.254)
		(layer "B.Cu")
		(net 43)
	)
	(segment
		(start 45.592962 154.6345)
		(end 45.592962 153.8915)
		(width 0.35)
		(layer "B.Cu")
		(net 43)
	)
	(segment
		(start 108.260134 134.8875)
		(end 108.567962 134.8875)
		(width 0.75)
		(layer "In2.Cu")
		(net 43)
	)
	(segment
		(start 106.417962 137.2665)
		(end 106.417962 136.729672)
		(width 0.75)
		(layer "In2.Cu")
		(net 43)
	)
	(segment
		(start 63.575615 155.478847)
		(end 63.567962 155.4865)
		(width 0.75)
		(layer "In2.Cu")
		(net 43)
	)
	(segment
		(start 106.417962 135.5465)
		(end 106.547962 135.5465)
		(width 0.75)
		(layer "In2.Cu")
		(net 43)
	)
	(segment
		(start 106.417962 134.8865)
		(end 106.417962 135.5465)
		(width 0.75)
		(layer "In2.Cu")
		(net 43)
	)
	(segment
		(start 72.872962 157.2915)
		(end 74.842962 157.2915)
		(width 0.2)
		(layer "In2.Cu")
		(net 43)
	)
	(segment
		(start 106.417962 136.729672)
		(end 107.074548 136.073086)
		(width 0.75)
		(layer "In2.Cu")
		(net 43)
	)
	(segment
		(start 69.780309 155.478847)
		(end 70.420309 154.838847)
		(width 0.75)
		(layer "In2.Cu")
		(net 43)
	)
	(segment
		(start 76.742656 148.5165)
		(end 70.420309 154.838847)
		(width 0.75)
		(layer "In2.Cu")
		(net 43)
	)
	(segment
		(start 69.780309 155.478847)
		(end 63.575615 155.478847)
		(width 0.75)
		(layer "In2.Cu")
		(net 43)
	)
	(segment
		(start 95.167962 148.5165)
		(end 76.742656 148.5165)
		(width 0.75)
		(layer "In2.Cu")
		(net 43)
	)
	(segment
		(start 106.417962 135.5465)
		(end 106.417962 136.729672)
		(width 0.75)
		(layer "In2.Cu")
		(net 43)
	)
	(segment
		(start 70.420309 154.838847)
		(end 72.872962 157.2915)
		(width 0.2)
		(layer "In2.Cu")
		(net 43)
	)
	(segment
		(start 106.547962 135.5465)
		(end 107.074548 136.073086)
		(width 0.75)
		(layer "In2.Cu")
		(net 43)
	)
	(segment
		(start 106.417962 137.2665)
		(end 95.167962 148.5165)
		(width 0.75)
		(layer "In2.Cu")
		(net 43)
	)
	(segment
		(start 108.260134 134.8875)
		(end 107.074548 136.073086)
		(width 0.75)
		(layer "In2.Cu")
		(net 43)
	)
	(segment
		(start 113.532963 148.082501)
		(end 113.692962 148.2425)
		(width 0.15)
		(layer "F.Cu")
		(net 44)
	)
	(segment
		(start 112.473961 148.118)
		(end 112.998962 148.118)
		(width 0.15)
		(layer "F.Cu")
		(net 44)
	)
	(segment
		(start 113.034462 148.0825)
		(end 113.532963 148.082501)
		(width 0.15)
		(layer "F.Cu")
		(net 44)
	)
	(segment
		(start 112.998962 148.118)
		(end 113.034462 148.0825)
		(width 0.15)
		(layer "F.Cu")
		(net 44)
	)
	(via
		(at 113.692962 148.2425)
		(size 0.45)
		(drill 0.1)
		(layers "F.Cu" "B.Cu")
		(net 44)
	)
	(segment
		(start 129.902962 142.654846)
		(end 134.682962 137.874846)
		(width 0.15)
		(layer "B.Cu")
		(net 44)
	)
	(segment
		(start 118.522962 149.6165)
		(end 118.522962 150.437101)
		(width 0.15)
		(layer "B.Cu")
		(net 44)
	)
	(segment
		(start 129.902962 144.424846)
		(end 129.902962 142.654846)
		(width 0.15)
		(layer "B.Cu")
		(net 44)
	)
	(segment
		(start 136.483961 135.8805)
		(end 136.567961 135.9645)
		(width 0.15)
		(layer "B.Cu")
		(net 44)
	)
	(segment
		(start 122.522962 149.6165)
		(end 122.522962 150.437078)
		(width 0.15)
		(layer "B.Cu")
		(net 44)
	)
	(segment
		(start 115.399616 149.2815)
		(end 118.187962 149.2815)
		(width 0.15)
		(layer "B.Cu")
		(net 44)
	)
	(segment
		(start 134.682962 136.694846)
		(end 135.497308 135.8805)
		(width 0.15)
		(layer "B.Cu")
		(net 44)
	)
	(segment
		(start 120.522962 149.6165)
		(end 120.522962 150.437101)
		(width 0.15)
		(layer "B.Cu")
		(net 44)
	)
	(segment
		(start 125.046308 149.2815)
		(end 129.902962 144.424846)
		(width 0.15)
		(layer "B.Cu")
		(net 44)
	)
	(segment
		(start 121.852962 150.437101)
		(end 121.852962 149.6165)
		(width 0.15)
		(layer "B.Cu")
		(net 44)
	)
	(segment
		(start 135.497308 135.8805)
		(end 136.483961 135.8805)
		(width 0.15)
		(layer "B.Cu")
		(net 44)
	)
	(segment
		(start 113.852961 148.082501)
		(end 114.200617 148.082501)
		(width 0.15)
		(layer "B.Cu")
		(net 44)
	)
	(segment
		(start 124.187962 149.2815)
		(end 125.046308 149.2815)
		(width 0.15)
		(layer "B.Cu")
		(net 44)
	)
	(segment
		(start 114.200617 148.082501)
		(end 115.399616 149.2815)
		(width 0.15)
		(layer "B.Cu")
		(net 44)
	)
	(segment
		(start 136.567961 135.9645)
		(end 137.467962 135.9645)
		(width 0.15)
		(layer "B.Cu")
		(net 44)
	)
	(segment
		(start 134.682962 137.874846)
		(end 134.682962 136.694846)
		(width 0.15)
		(layer "B.Cu")
		(net 44)
	)
	(segment
		(start 113.692962 148.2425)
		(end 113.850462 148.085)
		(width 0.135)
		(layer "B.Cu")
		(net 44)
	)
	(segment
		(start 113.692962 148.2425)
		(end 113.852961 148.082501)
		(width 0.15)
		(layer "B.Cu")
		(net 44)
	)
	(segment
		(start 123.852962 150.437078)
		(end 123.852962 149.6165)
		(width 0.15)
		(layer "B.Cu")
		(net 44)
	)
	(segment
		(start 119.852962 150.437101)
		(end 119.852962 149.6165)
		(width 0.15)
		(layer "B.Cu")
		(net 44)
	)
	(arc
		(start 123.187962 151.102078)
		(mid 123.658188 150.907304)
		(end 123.852962 150.437078)
		(width 0.15)
		(layer "B.Cu")
		(net 44)
	)
	(arc
		(start 119.187962 151.102101)
		(mid 119.658188 150.907327)
		(end 119.852962 150.437101)
		(width 0.15)
		(layer "B.Cu")
		(net 44)
	)
	(arc
		(start 123.852962 149.6165)
		(mid 123.951081 149.379619)
		(end 124.187962 149.2815)
		(width 0.15)
		(layer "B.Cu")
		(net 44)
	)
	(arc
		(start 121.852962 149.6165)
		(mid 121.951081 149.379619)
		(end 122.187962 149.2815)
		(width 0.15)
		(layer "B.Cu")
		(net 44)
	)
	(arc
		(start 121.187962 151.102101)
		(mid 121.658188 150.907327)
		(end 121.852962 150.437101)
		(width 0.15)
		(layer "B.Cu")
		(net 44)
	)
	(arc
		(start 120.187962 149.2815)
		(mid 120.424843 149.379619)
		(end 120.522962 149.6165)
		(width 0.15)
		(layer "B.Cu")
		(net 44)
	)
	(arc
		(start 122.187962 149.2815)
		(mid 122.424843 149.379619)
		(end 122.522962 149.6165)
		(width 0.15)
		(layer "B.Cu")
		(net 44)
	)
	(arc
		(start 122.522962 150.437078)
		(mid 122.717736 150.907304)
		(end 123.187962 151.102078)
		(width 0.15)
		(layer "B.Cu")
		(net 44)
	)
	(arc
		(start 119.852962 149.6165)
		(mid 119.951081 149.379619)
		(end 120.187962 149.2815)
		(width 0.15)
		(layer "B.Cu")
		(net 44)
	)
	(arc
		(start 118.522962 150.437101)
		(mid 118.717736 150.907327)
		(end 119.187962 151.102101)
		(width 0.15)
		(layer "B.Cu")
		(net 44)
	)
	(arc
		(start 120.522962 150.437101)
		(mid 120.717736 150.907327)
		(end 121.187962 151.102101)
		(width 0.15)
		(layer "B.Cu")
		(net 44)
	)
	(arc
		(start 118.187962 149.2815)
		(mid 118.424843 149.379619)
		(end 118.522962 149.6165)
		(width 0.15)
		(layer "B.Cu")
		(net 44)
	)
	(segment
		(start 110.695962 133.6015)
		(end 113.667962 133.6015)
		(width 0.254)
		(layer "B.Cu")
		(net 45)
	)
	(segment
		(start 110.263962 134.0335)
		(end 110.263962 134.8875)
		(width 0.254)
		(layer "B.Cu")
		(net 45)
	)
	(segment
		(start 110.263962 134.0335)
		(end 110.695962 133.6015)
		(width 0.254)
		(layer "B.Cu")
		(net 45)
	)
	(segment
		(start 113.451962 131.9965)
		(end 113.451962 133.1705)
		(width 0.254)
		(layer "B.Cu")
		(net 45)
	)
	(segment
		(start 114.127961 146.951499)
		(end 114.127961 148.473155)
		(width 0.15)
		(layer "F.Cu")
		(net 46)
	)
	(segment
		(start 112.998962 148.917)
		(end 112.473961 148.917)
		(width 0.15)
		(layer "F.Cu")
		(net 46)
	)
	(segment
		(start 113.033462 148.9515)
		(end 112.998962 148.917)
		(width 0.15)
		(layer "F.Cu")
		(net 46)
	)
	(segment
		(start 114.127961 148.473155)
		(end 113.649616 148.9515)
		(width 0.15)
		(layer "F.Cu")
		(net 46)
	)
	(segment
		(start 113.967962 146.7915)
		(end 114.127961 146.951499)
		(width 0.15)
		(layer "F.Cu")
		(net 46)
	)
	(segment
		(start 113.649616 148.9515)
		(end 113.033462 148.9515)
		(width 0.15)
		(layer "F.Cu")
		(net 46)
	)
	(via
		(at 113.967962 146.7915)
		(size 0.45)
		(drill 0.1)
		(layers "F.Cu" "B.Cu")
		(net 46)
	)
	(segment
		(start 121.652962 146.7265)
		(end 121.652962 147.563104)
		(width 0.15)
		(layer "B.Cu")
		(net 46)
	)
	(segment
		(start 136.567961 134.4665)
		(end 136.482961 134.5515)
		(width 0.15)
		(layer "B.Cu")
		(net 46)
	)
	(segment
		(start 119.652962 146.7265)
		(end 119.652962 147.563104)
		(width 0.15)
		(layer "B.Cu")
		(net 46)
	)
	(segment
		(start 127.912962 142.498154)
		(end 124.349616 146.0615)
		(width 0.15)
		(layer "B.Cu")
		(net 46)
	)
	(segment
		(start 124.349616 146.0615)
		(end 124.317962 146.0615)
		(width 0.15)
		(layer "B.Cu")
		(net 46)
	)
	(segment
		(start 137.467962 134.4665)
		(end 136.567961 134.4665)
		(width 0.15)
		(layer "B.Cu")
		(net 46)
	)
	(segment
		(start 114.419616 146.0615)
		(end 118.317962 146.0615)
		(width 0.15)
		(layer "B.Cu")
		(net 46)
	)
	(segment
		(start 120.982962 147.563104)
		(end 120.982962 146.7265)
		(width 0.15)
		(layer "B.Cu")
		(net 46)
	)
	(segment
		(start 134.809616 134.5515)
		(end 127.912962 141.448154)
		(width 0.15)
		(layer "B.Cu")
		(net 46)
	)
	(segment
		(start 114.127962 146.353154)
		(end 114.127962 146.6315)
		(width 0.15)
		(layer "B.Cu")
		(net 46)
	)
	(segment
		(start 136.482961 134.5515)
		(end 134.809616 134.5515)
		(width 0.15)
		(layer "B.Cu")
		(net 46)
	)
	(segment
		(start 123.652962 146.7265)
		(end 123.652962 147.563081)
		(width 0.15)
		(layer "B.Cu")
		(net 46)
	)
	(segment
		(start 127.912962 141.448154)
		(end 127.912962 142.498154)
		(width 0.15)
		(layer "B.Cu")
		(net 46)
	)
	(segment
		(start 118.982962 147.563104)
		(end 118.982962 146.7265)
		(width 0.15)
		(layer "B.Cu")
		(net 46)
	)
	(segment
		(start 114.127962 146.6315)
		(end 113.967962 146.7915)
		(width 0.15)
		(layer "B.Cu")
		(net 46)
	)
	(segment
		(start 114.419616 146.0615)
		(end 114.127962 146.353154)
		(width 0.15)
		(layer "B.Cu")
		(net 46)
	)
	(segment
		(start 122.982962 147.563081)
		(end 122.982962 146.7265)
		(width 0.15)
		(layer "B.Cu")
		(net 46)
	)
	(arc
		(start 121.317962 147.898104)
		(mid 121.081081 147.799985)
		(end 120.982962 147.563104)
		(width 0.15)
		(layer "B.Cu")
		(net 46)
	)
	(arc
		(start 119.317962 147.898104)
		(mid 119.081081 147.799985)
		(end 118.982962 147.563104)
		(width 0.15)
		(layer "B.Cu")
		(net 46)
	)
	(arc
		(start 118.982962 146.7265)
		(mid 118.788188 146.256274)
		(end 118.317962 146.0615)
		(width 0.15)
		(layer "B.Cu")
		(net 46)
	)
	(arc
		(start 122.317962 146.0615)
		(mid 121.847736 146.256274)
		(end 121.652962 146.7265)
		(width 0.15)
		(layer "B.Cu")
		(net 46)
	)
	(arc
		(start 121.652962 147.563104)
		(mid 121.554843 147.799985)
		(end 121.317962 147.898104)
		(width 0.15)
		(layer "B.Cu")
		(net 46)
	)
	(arc
		(start 123.652962 147.563081)
		(mid 123.554843 147.799962)
		(end 123.317962 147.898081)
		(width 0.15)
		(layer "B.Cu")
		(net 46)
	)
	(arc
		(start 120.982962 146.7265)
		(mid 120.788188 146.256274)
		(end 120.317962 146.0615)
		(width 0.15)
		(layer "B.Cu")
		(net 46)
	)
	(arc
		(start 123.317962 147.898081)
		(mid 123.081081 147.799962)
		(end 122.982962 147.563081)
		(width 0.15)
		(layer "B.Cu")
		(net 46)
	)
	(arc
		(start 122.982962 146.7265)
		(mid 122.788188 146.256274)
		(end 122.317962 146.0615)
		(width 0.15)
		(layer "B.Cu")
		(net 46)
	)
	(arc
		(start 120.317962 146.0615)
		(mid 119.847736 146.256274)
		(end 119.652962 146.7265)
		(width 0.15)
		(layer "B.Cu")
		(net 46)
	)
	(arc
		(start 124.317962 146.0615)
		(mid 123.847736 146.256274)
		(end 123.652962 146.7265)
		(width 0.15)
		(layer "B.Cu")
		(net 46)
	)
	(arc
		(start 119.652962 147.563104)
		(mid 119.554843 147.799985)
		(end 119.317962 147.898104)
		(width 0.15)
		(layer "B.Cu")
		(net 46)
	)
	(segment
		(start 59.967962 170.9165)
		(end 59.967962 167.7945)
		(width 0.127)
		(layer "F.Cu")
		(net 47)
	)
	(segment
		(start 59.967962 167.7945)
		(end 59.937962 167.7645)
		(width 0.127)
		(layer "F.Cu")
		(net 47)
	)
	(via
		(at 57.917962 165.7565)
		(size 0.5)
		(drill 0.15)
		(layers "F.Cu" "B.Cu")
		(net 47)
	)
	(via
		(at 56.577962 165.7665)
		(size 0.5)
		(drill 0.15)
		(layers "F.Cu" "B.Cu")
		(net 47)
	)
	(via
		(at 55.16386 164.795857)
		(size 0.5)
		(drill 0.15)
		(layers "F.Cu" "B.Cu")
		(net 47)
	)
	(via
		(at 57.257962 165.7665)
		(size 0.5)
		(drill 0.15)
		(layers "F.Cu" "B.Cu")
		(net 47)
	)
	(via
		(at 55.917962 165.7765)
		(size 0.5)
		(drill 0.15)
		(layers "F.Cu" "B.Cu")
		(net 47)
	)
	(segment
		(start 56.917962 163.8735)
		(end 55.364962 163.8735)
		(width 0.35)
		(layer "B.Cu")
		(net 47)
	)
	(segment
		(start 55.937962 164.8535)
		(end 55.937962 166.0965)
		(width 0.35)
		(layer "B.Cu")
		(net 47)
	)
	(segment
		(start 56.917962 163.8735)
		(end 55.937962 164.8535)
		(width 0.35)
		(layer "B.Cu")
		(net 47)
	)
	(segment
		(start 57.907962 164.8635)
		(end 57.907962 166.0155)
		(width 0.35)
		(layer "B.Cu")
		(net 47)
	)
	(segment
		(start 57.247962 164.2035)
		(end 57.247962 166.0255)
		(width 0.35)
		(layer "B.Cu")
		(net 47)
	)
	(segment
		(start 56.597962 164.1935)
		(end 56.597962 167.3045)
		(width 0.35)
		(layer "B.Cu")
		(net 47)
	)
	(segment
		(start 56.917962 163.8735)
		(end 57.907962 164.8635)
		(width 0.35)
		(layer "B.Cu")
		(net 47)
	)
	(segment
		(start 111.716962 132.2875)
		(end 111.214962 132.2875)
		(width 0.254)
		(layer "B.Cu")
		(net 48)
	)
	(segment
		(start 112.007962 131.9965)
		(end 111.716962 132.2875)
		(width 0.254)
		(layer "B.Cu")
		(net 48)
	)
	(segment
		(start 112.483962 131.9965)
		(end 112.007962 131.9965)
		(width 0.254)
		(layer "B.Cu")
		(net 48)
	)
	(segment
		(start 69.321962 162.1365)
		(end 69.321962 163.3455)
		(width 0.254)
		(layer "B.Cu")
		(net 49)
	)
	(segment
		(start 114.457963 146.951499)
		(end 114.457963 148.609845)
		(width 0.15)
		(layer "F.Cu")
		(net 50)
	)
	(segment
		(start 114.617962 146.7915)
		(end 114.457963 146.951499)
		(width 0.15)
		(layer "F.Cu")
		(net 50)
	)
	(segment
		(start 113.786308 149.2815)
		(end 113.033462 149.2815)
		(width 0.15)
		(layer "F.Cu")
		(net 50)
	)
	(segment
		(start 113.033462 149.2815)
		(end 112.998962 149.316)
		(width 0.15)
		(layer "F.Cu")
		(net 50)
	)
	(segment
		(start 112.998962 149.316)
		(end 112.473961 149.316)
		(width 0.15)
		(layer "F.Cu")
		(net 50)
	)
	(segment
		(start 114.457963 148.609845)
		(end 113.786308 149.2815)
		(width 0.15)
		(layer "F.Cu")
		(net 50)
	)
	(via
		(at 114.617962 146.7915)
		(size 0.45)
		(drill 0.1)
		(layers "F.Cu" "B.Cu")
		(net 50)
	)
	(segment
		(start 137.467962 134.9665)
		(end 136.567961 134.9665)
		(width 0.15)
		(layer "B.Cu")
		(net 50)
	)
	(segment
		(start 121.982962 146.7265)
		(end 121.982962 147.563104)
		(width 0.15)
		(layer "B.Cu")
		(net 50)
	)
	(segment
		(start 114.556308 146.3915)
		(end 118.317962 146.3915)
		(width 0.15)
		(layer "B.Cu")
		(net 50)
	)
	(segment
		(start 134.946308 134.8815)
		(end 128.242962 141.584846)
		(width 0.15)
		(layer "B.Cu")
		(net 50)
	)
	(segment
		(start 114.457962 146.6315)
		(end 114.617962 146.7915)
		(width 0.15)
		(layer "B.Cu")
		(net 50)
	)
	(segment
		(start 124.486308 146.3915)
		(end 124.317962 146.3915)
		(width 0.15)
		(layer "B.Cu")
		(net 50)
	)
	(segment
		(start 119.982962 146.7265)
		(end 119.982962 147.563104)
		(width 0.15)
		(layer "B.Cu")
		(net 50)
	)
	(segment
		(start 123.982962 146.7265)
		(end 123.982962 147.563081)
		(width 0.15)
		(layer "B.Cu")
		(net 50)
	)
	(segment
		(start 120.652962 147.563104)
		(end 120.652962 146.7265)
		(width 0.15)
		(layer "B.Cu")
		(net 50)
	)
	(segment
		(start 114.457962 146.489846)
		(end 114.457962 146.6315)
		(width 0.15)
		(layer "B.Cu")
		(net 50)
	)
	(segment
		(start 118.652962 147.563104)
		(end 118.652962 146.7265)
		(width 0.15)
		(layer "B.Cu")
		(net 50)
	)
	(segment
		(start 128.242962 141.584846)
		(end 128.242962 142.634846)
		(width 0.15)
		(layer "B.Cu")
		(net 50)
	)
	(segment
		(start 136.482961 134.8815)
		(end 134.946308 134.8815)
		(width 0.15)
		(layer "B.Cu")
		(net 50)
	)
	(segment
		(start 128.242962 142.634846)
		(end 124.486308 146.3915)
		(width 0.15)
		(layer "B.Cu")
		(net 50)
	)
	(segment
		(start 122.652962 147.563081)
		(end 122.652962 146.7265)
		(width 0.15)
		(layer "B.Cu")
		(net 50)
	)
	(segment
		(start 114.556308 146.3915)
		(end 114.457962 146.489846)
		(width 0.15)
		(layer "B.Cu")
		(net 50)
	)
	(segment
		(start 136.567961 134.9665)
		(end 136.482961 134.8815)
		(width 0.15)
		(layer "B.Cu")
		(net 50)
	)
	(arc
		(start 123.982962 147.563081)
		(mid 123.788188 148.033307)
		(end 123.317962 148.228081)
		(width 0.15)
		(layer "B.Cu")
		(net 50)
	)
	(arc
		(start 124.317962 146.3915)
		(mid 124.081081 146.489619)
		(end 123.982962 146.7265)
		(width 0.15)
		(layer "B.Cu")
		(net 50)
	)
	(arc
		(start 123.317962 148.228081)
		(mid 122.847736 148.033307)
		(end 122.652962 147.563081)
		(width 0.15)
		(layer "B.Cu")
		(net 50)
	)
	(arc
		(start 122.317962 146.3915)
		(mid 122.081081 146.489619)
		(end 121.982962 146.7265)
		(width 0.15)
		(layer "B.Cu")
		(net 50)
	)
	(arc
		(start 119.982962 147.563104)
		(mid 119.788188 148.03333)
		(end 119.317962 148.228104)
		(width 0.15)
		(layer "B.Cu")
		(net 50)
	)
	(arc
		(start 120.652962 146.7265)
		(mid 120.554843 146.489619)
		(end 120.317962 146.3915)
		(width 0.15)
		(layer "B.Cu")
		(net 50)
	)
	(arc
		(start 121.982962 147.563104)
		(mid 121.788188 148.03333)
		(end 121.317962 148.228104)
		(width 0.15)
		(layer "B.Cu")
		(net 50)
	)
	(arc
		(start 119.317962 148.228104)
		(mid 118.847736 148.03333)
		(end 118.652962 147.563104)
		(width 0.15)
		(layer "B.Cu")
		(net 50)
	)
	(arc
		(start 122.652962 146.7265)
		(mid 122.554843 146.489619)
		(end 122.317962 146.3915)
		(width 0.15)
		(layer "B.Cu")
		(net 50)
	)
	(arc
		(start 121.317962 148.228104)
		(mid 120.847736 148.03333)
		(end 120.652962 147.563104)
		(width 0.15)
		(layer "B.Cu")
		(net 50)
	)
	(arc
		(start 120.317962 146.3915)
		(mid 120.081081 146.489619)
		(end 119.982962 146.7265)
		(width 0.15)
		(layer "B.Cu")
		(net 50)
	)
	(arc
		(start 118.652962 146.7265)
		(mid 118.554843 146.489619)
		(end 118.317962 146.3915)
		(width 0.15)
		(layer "B.Cu")
		(net 50)
	)
	(segment
		(start 67.109962 162.4475)
		(end 67.601962 162.4475)
		(width 0.254)
		(layer "B.Cu")
		(net 51)
	)
	(segment
		(start 67.601962 162.4475)
		(end 67.912962 162.1365)
		(width 0.254)
		(layer "B.Cu")
		(net 51)
	)
	(segment
		(start 68.353962 162.1365)
		(end 67.912962 162.1365)
		(width 0.254)
		(layer "B.Cu")
		(net 51)
	)
	(segment
		(start 113.033462 150.1525)
		(end 113.557963 150.152499)
		(width 0.15)
		(layer "F.Cu")
		(net 52)
	)
	(segment
		(start 112.473961 150.118)
		(end 112.998962 150.118)
		(width 0.15)
		(layer "F.Cu")
		(net 52)
	)
	(segment
		(start 112.998962 150.118)
		(end 113.033462 150.1525)
		(width 0.15)
		(layer "F.Cu")
		(net 52)
	)
	(segment
		(start 113.557963 150.152499)
		(end 113.717962 149.9925)
		(width 0.15)
		(layer "F.Cu")
		(net 52)
	)
	(via
		(at 113.717962 149.9925)
		(size 0.45)
		(drill 0.1)
		(layers "F.Cu" "B.Cu")
		(net 52)
	)
	(segment
		(start 130.882962 143.408154)
		(end 135.542962 138.748154)
		(width 0.15)
		(layer "B.Cu")
		(net 52)
	)
	(segment
		(start 115.806308 154.9515)
		(end 121.995154 154.9515)
		(width 0.15)
		(layer "B.Cu")
		(net 52)
	)
	(segment
		(start 135.542962 138.748154)
		(end 135.542962 137.648154)
		(width 0.15)
		(layer "B.Cu")
		(net 52)
	)
	(segment
		(start 123.36538 153.050885)
		(end 123.464407 153.149912)
		(width 0.15)
		(layer "B.Cu")
		(net 52)
	)
	(segment
		(start 124.461471 153.814637)
		(end 124.602892 153.673215)
		(width 0.15)
		(layer "B.Cu")
		(net 52)
	)
	(segment
		(start 113.717962 149.9925)
		(end 113.877962 150.1525)
		(width 0.15)
		(layer "B.Cu")
		(net 52)
	)
	(segment
		(start 114.692962 150.538154)
		(end 114.692962 153.838154)
		(width 0.15)
		(layer "B.Cu")
		(net 52)
	)
	(segment
		(start 114.692962 153.838154)
		(end 115.806308 154.9515)
		(width 0.15)
		(layer "B.Cu")
		(net 52)
	)
	(segment
		(start 126.595 149.371654)
		(end 130.882962 145.083692)
		(width 0.15)
		(layer "B.Cu")
		(net 52)
	)
	(segment
		(start 123.747246 153.432753)
		(end 124.12913 153.814637)
		(width 0.15)
		(layer "B.Cu")
		(net 52)
	)
	(segment
		(start 124.50385 152.442802)
		(end 124.645272 152.301382)
		(width 0.15)
		(layer "B.Cu")
		(net 52)
	)
	(segment
		(start 124.602892 153.340875)
		(end 124.50385 153.241833)
		(width 0.15)
		(layer "B.Cu")
		(net 52)
	)
	(segment
		(start 114.307308 150.1525)
		(end 114.692962 150.538154)
		(width 0.15)
		(layer "B.Cu")
		(net 52)
	)
	(segment
		(start 123.464407 153.149912)
		(end 123.74725 153.432755)
		(width 0.15)
		(layer "B.Cu")
		(net 52)
	)
	(segment
		(start 135.542962 137.648154)
		(end 136.140616 137.0505)
		(width 0.15)
		(layer "B.Cu")
		(net 52)
	)
	(segment
		(start 125.522716 151.423938)
		(end 126.595 150.351654)
		(width 0.15)
		(layer "B.Cu")
		(net 52)
	)
	(segment
		(start 130.882962 145.083692)
		(end 130.882962 143.408154)
		(width 0.15)
		(layer "B.Cu")
		(net 52)
	)
	(segment
		(start 113.877962 150.1525)
		(end 114.307308 150.1525)
		(width 0.15)
		(layer "B.Cu")
		(net 52)
	)
	(segment
		(start 136.482961 137.0505)
		(end 136.567961 136.9655)
		(width 0.15)
		(layer "B.Cu")
		(net 52)
	)
	(segment
		(start 123.74725 153.432755)
		(end 123.747246 153.432753)
		(width 0.15)
		(layer "B.Cu")
		(net 52)
	)
	(segment
		(start 136.567961 136.9655)
		(end 137.467962 136.9655)
		(width 0.15)
		(layer "B.Cu")
		(net 52)
	)
	(segment
		(start 126.595 150.351654)
		(end 126.595 149.371654)
		(width 0.15)
		(layer "B.Cu")
		(net 52)
	)
	(segment
		(start 121.995154 154.9515)
		(end 122.52395 154.422704)
		(width 0.15)
		(layer "B.Cu")
		(net 52)
	)
	(segment
		(start 136.140616 137.0505)
		(end 136.482961 137.0505)
		(width 0.15)
		(layer "B.Cu")
		(net 52)
	)
	(segment
		(start 122.523951 154.090365)
		(end 122.424925 153.991339)
		(width 0.15)
		(layer "B.Cu")
		(net 52)
	)
	(segment
		(start 122.424926 153.192307)
		(end 122.566348 153.050886)
		(width 0.15)
		(layer "B.Cu")
		(net 52)
	)
	(segment
		(start 122.52395 154.422704)
		(end 122.523951 154.422705)
		(width 0.15)
		(layer "B.Cu")
		(net 52)
	)
	(segment
		(start 124.645272 152.301382)
		(end 125.522716 151.423938)
		(width 0.15)
		(layer "B.Cu")
		(net 52)
	)
	(arc
		(start 122.566348 153.050886)
		(mid 122.965865 152.8854)
		(end 123.36538 153.050885)
		(width 0.15)
		(layer "B.Cu")
		(net 52)
	)
	(arc
		(start 124.602892 153.673215)
		(mid 124.671722 153.507045)
		(end 124.602892 153.340875)
		(width 0.15)
		(layer "B.Cu")
		(net 52)
	)
	(arc
		(start 122.523951 154.422705)
		(mid 122.592781 154.256535)
		(end 122.523951 154.090365)
		(width 0.15)
		(layer "B.Cu")
		(net 52)
	)
	(arc
		(start 122.424925 153.991339)
		(mid 122.259441 153.591823)
		(end 122.424926 153.192307)
		(width 0.15)
		(layer "B.Cu")
		(net 52)
	)
	(arc
		(start 124.12913 153.814637)
		(mid 124.295301 153.883467)
		(end 124.461471 153.814637)
		(width 0.15)
		(layer "B.Cu")
		(net 52)
	)
	(arc
		(start 124.50385 153.241833)
		(mid 124.338365 152.842318)
		(end 124.50385 152.442802)
		(width 0.15)
		(layer "B.Cu")
		(net 52)
	)
	(segment
		(start 116.079962 150.118)
		(end 116.114462 150.1525)
		(width 0.15)
		(layer "F.Cu")
		(net 53)
	)
	(segment
		(start 116.682963 150.151499)
		(end 116.842962 149.9915)
		(width 0.15)
		(layer "F.Cu")
		(net 53)
	)
	(segment
		(start 116.114462 150.1525)
		(end 116.367962 150.1525)
		(width 0.15)
		(layer "F.Cu")
		(net 53)
	)
	(segment
		(start 116.368963 150.151499)
		(end 116.682963 150.151499)
		(width 0.15)
		(layer "F.Cu")
		(net 53)
	)
	(segment
		(start 116.367962 150.1525)
		(end 116.368963 150.151499)
		(width 0.15)
		(layer "F.Cu")
		(net 53)
	)
	(segment
		(start 115.554961 150.118)
		(end 116.079962 150.118)
		(width 0.15)
		(layer "F.Cu")
		(net 53)
	)
	(via
		(at 135.510462 126.3565)
		(size 0.45)
		(drill 0.1)
		(layers "F.Cu" "B.Cu")
		(net 53)
	)
	(via
		(at 116.842962 149.9915)
		(size 0.45)
		(drill 0.1)
		(layers "F.Cu" "B.Cu")
		(net 53)
	)
	(segment
		(start 135.510462 126.3565)
		(end 135.716462 126.5625)
		(width 0.138)
		(layer "B.Cu")
		(net 53)
	)
	(segment
		(start 136.352962 126.5575)
		(end 136.476961 126.5575)
		(width 0.138)
		(layer "B.Cu")
		(net 53)
	)
	(segment
		(start 136.567961 126.4665)
		(end 137.467962 126.4665)
		(width 0.138)
		(layer "B.Cu")
		(net 53)
	)
	(segment
		(start 136.476961 126.5575)
		(end 136.567961 126.4665)
		(width 0.138)
		(layer "B.Cu")
		(net 53)
	)
	(segment
		(start 136.347962 126.5625)
		(end 136.352962 126.5575)
		(width 0.138)
		(layer "B.Cu")
		(net 53)
	)
	(segment
		(start 135.716462 126.5625)
		(end 136.347962 126.5625)
		(width 0.138)
		(layer "B.Cu")
		(net 53)
	)
	(segment
		(start 125.446896 138.166251)
		(end 125.446897 138.166251)
		(width 0.138)
		(layer "In2.Cu")
		(net 53)
	)
	(segment
		(start 125.160589 139.747697)
		(end 124.993358 139.580466)
		(width 0.138)
		(layer "In2.Cu")
		(net 53)
	)
	(segment
		(start 127.988915 136.919269)
		(end 127.821684 136.752038)
		(width 0.138)
		(layer "In2.Cu")
		(net 53)
	)
	(segment
		(start 123.95179 140.622034)
		(end 123.951789 140.622034)
		(width 0.138)
		(layer "In2.Cu")
		(net 53)
	)
	(segment
		(start 118.285538 150.08)
		(end 116.931462 150.08)
		(width 0.138)
		(layer "In2.Cu")
		(net 53)
	)
	(segment
		(start 134.19 126.485)
		(end 132.481462 128.193538)
		(width 0.138)
		(layer "In2.Cu")
		(net 53)
	)
	(segment
		(start 120.406462 147.959076)
		(end 118.285538 150.08)
		(width 0.138)
		(layer "In2.Cu")
		(net 53)
	)
	(segment
		(start 124.032721 139.580466)
		(end 123.951789 139.661397)
		(width 0.138)
		(layer "In2.Cu")
		(net 53)
	)
	(segment
		(start 132.481462 128.193538)
		(end 132.481462 132.718538)
		(width 0.138)
		(layer "In2.Cu")
		(net 53)
	)
	(segment
		(start 126.860945 136.752038)
		(end 126.780115 136.832867)
		(width 0.138)
		(layer "In2.Cu")
		(net 53)
	)
	(segment
		(start 126.866517 138.333482)
		(end 126.866517 138.333483)
		(width 0.138)
		(layer "In2.Cu")
		(net 53)
	)
	(segment
		(start 124.119019 141.080978)
		(end 120.406462 144.793538)
		(width 0.138)
		(layer "In2.Cu")
		(net 53)
	)
	(segment
		(start 135.381962 126.485)
		(end 134.19 126.485)
		(width 0.138)
		(layer "In2.Cu")
		(net 53)
	)
	(segment
		(start 116.931462 150.08)
		(end 116.842962 149.9915)
		(width 0.138)
		(layer "In2.Cu")
		(net 53)
	)
	(segment
		(start 126.780116 137.793606)
		(end 126.780115 137.793606)
		(width 0.138)
		(layer "In2.Cu")
		(net 53)
	)
	(segment
		(start 125.452303 139.747696)
		(end 125.452303 139.747697)
		(width 0.138)
		(layer "In2.Cu")
		(net 53)
	)
	(segment
		(start 125.446897 138.166251)
		(end 125.365984 138.247163)
		(width 0.138)
		(layer "In2.Cu")
		(net 53)
	)
	(segment
		(start 126.860945 136.752037)
		(end 126.860945 136.752038)
		(width 0.138)
		(layer "In2.Cu")
		(net 53)
	)
	(segment
		(start 126.574785 138.333483)
		(end 126.574784 138.333483)
		(width 0.138)
		(layer "In2.Cu")
		(net 53)
	)
	(segment
		(start 126.780115 137.793606)
		(end 126.947345 137.960836)
		(width 0.138)
		(layer "In2.Cu")
		(net 53)
	)
	(segment
		(start 125.533215 139.666782)
		(end 125.452303 139.747696)
		(width 0.138)
		(layer "In2.Cu")
		(net 53)
	)
	(segment
		(start 125.365984 139.207819)
		(end 125.533215 139.37505)
		(width 0.138)
		(layer "In2.Cu")
		(net 53)
	)
	(segment
		(start 126.574784 138.333483)
		(end 126.407552 138.166251)
		(width 0.138)
		(layer "In2.Cu")
		(net 53)
	)
	(segment
		(start 125.365983 139.207818)
		(end 125.365984 139.207819)
		(width 0.138)
		(layer "In2.Cu")
		(net 53)
	)
	(segment
		(start 126.947345 138.252652)
		(end 126.866517 138.333482)
		(width 0.138)
		(layer "In2.Cu")
		(net 53)
	)
	(segment
		(start 124.032721 139.580465)
		(end 124.032721 139.580466)
		(width 0.138)
		(layer "In2.Cu")
		(net 53)
	)
	(segment
		(start 123.951789 140.622034)
		(end 124.119019 140.789264)
		(width 0.138)
		(layer "In2.Cu")
		(net 53)
	)
	(segment
		(start 135.510462 126.3565)
		(end 135.381962 126.485)
		(width 0.138)
		(layer "In2.Cu")
		(net 53)
	)
	(segment
		(start 132.481462 132.718538)
		(end 128.280731 136.919269)
		(width 0.138)
		(layer "In2.Cu")
		(net 53)
	)
	(segment
		(start 120.406462 144.793538)
		(end 120.406462 147.959076)
		(width 0.138)
		(layer "In2.Cu")
		(net 53)
	)
	(arc
		(start 126.866517 138.333483)
		(mid 126.720651 138.393903)
		(end 126.574785 138.333483)
		(width 0.138)
		(layer "In2.Cu")
		(net 53)
	)
	(arc
		(start 125.533215 139.37505)
		(mid 125.593635 139.520916)
		(end 125.533215 139.666782)
		(width 0.138)
		(layer "In2.Cu")
		(net 53)
	)
	(arc
		(start 126.407552 138.166251)
		(mid 125.927224 137.967293)
		(end 125.446896 138.166251)
		(width 0.138)
		(layer "In2.Cu")
		(net 53)
	)
	(arc
		(start 128.280731 136.919269)
		(mid 128.134823 136.979706)
		(end 127.988915 136.919269)
		(width 0.138)
		(layer "In2.Cu")
		(net 53)
	)
	(arc
		(start 126.780115 136.832867)
		(mid 126.58114 137.313237)
		(end 126.780116 137.793606)
		(width 0.138)
		(layer "In2.Cu")
		(net 53)
	)
	(arc
		(start 127.821684 136.752038)
		(mid 127.341315 136.553062)
		(end 126.860945 136.752037)
		(width 0.138)
		(layer "In2.Cu")
		(net 53)
	)
	(arc
		(start 125.365984 138.247163)
		(mid 125.167025 138.72749)
		(end 125.365983 139.207818)
		(width 0.138)
		(layer "In2.Cu")
		(net 53)
	)
	(arc
		(start 125.452303 139.747697)
		(mid 125.306446 139.808113)
		(end 125.160589 139.747697)
		(width 0.138)
		(layer "In2.Cu")
		(net 53)
	)
	(arc
		(start 126.947345 137.960836)
		(mid 127.007782 138.106744)
		(end 126.947345 138.252652)
		(width 0.138)
		(layer "In2.Cu")
		(net 53)
	)
	(arc
		(start 124.993358 139.580466)
		(mid 124.51304 139.381511)
		(end 124.032721 139.580465)
		(width 0.138)
		(layer "In2.Cu")
		(net 53)
	)
	(arc
		(start 124.119019 140.789264)
		(mid 124.179435 140.935121)
		(end 124.119019 141.080978)
		(width 0.138)
		(layer "In2.Cu")
		(net 53)
	)
	(arc
		(start 123.951789 139.661397)
		(mid 123.752835 140.141716)
		(end 123.95179 140.622034)
		(width 0.138)
		(layer "In2.Cu")
		(net 53)
	)
	(segment
		(start 112.998962 150.517)
		(end 113.033462 150.4825)
		(width 0.15)
		(layer "F.Cu")
		(net 54)
	)
	(segment
		(start 113.557963 150.482501)
		(end 113.717962 150.6425)
		(width 0.15)
		(layer "F.Cu")
		(net 54)
	)
	(segment
		(start 112.473961 150.517)
		(end 112.998962 150.517)
		(width 0.15)
		(layer "F.Cu")
		(net 54)
	)
	(segment
		(start 113.033462 150.4825)
		(end 113.557963 150.482501)
		(width 0.15)
		(layer "F.Cu")
		(net 54)
	)
	(via
		(at 113.717962 150.6425)
		(size 0.45)
		(drill 0.1)
		(layers "F.Cu" "B.Cu")
		(net 54)
	)
	(segment
		(start 115.669616 155.2815)
		(end 122.131846 155.2815)
		(width 0.15)
		(layer "B.Cu")
		(net 54)
	)
	(segment
		(start 131.212962 143.544846)
		(end 135.872962 138.884846)
		(width 0.15)
		(layer "B.Cu")
		(net 54)
	)
	(segment
		(start 113.717962 150.6425)
		(end 113.877962 150.4825)
		(width 0.15)
		(layer "B.Cu")
		(net 54)
	)
	(segment
		(start 114.362962 153.974846)
		(end 115.669616 155.2815)
		(width 0.15)
		(layer "B.Cu")
		(net 54)
	)
	(segment
		(start 114.362962 150.674846)
		(end 114.362962 153.974846)
		(width 0.15)
		(layer "B.Cu")
		(net 54)
	)
	(segment
		(start 126.925 149.508346)
		(end 131.212962 145.220384)
		(width 0.15)
		(layer "B.Cu")
		(net 54)
	)
	(segment
		(start 113.877962 150.4825)
		(end 114.170616 150.4825)
		(width 0.15)
		(layer "B.Cu")
		(net 54)
	)
	(segment
		(start 122.131846 155.2815)
		(end 122.757296 154.65605)
		(width 0.15)
		(layer "B.Cu")
		(net 54)
	)
	(segment
		(start 123.23106 153.383258)
		(end 123.513903 153.666101)
		(width 0.15)
		(layer "B.Cu")
		(net 54)
	)
	(segment
		(start 122.757297 153.857018)
		(end 122.658271 153.757992)
		(width 0.15)
		(layer "B.Cu")
		(net 54)
	)
	(segment
		(start 126.925 150.488346)
		(end 126.925 149.508346)
		(width 0.15)
		(layer "B.Cu")
		(net 54)
	)
	(segment
		(start 131.212962 145.220384)
		(end 131.212962 143.544846)
		(width 0.15)
		(layer "B.Cu")
		(net 54)
	)
	(segment
		(start 125.756062 151.657284)
		(end 126.925 150.488346)
		(width 0.15)
		(layer "B.Cu")
		(net 54)
	)
	(segment
		(start 123.513901 153.666098)
		(end 123.895785 154.047982)
		(width 0.15)
		(layer "B.Cu")
		(net 54)
	)
	(segment
		(start 136.277308 137.3805)
		(end 136.482961 137.3805)
		(width 0.15)
		(layer "B.Cu")
		(net 54)
	)
	(segment
		(start 122.658271 153.425652)
		(end 122.799693 153.284231)
		(width 0.15)
		(layer "B.Cu")
		(net 54)
	)
	(segment
		(start 136.482961 137.3805)
		(end 136.567961 137.4655)
		(width 0.15)
		(layer "B.Cu")
		(net 54)
	)
	(segment
		(start 123.132033 153.284231)
		(end 123.23106 153.383258)
		(width 0.15)
		(layer "B.Cu")
		(net 54)
	)
	(segment
		(start 114.170616 150.4825)
		(end 114.362962 150.674846)
		(width 0.15)
		(layer "B.Cu")
		(net 54)
	)
	(segment
		(start 135.872962 138.884846)
		(end 135.872962 137.784846)
		(width 0.15)
		(layer "B.Cu")
		(net 54)
	)
	(segment
		(start 136.567961 137.4655)
		(end 137.467962 137.4655)
		(width 0.15)
		(layer "B.Cu")
		(net 54)
	)
	(segment
		(start 124.737195 152.676147)
		(end 124.878617 152.534727)
		(width 0.15)
		(layer "B.Cu")
		(net 54)
	)
	(segment
		(start 135.872962 137.784846)
		(end 136.277308 137.3805)
		(width 0.15)
		(layer "B.Cu")
		(net 54)
	)
	(segment
		(start 123.513903 153.666101)
		(end 123.513901 153.666098)
		(width 0.15)
		(layer "B.Cu")
		(net 54)
	)
	(segment
		(start 124.878617 152.534727)
		(end 125.756062 151.657284)
		(width 0.15)
		(layer "B.Cu")
		(net 54)
	)
	(segment
		(start 124.836237 153.107529)
		(end 124.737195 153.008487)
		(width 0.15)
		(layer "B.Cu")
		(net 54)
	)
	(segment
		(start 124.694816 154.047982)
		(end 124.836237 153.90656)
		(width 0.15)
		(layer "B.Cu")
		(net 54)
	)
	(arc
		(start 124.737195 153.008487)
		(mid 124.668365 152.842317)
		(end 124.737195 152.676147)
		(width 0.15)
		(layer "B.Cu")
		(net 54)
	)
	(arc
		(start 122.799693 153.284231)
		(mid 122.965863 153.215401)
		(end 123.132033 153.284231)
		(width 0.15)
		(layer "B.Cu")
		(net 54)
	)
	(arc
		(start 122.757296 154.65605)
		(mid 122.922781 154.256535)
		(end 122.757297 153.857018)
		(width 0.15)
		(layer "B.Cu")
		(net 54)
	)
	(arc
		(start 122.658271 153.757992)
		(mid 122.589441 153.591822)
		(end 122.658271 153.425652)
		(width 0.15)
		(layer "B.Cu")
		(net 54)
	)
	(arc
		(start 123.895785 154.047982)
		(mid 124.295301 154.213466)
		(end 124.694816 154.047982)
		(width 0.15)
		(layer "B.Cu")
		(net 54)
	)
	(arc
		(start 124.836237 153.90656)
		(mid 125.001722 153.507044)
		(end 124.836237 153.107529)
		(width 0.15)
		(layer "B.Cu")
		(net 54)
	)
	(segment
		(start 116.495245 150.481501)
		(end 116.682963 150.481501)
		(width 0.15)
		(layer "F.Cu")
		(net 55)
	)
	(segment
		(start 116.494246 150.4825)
		(end 116.495245 150.481501)
		(width 0.15)
		(layer "F.Cu")
		(net 55)
	)
	(segment
		(start 116.682963 150.481501)
		(end 116.842962 150.6415)
		(width 0.15)
		(layer "F.Cu")
		(net 55)
	)
	(segment
		(start 116.114462 150.4825)
		(end 116.494246 150.4825)
		(width 0.15)
		(layer "F.Cu")
		(net 55)
	)
	(segment
		(start 115.554961 150.517)
		(end 116.079962 150.517)
		(width 0.15)
		(layer "F.Cu")
		(net 55)
	)
	(segment
		(start 116.079962 150.517)
		(end 116.114462 150.4825)
		(width 0.15)
		(layer "F.Cu")
		(net 55)
	)
	(via
		(at 135.510462 127.0865)
		(size 0.45)
		(drill 0.1)
		(layers "F.Cu" "B.Cu")
		(net 55)
	)
	(via
		(at 116.842962 150.6415)
		(size 0.45)
		(drill 0.1)
		(layers "F.Cu" "B.Cu")
		(net 55)
	)
	(segment
		(start 135.716462 126.8805)
		(end 136.469654 126.8805)
		(width 0.138)
		(layer "B.Cu")
		(net 55)
	)
	(segment
		(start 136.476961 126.8755)
		(end 136.567961 126.9665)
		(width 0.138)
		(layer "B.Cu")
		(net 55)
	)
	(segment
		(start 135.510462 127.0865)
		(end 135.716462 126.8805)
		(width 0.138)
		(layer "B.Cu")
		(net 55)
	)
	(segment
		(start 136.474654 126.8755)
		(end 136.476961 126.8755)
		(width 0.138)
		(layer "B.Cu")
		(net 55)
	)
	(segment
		(start 136.469654 126.8805)
		(end 136.474654 126.8755)
		(width 0.138)
		(layer "B.Cu")
		(net 55)
	)
	(segment
		(start 136.567961 126.9665)
		(end 137.467962 126.9665)
		(width 0.138)
		(layer "B.Cu")
		(net 55)
	)
	(segment
		(start 125.700446 138.873357)
		(end 125.867677 139.040588)
		(width 0.138)
		(layer "In2.Cu")
		(net 55)
	)
	(segment
		(start 127.654453 137.25373)
		(end 127.487222 137.086499)
		(width 0.138)
		(layer "In2.Cu")
		(net 55)
	)
	(segment
		(start 124.367182 139.914927)
		(end 124.28625 139.995858)
		(width 0.138)
		(layer "In2.Cu")
		(net 55)
	)
	(segment
		(start 126.240323 138.667944)
		(end 126.073091 138.500712)
		(width 0.138)
		(layer "In2.Cu")
		(net 55)
	)
	(segment
		(start 135.381962 126.958)
		(end 134.385924 126.958)
		(width 0.138)
		(layer "In2.Cu")
		(net 55)
	)
	(segment
		(start 120.879462 144.989462)
		(end 120.879462 148.155)
		(width 0.138)
		(layer "In2.Cu")
		(net 55)
	)
	(segment
		(start 132.954462 132.914462)
		(end 128.615192 137.25373)
		(width 0.138)
		(layer "In2.Cu")
		(net 55)
	)
	(segment
		(start 124.28625 140.287572)
		(end 124.45348 140.454802)
		(width 0.138)
		(layer "In2.Cu")
		(net 55)
	)
	(segment
		(start 118.481462 150.553)
		(end 116.931462 150.553)
		(width 0.138)
		(layer "In2.Cu")
		(net 55)
	)
	(segment
		(start 127.114576 137.459144)
		(end 127.281806 137.626374)
		(width 0.138)
		(layer "In2.Cu")
		(net 55)
	)
	(segment
		(start 135.510462 127.0865)
		(end 135.381962 126.958)
		(width 0.138)
		(layer "In2.Cu")
		(net 55)
	)
	(segment
		(start 120.879462 148.155)
		(end 118.481462 150.553)
		(width 0.138)
		(layer "In2.Cu")
		(net 55)
	)
	(segment
		(start 132.954462 128.389462)
		(end 132.954462 132.914462)
		(width 0.138)
		(layer "In2.Cu")
		(net 55)
	)
	(segment
		(start 124.453481 141.415439)
		(end 124.45348 141.415439)
		(width 0.138)
		(layer "In2.Cu")
		(net 55)
	)
	(segment
		(start 125.867677 140.001244)
		(end 125.867677 140.001243)
		(width 0.138)
		(layer "In2.Cu")
		(net 55)
	)
	(segment
		(start 125.700445 138.873357)
		(end 125.700446 138.873357)
		(width 0.138)
		(layer "In2.Cu")
		(net 55)
	)
	(segment
		(start 124.826127 140.082158)
		(end 124.658896 139.914927)
		(width 0.138)
		(layer "In2.Cu")
		(net 55)
	)
	(segment
		(start 126.240324 138.667944)
		(end 126.240323 138.667944)
		(width 0.138)
		(layer "In2.Cu")
		(net 55)
	)
	(segment
		(start 116.931462 150.553)
		(end 116.842962 150.6415)
		(width 0.138)
		(layer "In2.Cu")
		(net 55)
	)
	(segment
		(start 127.281806 138.587113)
		(end 127.200978 138.667944)
		(width 0.138)
		(layer "In2.Cu")
		(net 55)
	)
	(segment
		(start 125.781359 138.500712)
		(end 125.700446 138.581624)
		(width 0.138)
		(layer "In2.Cu")
		(net 55)
	)
	(segment
		(start 125.867677 140.001243)
		(end 125.786764 140.082158)
		(width 0.138)
		(layer "In2.Cu")
		(net 55)
	)
	(segment
		(start 134.385924 126.958)
		(end 132.954462 128.389462)
		(width 0.138)
		(layer "In2.Cu")
		(net 55)
	)
	(segment
		(start 127.195406 137.086499)
		(end 127.114576 137.167328)
		(width 0.138)
		(layer "In2.Cu")
		(net 55)
	)
	(segment
		(start 124.167819 141.701105)
		(end 120.879462 144.989462)
		(width 0.138)
		(layer "In2.Cu")
		(net 55)
	)
	(segment
		(start 124.826128 140.082158)
		(end 124.826127 140.082158)
		(width 0.138)
		(layer "In2.Cu")
		(net 55)
	)
	(segment
		(start 124.45348 141.415439)
		(end 124.167819 141.701105)
		(width 0.138)
		(layer "In2.Cu")
		(net 55)
	)
	(segment
		(start 127.281807 138.587113)
		(end 127.281806 138.587113)
		(width 0.138)
		(layer "In2.Cu")
		(net 55)
	)
	(segment
		(start 127.654454 137.25373)
		(end 127.654453 137.25373)
		(width 0.138)
		(layer "In2.Cu")
		(net 55)
	)
	(arc
		(start 125.700446 138.581624)
		(mid 125.640026 138.72749)
		(end 125.700445 138.873357)
		(width 0.138)
		(layer "In2.Cu")
		(net 55)
	)
	(arc
		(start 127.200978 138.667944)
		(mid 126.720651 138.866902)
		(end 126.240324 138.667944)
		(width 0.138)
		(layer "In2.Cu")
		(net 55)
	)
	(arc
		(start 125.786764 140.082158)
		(mid 125.306446 140.281112)
		(end 124.826128 140.082158)
		(width 0.138)
		(layer "In2.Cu")
		(net 55)
	)
	(arc
		(start 124.28625 139.995858)
		(mid 124.225834 140.141715)
		(end 124.28625 140.287572)
		(width 0.138)
		(layer "In2.Cu")
		(net 55)
	)
	(arc
		(start 124.658896 139.914927)
		(mid 124.513039 139.854511)
		(end 124.367182 139.914927)
		(width 0.138)
		(layer "In2.Cu")
		(net 55)
	)
	(arc
		(start 127.487222 137.086499)
		(mid 127.341314 137.026062)
		(end 127.195406 137.086499)
		(width 0.138)
		(layer "In2.Cu")
		(net 55)
	)
	(arc
		(start 127.281806 137.626374)
		(mid 127.480782 138.106743)
		(end 127.281807 138.587113)
		(width 0.138)
		(layer "In2.Cu")
		(net 55)
	)
	(arc
		(start 126.073091 138.500712)
		(mid 125.927225 138.440292)
		(end 125.781359 138.500712)
		(width 0.138)
		(layer "In2.Cu")
		(net 55)
	)
	(arc
		(start 128.615192 137.25373)
		(mid 128.134823 137.452705)
		(end 127.654454 137.25373)
		(width 0.138)
		(layer "In2.Cu")
		(net 55)
	)
	(arc
		(start 125.867677 139.040588)
		(mid 126.066635 139.520916)
		(end 125.867677 140.001244)
		(width 0.138)
		(layer "In2.Cu")
		(net 55)
	)
	(arc
		(start 127.114576 137.167328)
		(mid 127.054139 137.313236)
		(end 127.114576 137.459144)
		(width 0.138)
		(layer "In2.Cu")
		(net 55)
	)
	(arc
		(start 124.45348 140.454802)
		(mid 124.652435 140.93512)
		(end 124.453481 141.415439)
		(width 0.138)
		(layer "In2.Cu")
		(net 55)
	)
	(segment
		(start 111.94896 151.318)
		(end 111.91446 151.3525)
		(width 0.15)
		(layer "F.Cu")
		(net 56)
	)
	(segment
		(start 112.473961 151.318)
		(end 111.94896 151.318)
		(width 0.15)
		(layer "F.Cu")
		(net 56)
	)
	(segment
		(start 111.91446 151.3525)
		(end 111.352961 151.352499)
		(width 0.15)
		(layer "F.Cu")
		(net 56)
	)
	(segment
		(start 111.352961 151.352499)
		(end 111.192962 151.1925)
		(width 0.15)
		(layer "F.Cu")
		(net 56)
	)
	(via
		(at 111.192962 151.1925)
		(size 0.45)
		(drill 0.1)
		(layers "F.Cu" "B.Cu")
		(net 56)
	)
	(segment
		(start 123.523556 144.4715)
		(end 123.523557 144.4715)
		(width 0.15)
		(layer "B.Cu")
		(net 56)
	)
	(segment
		(start 125.411531 141.819582)
		(end 125.588044 141.643072)
		(width 0.15)
		(layer "B.Cu")
		(net 56)
	)
	(segment
		(start 126.765861 141.759744)
		(end 126.765861 141.759745)
		(width 0.15)
		(layer "B.Cu")
		(net 56)
	)
	(segment
		(start 123.997318 143.233796)
		(end 123.997317 143.233796)
		(width 0.15)
		(layer "B.Cu")
		(net 56)
	)
	(segment
		(start 126.765861 141.759745)
		(end 126.942395 141.58321)
		(width 0.15)
		(layer "B.Cu")
		(net 56)
	)
	(segment
		(start 123.937481 144.588172)
		(end 123.937481 144.588173)
		(width 0.15)
		(layer "B.Cu")
		(net 56)
	)
	(segment
		(start 114.129616 144.4715)
		(end 122.759616 144.4715)
		(width 0.15)
		(layer "B.Cu")
		(net 56)
	)
	(segment
		(start 136.567961 133.4665)
		(end 137.467962 133.4665)
		(width 0.15)
		(layer "B.Cu")
		(net 56)
	)
	(segment
		(start 125.351695 143.173958)
		(end 125.351695 143.173959)
		(width 0.15)
		(layer "B.Cu")
		(net 56)
	)
	(segment
		(start 125.411532 141.819582)
		(end 125.411531 141.819582)
		(width 0.15)
		(layer "B.Cu")
		(net 56)
	)
	(segment
		(start 123.937481 144.588173)
		(end 124.113991 144.411662)
		(width 0.15)
		(layer "B.Cu")
		(net 56)
	)
	(segment
		(start 126.942395 141.285983)
		(end 126.825721 141.169309)
		(width 0.15)
		(layer "B.Cu")
		(net 56)
	)
	(segment
		(start 111.352961 151.352499)
		(end 111.978617 151.352499)
		(width 0.15)
		(layer "B.Cu")
		(net 56)
	)
	(segment
		(start 126.942396 141.285983)
		(end 126.942395 141.285983)
		(width 0.15)
		(layer "B.Cu")
		(net 56)
	)
	(segment
		(start 126.351961 141.643072)
		(end 126.468634 141.759745)
		(width 0.15)
		(layer "B.Cu")
		(net 56)
	)
	(segment
		(start 124.113991 144.114411)
		(end 123.997317 143.997737)
		(width 0.15)
		(layer "B.Cu")
		(net 56)
	)
	(segment
		(start 125.528205 142.700197)
		(end 125.411531 142.583523)
		(width 0.15)
		(layer "B.Cu")
		(net 56)
	)
	(segment
		(start 123.997317 143.233796)
		(end 124.17383 143.057286)
		(width 0.15)
		(layer "B.Cu")
		(net 56)
	)
	(segment
		(start 125.528206 142.700197)
		(end 125.528205 142.700197)
		(width 0.15)
		(layer "B.Cu")
		(net 56)
	)
	(segment
		(start 133.679616 133.5515)
		(end 136.482961 133.5515)
		(width 0.15)
		(layer "B.Cu")
		(net 56)
	)
	(segment
		(start 124.937771 143.057286)
		(end 125.054444 143.173959)
		(width 0.15)
		(layer "B.Cu")
		(net 56)
	)
	(segment
		(start 124.113992 144.114411)
		(end 124.113991 144.114411)
		(width 0.15)
		(layer "B.Cu")
		(net 56)
	)
	(segment
		(start 124.93777 143.057286)
		(end 124.937771 143.057286)
		(width 0.15)
		(layer "B.Cu")
		(net 56)
	)
	(segment
		(start 126.825721 140.405392)
		(end 127.068477 140.162639)
		(width 0.15)
		(layer "B.Cu")
		(net 56)
	)
	(segment
		(start 111.192962 151.1925)
		(end 111.352961 151.352499)
		(width 0.15)
		(layer "B.Cu")
		(net 56)
	)
	(segment
		(start 126.35196 141.643072)
		(end 126.351961 141.643072)
		(width 0.15)
		(layer "B.Cu")
		(net 56)
	)
	(segment
		(start 125.351695 143.173959)
		(end 125.528205 142.997448)
		(width 0.15)
		(layer "B.Cu")
		(net 56)
	)
	(segment
		(start 123.523557 144.4715)
		(end 123.64023 144.588173)
		(width 0.15)
		(layer "B.Cu")
		(net 56)
	)
	(segment
		(start 136.482961 133.5515)
		(end 136.567961 133.4665)
		(width 0.15)
		(layer "B.Cu")
		(net 56)
	)
	(segment
		(start 111.978617 151.352499)
		(end 112.372962 150.958154)
		(width 0.15)
		(layer "B.Cu")
		(net 56)
	)
	(segment
		(start 112.372962 150.958154)
		(end 112.372962 146.228154)
		(width 0.15)
		(layer "B.Cu")
		(net 56)
	)
	(segment
		(start 127.068477 140.162639)
		(end 133.679616 133.5515)
		(width 0.15)
		(layer "B.Cu")
		(net 56)
	)
	(segment
		(start 112.372962 146.228154)
		(end 114.129616 144.4715)
		(width 0.15)
		(layer "B.Cu")
		(net 56)
	)
	(segment
		(start 126.825722 140.405392)
		(end 126.825721 140.405392)
		(width 0.15)
		(layer "B.Cu")
		(net 56)
	)
	(arc
		(start 126.825721 141.169309)
		(mid 126.667509 140.78735)
		(end 126.825722 140.405392)
		(width 0.15)
		(layer "B.Cu")
		(net 56)
	)
	(arc
		(start 124.113991 144.411662)
		(mid 124.175554 144.263037)
		(end 124.113992 144.114411)
		(width 0.15)
		(layer "B.Cu")
		(net 56)
	)
	(arc
		(start 123.997317 143.997737)
		(mid 123.8391 143.615766)
		(end 123.997318 143.233796)
		(width 0.15)
		(layer "B.Cu")
		(net 56)
	)
	(arc
		(start 126.942395 141.58321)
		(mid 127.003953 141.434597)
		(end 126.942396 141.285983)
		(width 0.15)
		(layer "B.Cu")
		(net 56)
	)
	(arc
		(start 122.759616 144.4715)
		(mid 123.141586 144.313283)
		(end 123.523556 144.4715)
		(width 0.15)
		(layer "B.Cu")
		(net 56)
	)
	(arc
		(start 125.588044 141.643072)
		(mid 125.970002 141.48486)
		(end 126.35196 141.643072)
		(width 0.15)
		(layer "B.Cu")
		(net 56)
	)
	(arc
		(start 125.411531 142.583523)
		(mid 125.253314 142.201552)
		(end 125.411532 141.819582)
		(width 0.15)
		(layer "B.Cu")
		(net 56)
	)
	(arc
		(start 123.64023 144.588173)
		(mid 123.788856 144.649735)
		(end 123.937481 144.588172)
		(width 0.15)
		(layer "B.Cu")
		(net 56)
	)
	(arc
		(start 124.17383 143.057286)
		(mid 124.5558 142.899069)
		(end 124.93777 143.057286)
		(width 0.15)
		(layer "B.Cu")
		(net 56)
	)
	(arc
		(start 125.054444 143.173959)
		(mid 125.20307 143.235521)
		(end 125.351695 143.173958)
		(width 0.15)
		(layer "B.Cu")
		(net 56)
	)
	(arc
		(start 125.528205 142.997448)
		(mid 125.589768 142.848823)
		(end 125.528206 142.700197)
		(width 0.15)
		(layer "B.Cu")
		(net 56)
	)
	(arc
		(start 126.468634 141.759745)
		(mid 126.617248 141.821302)
		(end 126.765861 141.759744)
		(width 0.15)
		(layer "B.Cu")
		(net 56)
	)
	(segment
		(start 116.079962 151.318)
		(end 116.114462 151.3525)
		(width 0.15)
		(layer "F.Cu")
		(net 57)
	)
	(segment
		(start 121.979999 148.51)
		(end 122.129999 148.66)
		(width 0.15)
		(layer "F.Cu")
		(net 57)
	)
	(segment
		(start 117.357963 151.352499)
		(end 120.774155 151.352499)
		(width 0.15)
		(layer "F.Cu")
		(net 57)
	)
	(segment
		(start 115.554961 151.318)
		(end 116.079962 151.318)
		(width 0.15)
		(layer "F.Cu")
		(net 57)
	)
	(segment
		(start 122.129999 148.66)
		(end 122.129999 149.996655)
		(width 0.15)
		(layer "F.Cu")
		(net 57)
	)
	(segment
		(start 122.129999 149.996655)
		(end 120.774155 151.352499)
		(width 0.15)
		(layer "F.Cu")
		(net 57)
	)
	(segment
		(start 116.114462 151.3525)
		(end 117.357963 151.352499)
		(width 0.15)
		(layer "F.Cu")
		(net 57)
	)
	(via
		(at 138.867962 125.3515)
		(size 0.45)
		(drill 0.1)
		(layers "F.Cu" "B.Cu")
		(net 57)
	)
	(via
		(at 121.979999 148.51)
		(size 0.45)
		(drill 0.1)
		(layers "F.Cu" "B.Cu")
		(net 57)
	)
	(segment
		(start 138.367963 125.4665)
		(end 137.467962 125.4665)
		(width 0.15)
		(layer "B.Cu")
		(net 57)
	)
	(segment
		(start 138.452963 125.5515)
		(end 138.367963 125.4665)
		(width 0.15)
		(layer "B.Cu")
		(net 57)
	)
	(segment
		(start 138.867962 125.3515)
		(end 138.667962 125.5515)
		(width 0.15)
		(layer "B.Cu")
		(net 57)
	)
	(segment
		(start 138.667962 125.5515)
		(end 138.452963 125.5515)
		(width 0.15)
		(layer "B.Cu")
		(net 57)
	)
	(segment
		(start 122.625731 145.74252)
		(end 122.058499 146.309752)
		(width 0.138)
		(layer "In2.Cu")
		(net 57)
	)
	(segment
		(start 135.291462 131.184462)
		(end 135.291462 133.068)
		(width 0.138)
		(layer "In2.Cu")
		(net 57)
	)
	(segment
		(start 122.058499 148.4315)
		(end 121.979999 148.51)
		(width 0.138)
		(layer "In2.Cu")
		(net 57)
	)
	(segment
		(start 134.471462 130.364462)
		(end 135.291462 131.184462)
		(width 0.138)
		(layer "In2.Cu")
		(net 57)
	)
	(segment
		(start 138.3 125.48)
		(end 134.471462 129.308538)
		(width 0.138)
		(layer "In2.Cu")
		(net 57)
	)
	(segment
		(start 138.739462 125.48)
		(end 138.3 125.48)
		(width 0.138)
		(layer "In2.Cu")
		(net 57)
	)
	(segment
		(start 122.058499 146.309752)
		(end 122.058499 148.4315)
		(width 0.138)
		(layer "In2.Cu")
		(net 57)
	)
	(segment
		(start 135.291462 133.068)
		(end 122.625731 145.733731)
		(width 0.138)
		(layer "In2.Cu")
		(net 57)
	)
	(segment
		(start 138.867962 125.3515)
		(end 138.739462 125.48)
		(width 0.138)
		(layer "In2.Cu")
		(net 57)
	)
	(segment
		(start 122.625731 145.733731)
		(end 122.625731 145.74252)
		(width 0.138)
		(layer "In2.Cu")
		(net 57)
	)
	(segment
		(start 134.471462 129.308538)
		(end 134.471462 130.364462)
		(width 0.138)
		(layer "In2.Cu")
		(net 57)
	)
	(segment
		(start 111.91446 151.6825)
		(end 111.352961 151.682501)
		(width 0.15)
		(layer "F.Cu")
		(net 58)
	)
	(segment
		(start 111.94896 151.717)
		(end 111.91446 151.6825)
		(width 0.15)
		(layer "F.Cu")
		(net 58)
	)
	(segment
		(start 111.352961 151.682501)
		(end 111.192962 151.8425)
		(width 0.15)
		(layer "F.Cu")
		(net 58)
	)
	(segment
		(start 112.473961 151.717)
		(end 111.94896 151.717)
		(width 0.15)
		(layer "F.Cu")
		(net 58)
	)
	(via
		(at 111.192962 151.8425)
		(size 0.45)
		(drill 0.1)
		(layers "F.Cu" "B.Cu")
		(net 58)
	)
	(segment
		(start 124.347336 143.881065)
		(end 124.230662 143.764391)
		(width 0.15)
		(layer "B.Cu")
		(net 58)
	)
	(segment
		(start 125.761551 142.466852)
		(end 125.76155 142.466851)
		(width 0.15)
		(layer "B.Cu")
		(net 58)
	)
	(segment
		(start 126.999206 141.99309)
		(end 127.17574 141.816555)
		(width 0.15)
		(layer "B.Cu")
		(net 58)
	)
	(segment
		(start 111.192962 151.8425)
		(end 111.352961 151.682501)
		(width 0.15)
		(layer "B.Cu")
		(net 58)
	)
	(segment
		(start 125.76155 142.466851)
		(end 125.644876 142.350177)
		(width 0.15)
		(layer "B.Cu")
		(net 58)
	)
	(segment
		(start 112.115307 151.682501)
		(end 112.702962 151.094846)
		(width 0.15)
		(layer "B.Cu")
		(net 58)
	)
	(segment
		(start 133.816308 133.8815)
		(end 136.482961 133.8815)
		(width 0.15)
		(layer "B.Cu")
		(net 58)
	)
	(segment
		(start 122.896308 144.8015)
		(end 122.992961 144.704845)
		(width 0.15)
		(layer "B.Cu")
		(net 58)
	)
	(segment
		(start 127.059067 140.638736)
		(end 127.059066 140.638736)
		(width 0.15)
		(layer "B.Cu")
		(net 58)
	)
	(segment
		(start 127.17574 141.052637)
		(end 127.059066 140.935963)
		(width 0.15)
		(layer "B.Cu")
		(net 58)
	)
	(segment
		(start 127.175741 141.052638)
		(end 127.17574 141.052637)
		(width 0.15)
		(layer "B.Cu")
		(net 58)
	)
	(segment
		(start 111.352961 151.682501)
		(end 112.115307 151.682501)
		(width 0.15)
		(layer "B.Cu")
		(net 58)
	)
	(segment
		(start 124.704425 143.290631)
		(end 124.704426 143.290631)
		(width 0.15)
		(layer "B.Cu")
		(net 58)
	)
	(segment
		(start 126.118615 141.876417)
		(end 126.118616 141.876417)
		(width 0.15)
		(layer "B.Cu")
		(net 58)
	)
	(segment
		(start 125.58504 143.407304)
		(end 125.76155 143.230793)
		(width 0.15)
		(layer "B.Cu")
		(net 58)
	)
	(segment
		(start 126.118616 141.876417)
		(end 126.235289 141.99309)
		(width 0.15)
		(layer "B.Cu")
		(net 58)
	)
	(segment
		(start 124.170826 144.821518)
		(end 124.347336 144.645007)
		(width 0.15)
		(layer "B.Cu")
		(net 58)
	)
	(segment
		(start 125.58504 143.407303)
		(end 125.58504 143.407304)
		(width 0.15)
		(layer "B.Cu")
		(net 58)
	)
	(segment
		(start 136.567961 133.9665)
		(end 137.467962 133.9665)
		(width 0.15)
		(layer "B.Cu")
		(net 58)
	)
	(segment
		(start 125.644877 142.052926)
		(end 125.644876 142.052926)
		(width 0.15)
		(layer "B.Cu")
		(net 58)
	)
	(segment
		(start 126.999206 141.993089)
		(end 126.999206 141.99309)
		(width 0.15)
		(layer "B.Cu")
		(net 58)
	)
	(segment
		(start 124.704426 143.290631)
		(end 124.821099 143.407304)
		(width 0.15)
		(layer "B.Cu")
		(net 58)
	)
	(segment
		(start 112.702962 146.364846)
		(end 114.266308 144.8015)
		(width 0.15)
		(layer "B.Cu")
		(net 58)
	)
	(segment
		(start 112.702962 151.094846)
		(end 112.702962 146.364846)
		(width 0.15)
		(layer "B.Cu")
		(net 58)
	)
	(segment
		(start 136.482961 133.8815)
		(end 136.567961 133.9665)
		(width 0.15)
		(layer "B.Cu")
		(net 58)
	)
	(segment
		(start 125.644876 142.052926)
		(end 125.821389 141.876417)
		(width 0.15)
		(layer "B.Cu")
		(net 58)
	)
	(segment
		(start 124.230663 143.46714)
		(end 124.230662 143.46714)
		(width 0.15)
		(layer "B.Cu")
		(net 58)
	)
	(segment
		(start 124.170826 144.821517)
		(end 124.170826 144.821518)
		(width 0.15)
		(layer "B.Cu")
		(net 58)
	)
	(segment
		(start 124.347337 143.881066)
		(end 124.347336 143.881065)
		(width 0.15)
		(layer "B.Cu")
		(net 58)
	)
	(segment
		(start 127.301823 140.395985)
		(end 133.816308 133.8815)
		(width 0.15)
		(layer "B.Cu")
		(net 58)
	)
	(segment
		(start 124.230662 143.46714)
		(end 124.407175 143.290631)
		(width 0.15)
		(layer "B.Cu")
		(net 58)
	)
	(segment
		(start 127.059066 140.638736)
		(end 127.301823 140.395985)
		(width 0.15)
		(layer "B.Cu")
		(net 58)
	)
	(segment
		(start 123.290212 144.704845)
		(end 123.406885 144.821518)
		(width 0.15)
		(layer "B.Cu")
		(net 58)
	)
	(segment
		(start 123.290211 144.704845)
		(end 123.290212 144.704845)
		(width 0.15)
		(layer "B.Cu")
		(net 58)
	)
	(segment
		(start 114.266308 144.8015)
		(end 122.896308 144.8015)
		(width 0.15)
		(layer "B.Cu")
		(net 58)
	)
	(arc
		(start 124.347336 144.645007)
		(mid 124.505554 144.263037)
		(end 124.347337 143.881066)
		(width 0.15)
		(layer "B.Cu")
		(net 58)
	)
	(arc
		(start 124.821099 143.407304)
		(mid 125.20307 143.565521)
		(end 125.58504 143.407303)
		(width 0.15)
		(layer "B.Cu")
		(net 58)
	)
	(arc
		(start 124.407175 143.290631)
		(mid 124.5558 143.229069)
		(end 124.704425 143.290631)
		(width 0.15)
		(layer "B.Cu")
		(net 58)
	)
	(arc
		(start 122.992961 144.704845)
		(mid 123.141586 144.643283)
		(end 123.290211 144.704845)
		(width 0.15)
		(layer "B.Cu")
		(net 58)
	)
	(arc
		(start 125.821389 141.876417)
		(mid 125.970002 141.814859)
		(end 126.118615 141.876417)
		(width 0.15)
		(layer "B.Cu")
		(net 58)
	)
	(arc
		(start 127.059066 140.935963)
		(mid 126.997509 140.787349)
		(end 127.059067 140.638736)
		(width 0.15)
		(layer "B.Cu")
		(net 58)
	)
	(arc
		(start 126.235289 141.99309)
		(mid 126.617248 142.151302)
		(end 126.999206 141.993089)
		(width 0.15)
		(layer "B.Cu")
		(net 58)
	)
	(arc
		(start 127.17574 141.816555)
		(mid 127.333953 141.434597)
		(end 127.175741 141.052638)
		(width 0.15)
		(layer "B.Cu")
		(net 58)
	)
	(arc
		(start 125.76155 143.230793)
		(mid 125.919768 142.848823)
		(end 125.761551 142.466852)
		(width 0.15)
		(layer "B.Cu")
		(net 58)
	)
	(arc
		(start 125.644876 142.350177)
		(mid 125.583314 142.201551)
		(end 125.644877 142.052926)
		(width 0.15)
		(layer "B.Cu")
		(net 58)
	)
	(arc
		(start 124.230662 143.764391)
		(mid 124.1691 143.615765)
		(end 124.230663 143.46714)
		(width 0.15)
		(layer "B.Cu")
		(net 58)
	)
	(arc
		(start 123.406885 144.821518)
		(mid 123.788856 144.979735)
		(end 124.170826 144.821517)
		(width 0.15)
		(layer "B.Cu")
		(net 58)
	)
	(segment
		(start 54.717962 155.8165)
		(end 56.151962 155.8165)
		(width 0.254)
		(layer "B.Cu")
		(net 59)
	)
	(segment
		(start 57.287962 155.1715)
		(end 61.242962 155.1715)
		(width 0.254)
		(layer "B.Cu")
		(net 59)
	)
	(segment
		(start 56.658962 155.8005)
		(end 57.287962 155.1715)
		(width 0.254)
		(layer "B.Cu")
		(net 59)
	)
	(segment
		(start 56.167962 155.8005)
		(end 56.658962 155.8005)
		(width 0.254)
		(layer "B.Cu")
		(net 59)
	)
	(segment
		(start 55.683962 155.3165)
		(end 55.116962 155.3165)
		(width 0.2)
		(layer "B.Cu")
		(net 60)
	)
	(segment
		(start 56.167962 154.8325)
		(end 55.683962 155.3165)
		(width 0.2)
		(layer "B.Cu")
		(net 60)
	)
	(segment
		(start 70.483512 126.00705)
		(end 67.167962 122.6915)
		(width 0.5)
		(layer "B.Cu")
		(net 61)
	)
	(segment
		(start 67.167962 122.6915)
		(end 67.167962 114.7165)
		(width 0.5)
		(layer "B.Cu")
		(net 61)
	)
	(segment
		(start 70.483512 126.553)
		(end 70.483512 126.00705)
		(width 0.5)
		(layer "B.Cu")
		(net 61)
	)
	(segment
		(start 67.167962 114.7165)
		(end 66.347962 113.8965)
		(width 0.5)
		(layer "B.Cu")
		(net 61)
	)
	(segment
		(start 66.347962 113.8965)
		(end 65.067962 113.8965)
		(width 0.5)
		(layer "B.Cu")
		(net 61)
	)
	(segment
		(start 66.037962 116.4365)
		(end 65.067962 116.4365)
		(width 0.5)
		(layer "B.Cu")
		(net 62)
	)
	(segment
		(start 66.342962 123.69045)
		(end 66.342962 116.7415)
		(width 0.5)
		(layer "B.Cu")
		(net 62)
	)
	(segment
		(start 67.944512 125.292)
		(end 66.342962 123.69045)
		(width 0.5)
		(layer "B.Cu")
		(net 62)
	)
	(segment
		(start 66.342962 116.7415)
		(end 66.037962 116.4365)
		(width 0.5)
		(layer "B.Cu")
		(net 62)
	)
	(segment
		(start 65.187962 123.5165)
		(end 65.187962 124.8465)
		(width 0.5)
		(layer "B.Cu")
		(net 63)
	)
	(segment
		(start 63.473462 126.561)
		(end 59.054512 126.561)
		(width 0.5)
		(layer "B.Cu")
		(net 63)
	)
	(segment
		(start 65.187962 124.8465)
		(end 63.473462 126.561)
		(width 0.5)
		(layer "B.Cu")
		(net 63)
	)
	(segment
		(start 62.647962 124.3865)
		(end 61.742462 125.292)
		(width 0.5)
		(layer "B.Cu")
		(net 64)
	)
	(segment
		(start 62.647962 123.5165)
		(end 62.647962 124.3865)
		(width 0.5)
		(layer "B.Cu")
		(net 64)
	)
	(segment
		(start 116.477962 137.7815)
		(end 116.477962 136.4765)
		(width 0.2)
		(layer "F.Cu")
		(net 65)
	)
	(segment
		(start 116.402962 131.7915)
		(end 116.667962 131.7915)
		(width 0.2)
		(layer "F.Cu")
		(net 65)
	)
	(segment
		(start 117.652962 137.7915)
		(end 116.487962 137.7915)
		(width 0.2)
		(layer "F.Cu")
		(net 65)
	)
	(segment
		(start 116.467962 135.4265)
		(end 115.642962 134.6015)
		(width 0.2)
		(layer "F.Cu")
		(net 65)
	)
	(segment
		(start 116.477962 136.4765)
		(end 116.467962 136.4665)
		(width 0.2)
		(layer "F.Cu")
		(net 65)
	)
	(segment
		(start 115.642962 132.5515)
		(end 116.402962 131.7915)
		(width 0.2)
		(layer "F.Cu")
		(net 65)
	)
	(segment
		(start 115.642962 134.6015)
		(end 115.642962 132.5515)
		(width 0.2)
		(layer "F.Cu")
		(net 65)
	)
	(segment
		(start 116.467962 135.4265)
		(end 116.467962 136.4665)
		(width 0.2)
		(layer "F.Cu")
		(net 65)
	)
	(via
		(at 116.667962 131.7915)
		(size 0.45)
		(drill 0.1)
		(layers "F.Cu" "B.Cu")
		(net 65)
	)
	(segment
		(start 120.619962 129.769)
		(end 119.624462 129.769)
		(width 0.2)
		(layer "B.Cu")
		(net 65)
	)
	(segment
		(start 117.317962 124.8165)
		(end 117.317962 131.7915)
		(width 0.5)
		(layer "B.Cu")
		(net 65)
	)
	(segment
		(start 120.619962 130.769)
		(end 119.661462 130.769)
		(width 0.2)
		(layer "B.Cu")
		(net 65)
	)
	(segment
		(start 119.142962 130.7415)
		(end 119.670462 131.269)
		(width 0.2)
		(layer "B.Cu")
		(net 65)
	)
	(segment
		(start 119.117962 133.7825)
		(end 117.867962 133.7825)
		(width 0.35)
		(layer "B.Cu")
		(net 65)
	)
	(segment
		(start 118.192962 130.2505)
		(end 119.142962 130.2505)
		(width 0.4)
		(layer "B.Cu")
		(net 65)
	)
	(segment
		(start 119.670462 131.269)
		(end 120.619962 131.269)
		(width 0.2)
		(layer "B.Cu")
		(net 65)
	)
	(segment
		(start 118.152962 117.6565)
		(end 118.117962 117.6915)
		(width 0.2)
		(layer "B.Cu")
		(net 65)
	)
	(segment
		(start 118.117962 122.9515)
		(end 118.117962 123.5415)
		(width 0.2)
		(layer "B.Cu")
		(net 65)
	)
	(segment
		(start 119.624462 129.769)
		(end 119.142962 130.2505)
		(width 0.2)
		(layer "B.Cu")
		(net 65)
	)
	(segment
		(start 117.842962 132.3165)
		(end 117.842962 132.7415)
		(width 0.5)
		(layer "B.Cu")
		(net 65)
	)
	(segment
		(start 118.192962 130.2505)
		(end 118.192962 131.9665)
		(width 0.4)
		(layer "B.Cu")
		(net 65)
	)
	(segment
		(start 119.548462 115.77)
		(end 119.067962 116.2505)
		(width 0.2)
		(layer "B.Cu")
		(net 65)
	)
	(segment
		(start 118.117962 123.5415)
		(end 118.117962 120.5665)
		(width 0.5)
		(layer "B.Cu")
		(net 65)
	)
	(segment
		(start 119.142962 132.8005)
		(end 117.901962 132.8005)
		(width 0.35)
		(layer "B.Cu")
		(net 65)
	)
	(segment
		(start 119.117962 133.7825)
		(end 119.117962 132.8255)
		(width 0.2)
		(layer "B.Cu")
		(net 65)
	)
	(segment
		(start 117.317962 131.7915)
		(end 117.842962 132.3165)
		(width 0.5)
		(layer "B.Cu")
		(net 65)
	)
	(segment
		(start 118.192962 131.9665)
		(end 117.842962 132.3165)
		(width 0.4)
		(layer "B.Cu")
		(net 65)
	)
	(segment
		(start 117.842962 132.7415)
		(end 117.842962 134.3165)
		(width 0.5)
		(layer "B.Cu")
		(net 65)
	)
	(segment
		(start 120.619962 115.77)
		(end 119.548462 115.77)
		(width 0.2)
		(layer "B.Cu")
		(net 65)
	)
	(segment
		(start 118.117962 120.5665)
		(end 118.117962 118.7415)
		(width 0.5)
		(layer "B.Cu")
		(net 65)
	)
	(segment
		(start 119.092962 122.9515)
		(end 118.117962 122.9515)
		(width 0.2)
		(layer "B.Cu")
		(net 65)
	)
	(segment
		(start 120.619962 116.769)
		(end 119.586462 116.769)
		(width 0.2)
		(layer "B.Cu")
		(net 65)
	)
	(segment
		(start 118.117962 118.7415)
		(end 118.117962 117.6915)
		(width 0.5)
		(layer "B.Cu")
		(net 65)
	)
	(segment
		(start 118.117962 116.2505)
		(end 119.067962 116.2505)
		(width 0.5)
		(layer "B.Cu")
		(net 65)
	)
	(segment
		(start 119.142962 130.2505)
		(end 119.142962 130.7415)
		(width 0.2)
		(layer "B.Cu")
		(net 65)
	)
	(segment
		(start 118.117962 124.0165)
		(end 117.317962 124.8165)
		(width 0.5)
		(layer "B.Cu")
		(net 65)
	)
	(segment
		(start 120.619962 133.27)
		(end 119.630462 133.27)
		(width 0.2)
		(layer "B.Cu")
		(net 65)
	)
	(segment
		(start 119.661462 130.769)
		(end 119.142962 130.2505)
		(width 0.2)
		(layer "B.Cu")
		(net 65)
	)
	(segment
		(start 118.117962 119.5565)
		(end 118.117962 118.7415)
		(width 0.2)
		(layer "B.Cu")
		(net 65)
	)
	(segment
		(start 120.619962 133.77)
		(end 119.180462 133.77)
		(width 0.2)
		(layer "B.Cu")
		(net 65)
	)
	(segment
		(start 120.619962 130.269)
		(end 119.186462 130.269)
		(width 0.2)
		(layer "B.Cu")
		(net 65)
	)
	(segment
		(start 119.630462 133.27)
		(end 119.117962 133.7825)
		(width 0.2)
		(layer "B.Cu")
		(net 65)
	)
	(segment
		(start 118.892962 119.5565)
		(end 118.117962 119.5565)
		(width 0.2)
		(layer "B.Cu")
		(net 65)
	)
	(segment
		(start 119.586462 116.769)
		(end 119.067962 116.2505)
		(width 0.2)
		(layer "B.Cu")
		(net 65)
	)
	(segment
		(start 118.117962 117.6915)
		(end 118.117962 116.2505)
		(width 0.5)
		(layer "B.Cu")
		(net 65)
	)
	(segment
		(start 118.117962 123.5415)
		(end 118.117962 124.0165)
		(width 0.5)
		(layer "B.Cu")
		(net 65)
	)
	(segment
		(start 120.619962 116.27)
		(end 119.087462 116.27)
		(width 0.2)
		(layer "B.Cu")
		(net 65)
	)
	(segment
		(start 117.317962 131.7915)
		(end 116.667962 131.7915)
		(width 0.5)
		(layer "B.Cu")
		(net 65)
	)
	(segment
		(start 118.892962 117.6565)
		(end 118.152962 117.6565)
		(width 0.2)
		(layer "B.Cu")
		(net 65)
	)
	(segment
		(start 119.160962 132.8005)
		(end 119.630462 133.27)
		(width 0.2)
		(layer "B.Cu")
		(net 65)
	)
	(segment
		(start 117.901962 132.8005)
		(end 117.842962 132.7415)
		(width 0.35)
		(layer "B.Cu")
		(net 65)
	)
	(segment
		(start 57.187962 157.462897)
		(end 57.187962 152.9565)
		(width 0.2)
		(layer "F.Cu")
		(net 66)
	)
	(segment
		(start 55.242962 159.0665)
		(end 55.584359 159.0665)
		(width 0.2)
		(layer "F.Cu")
		(net 66)
	)
	(segment
		(start 55.584359 159.0665)
		(end 57.187962 157.462897)
		(width 0.2)
		(layer "F.Cu")
		(net 66)
	)
	(segment
		(start 57.187962 152.9565)
		(end 56.882961 152.651499)
		(width 0.2)
		(layer "F.Cu")
		(net 66)
	)
	(via
		(at 56.882961 152.651499)
		(size 0.5)
		(drill 0.15)
		(layers "F.Cu" "B.Cu")
		(net 66)
	)
	(via
		(at 55.242962 159.0665)
		(size 0.45)
		(drill 0.1)
		(layers "F.Cu" "B.Cu")
		(net 66)
	)
	(segment
		(start 56.882961 152.651499)
		(end 56.60296 152.9315)
		(width 0.2)
		(layer "B.Cu")
		(net 66)
	)
	(segment
		(start 56.60296 152.9315)
		(end 56.167962 152.9315)
		(width 0.2)
		(layer "B.Cu")
		(net 66)
	)
	(segment
		(start 55.242962 159.0665)
		(end 55.242962 158.4325)
		(width 0.2)
		(layer "B.Cu")
		(net 66)
	)
	(segment
		(start 54.915962 158.1055)
		(end 54.915962 157.2655)
		(width 0.2)
		(layer "B.Cu")
		(net 66)
	)
	(segment
		(start 55.226962 158.4165)
		(end 54.915962 158.1055)
		(width 0.2)
		(layer "B.Cu")
		(net 66)
	)
	(segment
		(start 117.357963 151.682501)
		(end 120.910845 151.682501)
		(width 0.15)
		(layer "F.Cu")
		(net 67)
	)
	(segment
		(start 115.554961 151.717)
		(end 116.079962 151.717)
		(width 0.15)
		(layer "F.Cu")
		(net 67)
	)
	(segment
		(start 122.61 148.51)
		(end 122.46 148.66)
		(width 0.15)
		(layer "F.Cu")
		(net 67)
	)
	(segment
		(start 116.114462 151.6825)
		(end 117.357963 151.682501)
		(width 0.15)
		(layer "F.Cu")
		(net 67)
	)
	(segment
		(start 122.46 150.133346)
		(end 120.910845 151.682501)
		(width 0.15)
		(layer "F.Cu")
		(net 67)
	)
	(segment
		(start 116.079962 151.717)
		(end 116.114462 151.6825)
		(width 0.15)
		(layer "F.Cu")
		(net 67)
	)
	(segment
		(start 122.46 148.66)
		(end 122.46 150.133346)
		(width 0.15)
		(layer "F.Cu")
		(net 67)
	)
	(via
		(at 138.867962 126.0815)
		(size 0.45)
		(drill 0.1)
		(layers "F.Cu" "B.Cu")
		(net 67)
	)
	(via
		(at 122.61 148.51)
		(size 0.45)
		(drill 0.1)
		(layers "F.Cu" "B.Cu")
		(net 67)
	)
	(segment
		(start 138.367963 125.9665)
		(end 137.467962 125.9665)
		(width 0.15)
		(layer "B.Cu")
		(net 67)
	)
	(segment
		(start 138.667962 125.8815)
		(end 138.452963 125.8815)
		(width 0.15)
		(layer "B.Cu")
		(net 67)
	)
	(segment
		(start 138.452963 125.8815)
		(end 138.367963 125.9665)
		(width 0.15)
		(layer "B.Cu")
		(net 67)
	)
	(segment
		(start 138.867962 126.0815)
		(end 138.667962 125.8815)
		(width 0.15)
		(layer "B.Cu")
		(net 67)
	)
	(segment
		(start 138.867962 126.0815)
		(end 138.739462 125.953)
		(width 0.138)
		(layer "In2.Cu")
		(net 67)
	)
	(segment
		(start 134.944462 130.168538)
		(end 135.764462 130.988538)
		(width 0.138)
		(layer "In2.Cu")
		(net 67)
	)
	(segment
		(start 122.531499 146.505676)
		(end 122.531499 148.431499)
		(width 0.138)
		(layer "In2.Cu")
		(net 67)
	)
	(segment
		(start 138.739462 125.953)
		(end 138.495924 125.953)
		(width 0.138)
		(layer "In2.Cu")
		(net 67)
	)
	(segment
		(start 123.109175 145.928)
		(end 122.531499 146.505676)
		(width 0.138)
		(layer "In2.Cu")
		(net 67)
	)
	(segment
		(start 137.767965 126.680962)
		(end 137.720635 126.72829)
		(width 0.138)
		(layer "In2.Cu")
		(net 67)
	)
	(segment
		(start 136.748244 127.70068)
		(end 134.944462 129.504462)
		(width 0.138)
		(layer "In2.Cu")
		(net 67)
	)
	(segment
		(start 138.102473 126.633631)
		(end 138.055143 126.680962)
		(width 0.138)
		(layer "In2.Cu")
		(net 67)
	)
	(segment
		(start 123.117962 145.928)
		(end 123.109175 145.928)
		(width 0.138)
		(layer "In2.Cu")
		(net 67)
	)
	(segment
		(start 138.495924 125.953)
		(end 138.102473 126.346451)
		(width 0.138)
		(layer "In2.Cu")
		(net 67)
	)
	(segment
		(start 135.764462 133.2815)
		(end 123.117962 145.928)
		(width 0.138)
		(layer "In2.Cu")
		(net 67)
	)
	(segment
		(start 135.764462 130.988538)
		(end 135.764462 133.2815)
		(width 0.138)
		(layer "In2.Cu")
		(net 67)
	)
	(segment
		(start 122.531499 148.431499)
		(end 122.61 148.51)
		(width 0.138)
		(layer "In2.Cu")
		(net 67)
	)
	(segment
		(start 137.720635 126.72829)
		(end 136.748244 127.70068)
		(width 0.138)
		(layer "In2.Cu")
		(net 67)
	)
	(segment
		(start 134.944462 129.504462)
		(end 134.944462 130.168538)
		(width 0.138)
		(layer "In2.Cu")
		(net 67)
	)
	(arc
		(start 138.102473 126.490041)
		(mid 138.13221 126.561837)
		(end 138.102473 126.633631)
		(width 0.138)
		(layer "In2.Cu")
		(net 67)
	)
	(arc
		(start 138.055143 126.680962)
		(mid 137.983349 126.7107)
		(end 137.911555 126.680961)
		(width 0.138)
		(layer "In2.Cu")
		(net 67)
	)
	(arc
		(start 138.102473 126.346451)
		(mid 138.072734 126.418247)
		(end 138.102473 126.490041)
		(width 0.138)
		(layer "In2.Cu")
		(net 67)
	)
	(arc
		(start 137.911555 126.680961)
		(mid 137.839759 126.651224)
		(end 137.767965 126.680962)
		(width 0.138)
		(layer "In2.Cu")
		(net 67)
	)
	(segment
		(start 110.752962 152.138154)
		(end 111.165808 152.551)
		(width 0.15)
		(layer "F.Cu")
		(net 68)
	)
	(segment
		(start 110.481748 148.87694)
		(end 110.752962 149.148154)
		(width 0.15)
		(layer "F.Cu")
		(net 68)
	)
	(segment
		(start 110.210462 148.87694)
		(end 110.481748 148.87694)
		(width 0.15)
		(layer "F.Cu")
		(net 68)
	)
	(segment
		(start 110.752962 149.148154)
		(end 110.752962 152.138154)
		(width 0.15)
		(layer "F.Cu")
		(net 68)
	)
	(segment
		(start 111.94896 152.516)
		(end 112.473961 152.516)
		(width 0.15)
		(layer "F.Cu")
		(net 68)
	)
	(segment
		(start 110.047962 148.71444)
		(end 110.210462 148.87694)
		(width 0.15)
		(layer "F.Cu")
		(net 68)
	)
	(segment
		(start 111.91396 152.551)
		(end 111.94896 152.516)
		(width 0.15)
		(layer "F.Cu")
		(net 68)
	)
	(segment
		(start 111.165808 152.551)
		(end 111.91396 152.551)
		(width 0.15)
		(layer "F.Cu")
		(net 68)
	)
	(via
		(at 110.047962 148.71444)
		(size 0.45)
		(drill 0.1)
		(layers "F.Cu" "B.Cu")
		(free yes)
		(net 68)
	)
	(segment
		(start 122.239616 142.9615)
		(end 113.749616 142.9615)
		(width 0.15)
		(layer "B.Cu")
		(net 68)
	)
	(segment
		(start 132.649616 132.5515)
		(end 122.239616 142.9615)
		(width 0.15)
		(layer "B.Cu")
		(net 68)
	)
	(segment
		(start 113.749616 142.9615)
		(end 110.592962 146.118154)
		(width 0.15)
		(layer "B.Cu")
		(net 68)
	)
	(segment
		(start 137.467962 132.4665)
		(end 136.567961 132.4665)
		(width 0.15)
		(layer "B.Cu")
		(net 68)
	)
	(segment
		(start 110.592962 148.668154)
		(end 110.384176 148.87694)
		(width 0.15)
		(layer "B.Cu")
		(net 68)
	)
	(segment
		(start 136.482961 132.5515)
		(end 132.649616 132.5515)
		(width 0.15)
		(layer "B.Cu")
		(net 68)
	)
	(segment
		(start 110.210462 148.87694)
		(end 110.047962 148.71444)
		(width 0.15)
		(layer "B.Cu")
		(net 68)
	)
	(segment
		(start 136.567961 132.4665)
		(end 136.482961 132.5515)
		(width 0.15)
		(layer "B.Cu")
		(net 68)
	)
	(segment
		(start 110.592962 146.118154)
		(end 110.592962 148.668154)
		(width 0.15)
		(layer "B.Cu")
		(net 68)
	)
	(segment
		(start 110.384176 148.87694)
		(end 110.210462 148.87694)
		(width 0.15)
		(layer "B.Cu")
		(net 68)
	)
	(segment
		(start 116.515654 152.551)
		(end 116.831654 152.235)
		(width 0.15)
		(layer "F.Cu")
		(net 69)
	)
	(segment
		(start 116.079962 152.516)
		(end 116.114962 152.551)
		(width 0.15)
		(layer "F.Cu")
		(net 69)
	)
	(segment
		(start 120.110607 152.477261)
		(end 120.322739 152.477261)
		(width 0.15)
		(layer "F.Cu")
		(net 69)
	)
	(segment
		(start 116.114962 152.551)
		(end 116.515654 152.551)
		(width 0.15)
		(layer "F.Cu")
		(net 69)
	)
	(segment
		(start 115.554961 152.516)
		(end 116.079962 152.516)
		(width 0.15)
		(layer "F.Cu")
		(net 69)
	)
	(segment
		(start 119.868346 152.235)
		(end 120.110607 152.477261)
		(width 0.15)
		(layer "F.Cu")
		(net 69)
	)
	(segment
		(start 116.831654 152.235)
		(end 119.868346 152.235)
		(width 0.15)
		(layer "F.Cu")
		(net 69)
	)
	(via
		(at 120.322739 152.477261)
		(size 0.45)
		(drill 0.1)
		(layers "F.Cu" "B.Cu")
		(net 69)
	)
	(via
		(at 139.317962 127.8515)
		(size 0.45)
		(drill 0.1)
		(layers "F.Cu" "B.Cu")
		(net 69)
	)
	(segment
		(start 139.117963 128.051499)
		(end 139.317962 127.8515)
		(width 0.15)
		(layer "B.Cu")
		(net 69)
	)
	(segment
		(start 138.367963 127.9665)
		(end 138.452964 128.051499)
		(width 0.15)
		(layer "B.Cu")
		(net 69)
	)
	(segment
		(start 137.467962 127.9665)
		(end 138.367963 127.9665)
		(width 0.15)
		(layer "B.Cu")
		(net 69)
	)
	(segment
		(start 138.452964 128.051499)
		(end 139.117963 128.051499)
		(width 0.15)
		(layer "B.Cu")
		(net 69)
	)
	(segment
		(start 125.006462 146.693538)
		(end 136.781462 134.918538)
		(width 0.138)
		(layer "In2.Cu")
		(net 69)
	)
	(segment
		(start 121.402038 153.0635)
		(end 125.006462 149.459076)
		(width 0.138)
		(layer "In2.Cu")
		(net 69)
	)
	(segment
		(start 136.781462 130.038538)
		(end 138.188765 128.631235)
		(width 0.138)
		(layer "In2.Cu")
		(net 69)
	)
	(segment
		(start 138.416704 128.403296)
		(end 138.84 127.98)
		(width 0.138)
		(layer "In2.Cu")
		(net 69)
	)
	(segment
		(start 136.781462 134.918538)
		(end 136.781462 130.038538)
		(width 0.138)
		(layer "In2.Cu")
		(net 69)
	)
	(segment
		(start 120.322739 152.477261)
		(end 120.322739 152.588277)
		(width 0.138)
		(layer "In2.Cu")
		(net 69)
	)
	(segment
		(start 138.84 127.98)
		(end 139.189462 127.98)
		(width 0.138)
		(layer "In2.Cu")
		(net 69)
	)
	(segment
		(start 125.006462 149.459076)
		(end 125.006462 146.693538)
		(width 0.138)
		(layer "In2.Cu")
		(net 69)
	)
	(segment
		(start 120.797962 153.0635)
		(end 121.402038 153.0635)
		(width 0.138)
		(layer "In2.Cu")
		(net 69)
	)
	(segment
		(start 138.188765 128.631235)
		(end 138.416704 128.403296)
		(width 0.138)
		(layer "In2.Cu")
		(net 69)
	)
	(segment
		(start 120.322739 152.588277)
		(end 120.797962 153.0635)
		(width 0.138)
		(layer "In2.Cu")
		(net 69)
	)
	(segment
		(start 139.189462 127.98)
		(end 139.317962 127.8515)
		(width 0.138)
		(layer "In2.Cu")
		(net 69)
	)
	(segment
		(start 111.029116 152.881)
		(end 111.91396 152.881)
		(width 0.15)
		(layer "F.Cu")
		(net 70)
	)
	(segment
		(start 110.422962 149.284846)
		(end 110.422962 152.274846)
		(width 0.15)
		(layer "F.Cu")
		(net 70)
	)
	(segment
		(start 110.210462 149.20694)
		(end 110.345056 149.20694)
		(width 0.15)
		(layer "F.Cu")
		(net 70)
	)
	(segment
		(start 110.422962 152.274846)
		(end 111.029116 152.881)
		(width 0.15)
		(layer "F.Cu")
		(net 70)
	)
	(segment
		(start 111.94896 152.916)
		(end 112.473961 152.916)
		(width 0.15)
		(layer "F.Cu")
		(net 70)
	)
	(segment
		(start 110.047962 149.36944)
		(end 110.210462 149.20694)
		(width 0.15)
		(layer "F.Cu")
		(net 70)
	)
	(segment
		(start 111.91396 152.881)
		(end 111.94896 152.916)
		(width 0.15)
		(layer "F.Cu")
		(net 70)
	)
	(segment
		(start 110.345056 149.20694)
		(end 110.422962 149.284846)
		(width 0.15)
		(layer "F.Cu")
		(net 70)
	)
	(via
		(at 110.047962 149.36944)
		(size 0.45)
		(drill 0.1)
		(layers "F.Cu" "B.Cu")
		(free yes)
		(net 70)
	)
	(segment
		(start 136.567961 132.9665)
		(end 136.482961 132.8815)
		(width 0.15)
		(layer "B.Cu")
		(net 70)
	)
	(segment
		(start 110.922962 148.804846)
		(end 110.520868 149.20694)
		(width 0.15)
		(layer "B.Cu")
		(net 70)
	)
	(segment
		(start 136.482961 132.8815)
		(end 132.786308 132.8815)
		(width 0.15)
		(layer "B.Cu")
		(net 70)
	)
	(segment
		(start 110.210462 149.20694)
		(end 110.047962 149.36944)
		(width 0.15)
		(layer "B.Cu")
		(net 70)
	)
	(segment
		(start 122.376308 143.2915)
		(end 113.886308 143.2915)
		(width 0.15)
		(layer "B.Cu")
		(net 70)
	)
	(segment
		(start 137.467962 132.9665)
		(end 136.567961 132.9665)
		(width 0.15)
		(layer "B.Cu")
		(net 70)
	)
	(segment
		(start 113.886308 143.2915)
		(end 110.922962 146.254846)
		(width 0.15)
		(layer "B.Cu")
		(net 70)
	)
	(segment
		(start 132.786308 132.8815)
		(end 122.376308 143.2915)
		(width 0.15)
		(layer "B.Cu")
		(net 70)
	)
	(segment
		(start 110.922962 146.254846)
		(end 110.922962 148.804846)
		(width 0.15)
		(layer "B.Cu")
		(net 70)
	)
	(segment
		(start 110.520868 149.20694)
		(end 110.210462 149.20694)
		(width 0.15)
		(layer "B.Cu")
		(net 70)
	)
	(segment
		(start 116.079962 152.916)
		(end 116.114962 152.881)
		(width 0.15)
		(layer "F.Cu")
		(net 71)
	)
	(segment
		(start 119.731654 152.565)
		(end 119.877261 152.710607)
		(width 0.15)
		(layer "F.Cu")
		(net 71)
	)
	(segment
		(start 119.877261 152.710607)
		(end 119.877261 152.922739)
		(width 0.15)
		(layer "F.Cu")
		(net 71)
	)
	(segment
		(start 116.652346 152.881)
		(end 116.968346 152.565)
		(width 0.15)
		(layer "F.Cu")
		(net 71)
	)
	(segment
		(start 115.554961 152.916)
		(end 116.079962 152.916)
		(width 0.15)
		(layer "F.Cu")
		(net 71)
	)
	(segment
		(start 116.968346 152.565)
		(end 119.731654 152.565)
		(width 0.15)
		(layer "F.Cu")
		(net 71)
	)
	(segment
		(start 116.114962 152.881)
		(end 116.652346 152.881)
		(width 0.15)
		(layer "F.Cu")
		(net 71)
	)
	(via
		(at 139.317962 128.5815)
		(size 0.45)
		(drill 0.1)
		(layers "F.Cu" "B.Cu")
		(net 71)
	)
	(via
		(at 119.877261 152.922739)
		(size 0.45)
		(drill 0.1)
		(layers "F.Cu" "B.Cu")
		(net 71)
	)
	(segment
		(start 138.367963 128.4665)
		(end 138.452964 128.381501)
		(width 0.15)
		(layer "B.Cu")
		(net 71)
	)
	(segment
		(start 138.452964 128.381501)
		(end 139.117963 128.381501)
		(width 0.15)
		(layer "B.Cu")
		(net 71)
	)
	(segment
		(start 139.117963 128.381501)
		(end 139.317962 128.5815)
		(width 0.15)
		(layer "B.Cu")
		(net 71)
	)
	(segment
		(start 137.467962 128.4665)
		(end 138.367963 128.4665)
		(width 0.15)
		(layer "B.Cu")
		(net 71)
	)
	(segment
		(start 119.877261 152.922739)
		(end 119.988277 152.922739)
		(width 0.138)
		(layer "In2.Cu")
		(net 71)
	)
	(segment
		(start 139.035924 128.453)
		(end 139.189462 128.453)
		(width 0.138)
		(layer "In2.Cu")
		(net 71)
	)
	(segment
		(start 125.479462 149.655)
		(end 125.479462 146.889462)
		(width 0.138)
		(layer "In2.Cu")
		(net 71)
	)
	(segment
		(start 138.751166 128.737758)
		(end 138.845023 128.643901)
		(width 0.138)
		(layer "In2.Cu")
		(net 71)
	)
	(segment
		(start 138.845023 128.643901)
		(end 139.035924 128.453)
		(width 0.138)
		(layer "In2.Cu")
		(net 71)
	)
	(segment
		(start 119.988277 152.922739)
		(end 120.602038 153.5365)
		(width 0.138)
		(layer "In2.Cu")
		(net 71)
	)
	(segment
		(start 120.602038 153.5365)
		(end 121.597962 153.5365)
		(width 0.138)
		(layer "In2.Cu")
		(net 71)
	)
	(segment
		(start 125.479462 146.889462)
		(end 137.254462 135.114462)
		(width 0.138)
		(layer "In2.Cu")
		(net 71)
	)
	(segment
		(start 137.254462 135.114462)
		(end 137.254462 130.234462)
		(width 0.138)
		(layer "In2.Cu")
		(net 71)
	)
	(segment
		(start 137.254462 130.234462)
		(end 138.523227 128.965697)
		(width 0.138)
		(layer "In2.Cu")
		(net 71)
	)
	(segment
		(start 121.597962 153.5365)
		(end 125.479462 149.655)
		(width 0.138)
		(layer "In2.Cu")
		(net 71)
	)
	(segment
		(start 139.189462 128.453)
		(end 139.317962 128.5815)
		(width 0.138)
		(layer "In2.Cu")
		(net 71)
	)
	(segment
		(start 138.523227 128.965697)
		(end 138.751166 128.737758)
		(width 0.138)
		(layer "In2.Cu")
		(net 71)
	)
	(segment
		(start 111.94896 159.716)
		(end 111.91346 159.7515)
		(width 0.15)
		(layer "F.Cu")
		(net 72)
	)
	(segment
		(start 104.202962 163.0865)
		(end 104.202962 162.51964)
		(width 0.15)
		(layer "F.Cu")
		(net 72)
	)
	(segment
		(start 87.142962 166.298154)
		(end 87.142962 171.034846)
		(width 0.15)
		(layer "F.Cu")
		(net 72)
	)
	(segment
		(start 90.019616 163.4215)
		(end 87.142962 166.298154)
		(width 0.15)
		(layer "F.Cu")
		(net 72)
	)
	(segment
		(start 90.019616 163.4215)
		(end 102.537962 163.4215)
		(width 0.15)
		(layer "F.Cu")
		(net 72)
	)
	(segment
		(start 102.872962 162.51964)
		(end 102.872962 163.0865)
		(width 0.15)
		(layer "F.Cu")
		(net 72)
	)
	(segment
		(start 87.957963 171.593501)
		(end 88.117962 171.7535)
		(width 0.15)
		(layer "F.Cu")
		(net 72)
	)
	(segment
		(start 87.142962 171.034846)
		(end 87.701617 171.593501)
		(width 0.15)
		(layer "F.Cu")
		(net 72)
	)
	(segment
		(start 111.91346 159.7515)
		(end 108.769616 159.7515)
		(width 0.15)
		(layer "F.Cu")
		(net 72)
	)
	(segment
		(start 105.099616 163.4215)
		(end 104.537962 163.4215)
		(width 0.15)
		(layer "F.Cu")
		(net 72)
	)
	(segment
		(start 108.769616 159.7515)
		(end 105.099616 163.4215)
		(width 0.15)
		(layer "F.Cu")
		(net 72)
	)
	(segment
		(start 112.473961 159.716)
		(end 111.94896 159.716)
		(width 0.15)
		(layer "F.Cu")
		(net 72)
	)
	(segment
		(start 87.701617 171.593501)
		(end 87.957963 171.593501)
		(width 0.15)
		(layer "F.Cu")
		(net 72)
	)
	(via
		(at 88.117962 171.7535)
		(size 0.45)
		(drill 0.1)
		(layers "F.Cu" "B.Cu")
		(net 72)
	)
	(arc
		(start 103.537962 161.85464)
		(mid 103.067736 162.049414)
		(end 102.872962 162.51964)
		(width 0.15)
		(layer "F.Cu")
		(net 72)
	)
	(arc
		(start 104.202962 162.51964)
		(mid 104.008188 162.049414)
		(end 103.537962 161.85464)
		(width 0.15)
		(layer "F.Cu")
		(net 72)
	)
	(arc
		(start 102.872962 163.0865)
		(mid 102.774843 163.323381)
		(end 102.537962 163.4215)
		(width 0.15)
		(layer "F.Cu")
		(net 72)
	)
	(arc
		(start 104.537962 163.4215)
		(mid 104.301081 163.323381)
		(end 104.202962 163.0865)
		(width 0.15)
		(layer "F.Cu")
		(net 72)
	)
	(segment
		(start 88.679711 171.596)
		(end 88.275462 171.596)
		(width 0.135)
		(layer "B.Cu")
		(net 72)
	)
	(segment
		(start 89.893462 171.6785)
		(end 90.249713 171.6785)
		(width 0.15)
		(layer "B.Cu")
		(net 72)
	)
	(segment
		(start 88.275462 171.596)
		(end 88.117962 171.7535)
		(width 0.135)
		(layer "B.Cu")
		(net 72)
	)
	(segment
		(start 90.649966 171.5935)
		(end 90.658966 171.6025)
		(width 0.15)
		(layer "B.Cu")
		(net 72)
	)
	(segment
		(start 90.249713 171.6785)
		(end 90.334713 171.5935)
		(width 0.15)
		(layer "B.Cu")
		(net 72)
	)
	(segment
		(start 90.334713 171.5935)
		(end 90.649966 171.5935)
		(width 0.15)
		(layer "B.Cu")
		(net 72)
	)
	(segment
		(start 90.827962 171.6025)
		(end 90.912962 171.6875)
		(width 0.15)
		(layer "B.Cu")
		(net 72)
	)
	(segment
		(start 90.658966 171.6025)
		(end 90.827962 171.6025)
		(width 0.15)
		(layer "B.Cu")
		(net 72)
	)
	(segment
		(start 89.118462 171.6785)
		(end 89.893462 171.6785)
		(width 0.15)
		(layer "B.Cu")
		(net 72)
	)
	(segment
		(start 88.762211 171.6785)
		(end 88.679711 171.596)
		(width 0.135)
		(layer "B.Cu")
		(net 72)
	)
	(segment
		(start 89.118462 171.6785)
		(end 88.762211 171.6785)
		(width 0.135)
		(layer "B.Cu")
		(net 72)
	)
	(segment
		(start 105.236308 163.7515)
		(end 108.906308 160.0815)
		(width 0.15)
		(layer "F.Cu")
		(net 73)
	)
	(segment
		(start 103.872962 162.51964)
		(end 103.872962 163.0865)
		(width 0.15)
		(layer "F.Cu")
		(net 73)
	)
	(segment
		(start 87.991411 169.1865)
		(end 87.672962 169.1865)
		(width 0.15)
		(layer "F.Cu")
		(net 73)
	)
	(segment
		(start 111.94896 160.117)
		(end 112.473961 160.117)
		(width 0.15)
		(layer "F.Cu")
		(net 73)
	)
	(segment
		(start 87.472962 170.898154)
		(end 87.472962 169.7865)
		(width 0.15)
		(layer "F.Cu")
		(net 73)
	)
	(segment
		(start 104.537962 163.7515)
		(end 105.236308 163.7515)
		(width 0.15)
		(layer "F.Cu")
		(net 73)
	)
	(segment
		(start 87.957963 171.263499)
		(end 87.838307 171.263499)
		(width 0.15)
		(layer "F.Cu")
		(net 73)
	)
	(segment
		(start 87.838307 171.263499)
		(end 87.472962 170.898154)
		(width 0.15)
		(layer "F.Cu")
		(net 73)
	)
	(segment
		(start 103.202962 163.0865)
		(end 103.202962 162.51964)
		(width 0.15)
		(layer "F.Cu")
		(net 73)
	)
	(segment
		(start 87.672962 169.5865)
		(end 87.991411 169.5865)
		(width 0.15)
		(layer "F.Cu")
		(net 73)
	)
	(segment
		(start 88.117962 171.1035)
		(end 87.957963 171.263499)
		(width 0.15)
		(layer "F.Cu")
		(net 73)
	)
	(segment
		(start 108.906308 160.0815)
		(end 111.91346 160.0815)
		(width 0.15)
		(layer "F.Cu")
		(net 73)
	)
	(segment
		(start 90.156308 163.7515)
		(end 102.537962 163.7515)
		(width 0.15)
		(layer "F.Cu")
		(net 73)
	)
	(segment
		(start 111.91346 160.0815)
		(end 111.94896 160.117)
		(width 0.15)
		(layer "F.Cu")
		(net 73)
	)
	(segment
		(start 87.472962 168.9865)
		(end 87.472962 166.434846)
		(width 0.15)
		(layer "F.Cu")
		(net 73)
	)
	(segment
		(start 87.472962 166.434846)
		(end 90.156308 163.7515)
		(width 0.15)
		(layer "F.Cu")
		(net 73)
	)
	(via
		(at 88.117962 171.1035)
		(size 0.45)
		(drill 0.1)
		(layers "F.Cu" "B.Cu")
		(net 73)
	)
	(arc
		(start 87.472962 169.7865)
		(mid 87.531541 169.645079)
		(end 87.672962 169.5865)
		(width 0.15)
		(layer "F.Cu")
		(net 73)
	)
	(arc
		(start 88.191411 169.3865)
		(mid 88.132832 169.245079)
		(end 87.991411 169.1865)
		(width 0.15)
		(layer "F.Cu")
		(net 73)
	)
	(arc
		(start 103.872962 163.0865)
		(mid 104.067736 163.556726)
		(end 104.537962 163.7515)
		(width 0.15)
		(layer "F.Cu")
		(net 73)
	)
	(arc
		(start 103.537962 162.18464)
		(mid 103.774843 162.282759)
		(end 103.872962 162.51964)
		(width 0.15)
		(layer "F.Cu")
		(net 73)
	)
	(arc
		(start 103.202962 162.51964)
		(mid 103.301081 162.282759)
		(end 103.537962 162.18464)
		(width 0.15)
		(layer "F.Cu")
		(net 73)
	)
	(arc
		(start 87.991411 169.5865)
		(mid 88.132832 169.527921)
		(end 88.191411 169.3865)
		(width 0.15)
		(layer "F.Cu")
		(net 73)
	)
	(arc
		(start 87.672962 169.1865)
		(mid 87.531541 169.127921)
		(end 87.472962 168.9865)
		(width 0.15)
		(layer "F.Cu")
		(net 73)
	)
	(arc
		(start 102.537962 163.7515)
		(mid 103.008188 163.556726)
		(end 103.202962 163.0865)
		(width 0.15)
		(layer "F.Cu")
		(net 73)
	)
	(segment
		(start 89.118462 171.1785)
		(end 89.893462 171.1785)
		(width 0.15)
		(layer "B.Cu")
		(net 73)
	)
	(segment
		(start 90.827962 171.2725)
		(end 90.912962 171.1875)
		(width 0.15)
		(layer "B.Cu")
		(net 73)
	)
	(segment
		(start 88.275462 171.261)
		(end 88.117962 171.1035)
		(width 0.135)
		(layer "B.Cu")
		(net 73)
	)
	(segment
		(start 90.77625 171.2635)
		(end 90.78525 171.2725)
		(width 0.15)
		(layer "B.Cu")
		(net 73)
	)
	(segment
		(start 89.118462 171.1785)
		(end 88.762211 171.1785)
		(width 0.135)
		(layer "B.Cu")
		(net 73)
	)
	(segment
		(start 88.762211 171.1785)
		(end 88.679711 171.261)
		(width 0.135)
		(layer "B.Cu")
		(net 73)
	)
	(segment
		(start 89.893462 171.1785)
		(end 90.249713 171.1785)
		(width 0.15)
		(layer "B.Cu")
		(net 73)
	)
	(segment
		(start 90.334713 171.2635)
		(end 90.77625 171.2635)
		(width 0.15)
		(layer "B.Cu")
		(net 73)
	)
	(segment
		(start 90.249713 171.1785)
		(end 90.334713 171.2635)
		(width 0.15)
		(layer "B.Cu")
		(net 73)
	)
	(segment
		(start 90.78525 171.2725)
		(end 90.827962 171.2725)
		(width 0.15)
		(layer "B.Cu")
		(net 73)
	)
	(segment
		(start 88.679711 171.261)
		(end 88.275462 171.261)
		(width 0.135)
		(layer "B.Cu")
		(net 73)
	)
	(segment
		(start 106.304617 164.996499)
		(end 90.187961 164.996499)
		(width 0.15)
		(layer "F.Cu")
		(net 74)
	)
	(segment
		(start 110.349616 160.9515)
		(end 106.304617 164.996499)
		(width 0.15)
		(layer "F.Cu")
		(net 74)
	)
	(segment
		(start 90.187961 164.996499)
		(end 90.027962 164.8365)
		(width 0.15)
		(layer "F.Cu")
		(net 74)
	)
	(segment
		(start 111.91446 160.9515)
		(end 110.349616 160.9515)
		(width 0.15)
		(layer "F.Cu")
		(net 74)
	)
	(segment
		(start 112.473961 160.917)
		(end 111.94896 160.917)
		(width 0.15)
		(layer "F.Cu")
		(net 74)
	)
	(segment
		(start 111.94896 160.917)
		(end 111.91446 160.9515)
		(width 0.15)
		(layer "F.Cu")
		(net 74)
	)
	(segment
		(start 90.027962 164.8365)
		(end 90.195462 165.004)
		(width 0.135)
		(layer "F.Cu")
		(net 74)
	)
	(via
		(at 90.027962 164.8365)
		(size 0.45)
		(drill 0.1)
		(layers "F.Cu" "B.Cu")
		(net 74)
	)
	(segment
		(start 86.482962 167.9065)
		(end 86.317962 167.9065)
		(width 0.15)
		(layer "B.Cu")
		(net 74)
	)
	(segment
		(start 86.317962 169.2365)
		(end 86.482962 169.2365)
		(width 0.15)
		(layer "B.Cu")
		(net 74)
	)
	(segment
		(start 90.249713 173.1785)
		(end 90.334213 173.094)
		(width 0.15)
		(layer "B.Cu")
		(net 74)
	)
	(segment
		(start 85.867962 168.3565)
		(end 85.867962 168.7865)
		(width 0.15)
		(layer "B.Cu")
		(net 74)
	)
	(segment
		(start 88.762211 173.1785)
		(end 89.118462 173.1785)
		(width 0.15)
		(layer "B.Cu")
		(net 74)
	)
	(segment
		(start 89.118462 173.1785)
		(end 89.893462 173.1785)
		(width 0.15)
		(layer "B.Cu")
		(net 74)
	)
	(segment
		(start 90.619579 173.094)
		(end 90.628079 173.1025)
		(width 0.15)
		(layer "B.Cu")
		(net 74)
	)
	(segment
		(start 90.027962 164.8365)
		(end 89.867963 164.996499)
		(width 0.15)
		(layer "B.Cu")
		(net 74)
	)
	(segment
		(start 87.961616 173.0935)
		(end 88.677211 173.0935)
		(width 0.15)
		(layer "B.Cu")
		(net 74)
	)
	(segment
		(start 90.628079 173.1025)
		(end 90.827962 173.1025)
		(width 0.15)
		(layer "B.Cu")
		(net 74)
	)
	(segment
		(start 88.484617 164.996499)
		(end 86.602962 166.878154)
		(width 0.15)
		(layer "B.Cu")
		(net 74)
	)
	(segment
		(start 86.602962 169.3565)
		(end 86.602962 171.734846)
		(width 0.15)
		(layer "B.Cu")
		(net 74)
	)
	(segment
		(start 89.867963 164.996499)
		(end 88.484617 164.996499)
		(width 0.15)
		(layer "B.Cu")
		(net 74)
	)
	(segment
		(start 90.827962 173.1025)
		(end 90.912962 173.1875)
		(width 0.15)
		(layer "B.Cu")
		(net 74)
	)
	(segment
		(start 86.602962 171.734846)
		(end 87.961616 173.0935)
		(width 0.15)
		(layer "B.Cu")
		(net 74)
	)
	(segment
		(start 90.334213 173.094)
		(end 90.619579 173.094)
		(width 0.15)
		(layer "B.Cu")
		(net 74)
	)
	(segment
		(start 86.602962 166.878154)
		(end 86.602962 167.7865)
		(width 0.15)
		(layer "B.Cu")
		(net 74)
	)
	(segment
		(start 88.677211 173.0935)
		(end 88.762211 173.1785)
		(width 0.15)
		(layer "B.Cu")
		(net 74)
	)
	(segment
		(start 89.893462 173.1785)
		(end 90.249713 173.1785)
		(width 0.15)
		(layer "B.Cu")
		(net 74)
	)
	(arc
		(start 85.867962 168.7865)
		(mid 85.999764 169.104698)
		(end 86.317962 169.2365)
		(width 0.15)
		(layer "B.Cu")
		(net 74)
	)
	(arc
		(start 86.482962 169.2365)
		(mid 86.567815 169.271647)
		(end 86.602962 169.3565)
		(width 0.15)
		(layer "B.Cu")
		(net 74)
	)
	(arc
		(start 86.317962 167.9065)
		(mid 85.999764 168.038302)
		(end 85.867962 168.3565)
		(width 0.15)
		(layer "B.Cu")
		(net 74)
	)
	(arc
		(start 86.602962 167.7865)
		(mid 86.567815 167.871353)
		(end 86.482962 167.9065)
		(width 0.15)
		(layer "B.Cu")
		(net 74)
	)
	(segment
		(start 111.94896 161.316)
		(end 111.91446 161.2815)
		(width 0.15)
		(layer "F.Cu")
		(net 75)
	)
	(segment
		(start 90.187961 165.326501)
		(end 90.027962 165.4865)
		(width 0.15)
		(layer "F.Cu")
		(net 75)
	)
	(segment
		(start 110.486308 161.2815)
		(end 106.441307 165.326501)
		(width 0.15)
		(layer "F.Cu")
		(net 75)
	)
	(segment
		(start 90.027962 165.4865)
		(end 90.195462 165.319)
		(width 0.135)
		(layer "F.Cu")
		(net 75)
	)
	(segment
		(start 106.441307 165.326501)
		(end 90.187961 165.326501)
		(width 0.15)
		(layer "F.Cu")
		(net 75)
	)
	(segment
		(start 112.473961 161.316)
		(end 111.94896 161.316)
		(width 0.15)
		(layer "F.Cu")
		(net 75)
	)
	(segment
		(start 111.91446 161.2815)
		(end 110.486308 161.2815)
		(width 0.15)
		(layer "F.Cu")
		(net 75)
	)
	(via
		(at 90.027962 165.4865)
		(size 0.45)
		(drill 0.1)
		(layers "F.Cu" "B.Cu")
		(net 75)
	)
	(segment
		(start 86.197962 168.7865)
		(end 86.197962 168.3565)
		(width 0.15)
		(layer "B.Cu")
		(net 75)
	)
	(segment
		(start 89.118462 172.6785)
		(end 88.762211 172.6785)
		(width 0.15)
		(layer "B.Cu")
		(net 75)
	)
	(segment
		(start 90.754363 172.7725)
		(end 90.827962 172.7725)
		(width 0.15)
		(layer "B.Cu")
		(net 75)
	)
	(segment
		(start 88.677211 172.7635)
		(end 88.098308 172.7635)
		(width 0.15)
		(layer "B.Cu")
		(net 75)
	)
	(segment
		(start 90.249713 172.6795)
		(end 90.334213 172.764)
		(width 0.15)
		(layer "B.Cu")
		(net 75)
	)
	(segment
		(start 86.932962 170.1365)
		(end 86.932962 169.3565)
		(width 0.15)
		(layer "B.Cu")
		(net 75)
	)
	(segment
		(start 86.317962 168.2365)
		(end 86.482962 168.2365)
		(width 0.15)
		(layer "B.Cu")
		(net 75)
	)
	(segment
		(start 88.762211 172.6785)
		(end 88.677211 172.7635)
		(width 0.15)
		(layer "B.Cu")
		(net 75)
	)
	(segment
		(start 87.452822 170.3365)
		(end 87.132962 170.3365)
		(width 0.15)
		(layer "B.Cu")
		(net 75)
	)
	(segment
		(start 90.745863 172.764)
		(end 90.754363 172.7725)
		(width 0.15)
		(layer "B.Cu")
		(net 75)
	)
	(segment
		(start 86.932962 171.598154)
		(end 86.932962 170.9365)
		(width 0.15)
		(layer "B.Cu")
		(net 75)
	)
	(segment
		(start 88.098308 172.7635)
		(end 86.932962 171.598154)
		(width 0.15)
		(layer "B.Cu")
		(net 75)
	)
	(segment
		(start 87.132962 170.7365)
		(end 87.452822 170.7365)
		(width 0.15)
		(layer "B.Cu")
		(net 75)
	)
	(segment
		(start 86.932962 167.014846)
		(end 88.621307 165.326501)
		(width 0.15)
		(layer "B.Cu")
		(net 75)
	)
	(segment
		(start 86.932962 167.7865)
		(end 86.932962 167.014846)
		(width 0.15)
		(layer "B.Cu")
		(net 75)
	)
	(segment
		(start 89.118462 172.6785)
		(end 89.892462 172.6785)
		(width 0.15)
		(layer "B.Cu")
		(net 75)
	)
	(segment
		(start 86.482962 168.9065)
		(end 86.317962 168.9065)
		(width 0.15)
		(layer "B.Cu")
		(net 75)
	)
	(segment
		(start 89.893462 172.6795)
		(end 90.249713 172.6795)
		(width 0.15)
		(layer "B.Cu")
		(net 75)
	)
	(segment
		(start 89.867963 165.326501)
		(end 90.027962 165.4865)
		(width 0.15)
		(layer "B.Cu")
		(net 75)
	)
	(segment
		(start 88.621307 165.326501)
		(end 89.867963 165.326501)
		(width 0.15)
		(layer "B.Cu")
		(net 75)
	)
	(segment
		(start 90.334213 172.764)
		(end 90.745863 172.764)
		(width 0.15)
		(layer "B.Cu")
		(net 75)
	)
	(segment
		(start 90.827962 172.7725)
		(end 90.912962 172.6875)
		(width 0.15)
		(layer "B.Cu")
		(net 75)
	)
	(arc
		(start 87.452822 170.7365)
		(mid 87.594243 170.677921)
		(end 87.652822 170.5365)
		(width 0.15)
		(layer "B.Cu")
		(net 75)
	)
	(arc
		(start 86.932962 169.3565)
		(mid 86.80116 169.038302)
		(end 86.482962 168.9065)
		(width 0.15)
		(layer "B.Cu")
		(net 75)
	)
	(arc
		(start 86.317962 168.9065)
		(mid 86.233109 168.871353)
		(end 86.197962 168.7865)
		(width 0.15)
		(layer "B.Cu")
		(net 75)
	)
	(arc
		(start 87.652822 170.5365)
		(mid 87.594243 170.395079)
		(end 87.452822 170.3365)
		(width 0.15)
		(layer "B.Cu")
		(net 75)
	)
	(arc
		(start 86.197962 168.3565)
		(mid 86.233109 168.271647)
		(end 86.317962 168.2365)
		(width 0.15)
		(layer "B.Cu")
		(net 75)
	)
	(arc
		(start 86.482962 168.2365)
		(mid 86.80116 168.104698)
		(end 86.932962 167.7865)
		(width 0.15)
		(layer "B.Cu")
		(net 75)
	)
	(arc
		(start 87.132962 170.3365)
		(mid 86.991541 170.277921)
		(end 86.932962 170.1365)
		(width 0.15)
		(layer "B.Cu")
		(net 75)
	)
	(arc
		(start 86.932962 170.9365)
		(mid 86.991541 170.795079)
		(end 87.132962 170.7365)
		(width 0.15)
		(layer "B.Cu")
		(net 75)
	)
	(segment
		(start 107.202861 166.27826)
		(end 107.20286 166.278257)
		(width 0.15)
		(layer "F.Cu")
		(net 76)
	)
	(segment
		(start 108.617077 164.864043)
		(end 108.617075 164.864042)
		(width 0.15)
		(layer "F.Cu")
		(net 76)
	)
	(segment
		(start 110.389922 165.696436)
		(end 109.557529 164.864043)
		(width 0.15)
		(layer "F.Cu")
		(net 76)
	)
	(segment
		(start 110.03129 164.39028)
		(end 110.863684 165.222674)
		(width 0.15)
		(layer "F.Cu")
		(net 76)
	)
	(segment
		(start 111.94896 162.117)
		(end 111.91446 162.1515)
		(width 0.15)
		(layer "F.Cu")
		(net 76)
	)
	(segment
		(start 111.329616 162.1515)
		(end 110.03129 163.449828)
		(width 0.15)
		(layer "F.Cu")
		(net 76)
	)
	(segment
		(start 111.91446 162.1515)
		(end 111.329616 162.1515)
		(width 0.15)
		(layer "F.Cu")
		(net 76)
	)
	(segment
		(start 106.72412 166.756996)
		(end 90.190461 166.756996)
		(width 0.15)
		(layer "F.Cu")
		(net 76)
	)
	(segment
		(start 112.473961 162.117)
		(end 111.94896 162.117)
		(width 0.15)
		(layer "F.Cu")
		(net 76)
	)
	(segment
		(start 90.190461 166.756996)
		(end 90.027962 166.594497)
		(width 0.15)
		(layer "F.Cu")
		(net 76)
	)
	(segment
		(start 109.44948 167.110662)
		(end 109.449479 167.110664)
		(width 0.15)
		(layer "F.Cu")
		(net 76)
	)
	(segment
		(start 107.20286 166.278257)
		(end 106.72412 166.756996)
		(width 0.15)
		(layer "F.Cu")
		(net 76)
	)
	(segment
		(start 108.617075 164.864042)
		(end 108.617075 164.864043)
		(width 0.15)
		(layer "F.Cu")
		(net 76)
	)
	(segment
		(start 108.617075 165.804495)
		(end 109.44948 166.6369)
		(width 0.15)
		(layer "F.Cu")
		(net 76)
	)
	(segment
		(start 108.975717 167.110664)
		(end 108.143313 166.27826)
		(width 0.15)
		(layer "F.Cu")
		(net 76)
	)
	(via
		(at 90.027962 166.594497)
		(size 0.45)
		(drill 0.1)
		(layers "F.Cu" "B.Cu")
		(net 76)
	)
	(arc
		(start 109.449479 167.110664)
		(mid 109.212598 167.208783)
		(end 108.975717 167.110664)
		(width 0.15)
		(layer "F.Cu")
		(net 76)
	)
	(arc
		(start 109.557529 164.864043)
		(mid 109.087303 164.669269)
		(end 108.617077 164.864043)
		(width 0.15)
		(layer "F.Cu")
		(net 76)
	)
	(arc
		(start 108.143313 166.27826)
		(mid 107.673087 166.083486)
		(end 107.202861 166.27826)
		(width 0.15)
		(layer "F.Cu")
		(net 76)
	)
	(arc
		(start 108.617075 164.864043)
		(mid 108.422301 165.334269)
		(end 108.617075 165.804495)
		(width 0.15)
		(layer "F.Cu")
		(net 76)
	)
	(arc
		(start 110.863684 165.222674)
		(mid 110.961803 165.459555)
		(end 110.863684 165.696436)
		(width 0.15)
		(layer "F.Cu")
		(net 76)
	)
	(arc
		(start 110.863684 165.696436)
		(mid 110.626803 165.794555)
		(end 110.389922 165.696436)
		(width 0.15)
		(layer "F.Cu")
		(net 76)
	)
	(arc
		(start 109.44948 166.6369)
		(mid 109.547599 166.873781)
		(end 109.44948 167.110662)
		(width 0.15)
		(layer "F.Cu")
		(net 76)
	)
	(arc
		(start 110.03129 163.449828)
		(mid 109.836516 163.920054)
		(end 110.03129 164.39028)
		(width 0.15)
		(layer "F.Cu")
		(net 76)
	)
	(segment
		(start 88.78412 166.756996)
		(end 87.892962 167.648154)
		(width 0.15)
		(layer "B.Cu")
		(net 76)
	)
	(segment
		(start 90.249713 170.1785)
		(end 90.334213 170.094)
		(width 0.15)
		(layer "B.Cu")
		(net 76)
	)
	(segment
		(start 87.892962 167.648154)
		(end 87.892962 169.644846)
		(width 0.15)
		(layer "B.Cu")
		(net 76)
	)
	(segment
		(start 88.341616 170.0935)
		(end 88.677211 170.0935)
		(width 0.15)
		(layer "B.Cu")
		(net 76)
	)
	(segment
		(start 90.027962 166.594497)
		(end 89.865463 166.756996)
		(width 0.15)
		(layer "B.Cu")
		(net 76)
	)
	(segment
		(start 89.118462 170.1785)
		(end 89.893462 170.1785)
		(width 0.15)
		(layer "B.Cu")
		(net 76)
	)
	(segment
		(start 88.762211 170.1785)
		(end 89.118462 170.1785)
		(width 0.15)
		(layer "B.Cu")
		(net 76)
	)
	(segment
		(start 88.677211 170.0935)
		(end 88.762211 170.1785)
		(width 0.15)
		(layer "B.Cu")
		(net 76)
	)
	(segment
		(start 87.892962 169.644846)
		(end 88.341616 170.0935)
		(width 0.15)
		(layer "B.Cu")
		(net 76)
	)
	(segment
		(start 90.573899 170.103)
		(end 90.828462 170.103)
		(width 0.15)
		(layer "B.Cu")
		(net 76)
	)
	(segment
		(start 90.828462 170.103)
		(end 90.912962 170.1875)
		(width 0.15)
		(layer "B.Cu")
		(net 76)
	)
	(segment
		(start 89.865463 166.756996)
		(end 88.78412 166.756996)
		(width 0.15)
		(layer "B.Cu")
		(net 76)
	)
	(segment
		(start 90.564899 170.094)
		(end 90.573899 170.103)
		(width 0.15)
		(layer "B.Cu")
		(net 76)
	)
	(segment
		(start 90.334213 170.094)
		(end 90.564899 170.094)
		(width 0.15)
		(layer "B.Cu")
		(net 76)
	)
	(segment
		(start 89.893462 170.1785)
		(end 90.249713 170.1785)
		(width 0.15)
		(layer "B.Cu")
		(net 76)
	)
	(segment
		(start 65.817962 159.1665)
		(end 61.286962 159.1665)
		(width 0.75)
		(layer "B.Cu")
		(net 77)
	)
	(segment
		(start 67.717962 159.1665)
		(end 65.817962 159.1665)
		(width 0.75)
		(layer "B.Cu")
		(net 77)
	)
	(segment
		(start 54.292962 159.9165)
		(end 56.017962 159.9165)
		(width 0.15)
		(layer "B.Cu")
		(net 77)
	)
	(segment
		(start 56.017962 159.9165)
		(end 56.667962 159.2665)
		(width 0.15)
		(layer "B.Cu")
		(net 77)
	)
	(segment
		(start 56.667962 159.2665)
		(end 61.186962 159.2665)
		(width 1)
		(layer "B.Cu")
		(net 77)
	)
	(segment
		(start 53.327962 159.3915)
		(end 53.767962 159.3915)
		(width 0.15)
		(layer "B.Cu")
		(net 77)
	)
	(segment
		(start 69.217962 159.1665)
		(end 67.717962 159.1665)
		(width 0.6)
		(layer "B.Cu")
		(net 77)
	)
	(segment
		(start 53.767962 159.3915)
		(end 54.292962 159.9165)
		(width 0.15)
		(layer "B.Cu")
		(net 77)
	)
	(via
		(at 114.757962 137.5665)
		(size 0.45)
		(drill 0.1)
		(layers "F.Cu" "B.Cu")
		(net 78)
	)
	(via
		(at 108.942962 133.4915)
		(size 0.45)
		(drill 0.1)
		(layers "F.Cu" "B.Cu")
		(net 78)
	)
	(segment
		(start 113.492962 137.5965)
		(end 113.492962 135.9115)
		(width 0.75)
		(layer "B.Cu")
		(net 78)
	)
	(segment
		(start 116.292962 136.6665)
		(end 116.292962 135.7465)
		(width 0.5)
		(layer "B.Cu")
		(net 78)
	)
	(segment
		(start 114.327962 137.5965)
		(end 114.337962 137.5865)
		(width 0.5)
		(layer "B.Cu")
		(net 78)
	)
	(segment
		(start 115.372962 137.5865)
		(end 116.292962 136.6665)
		(width 0.5)
		(layer "B.Cu")
		(net 78)
	)
	(segment
		(start 113.492962 137.5965)
		(end 114.327962 137.5965)
		(width 0.5)
		(layer "B.Cu")
		(net 78)
	)
	(segment
		(start 114.337962 137.5865)
		(end 115.372962 137.5865)
		(width 0.5)
		(layer "B.Cu")
		(net 78)
	)
	(segment
		(start 116.292962 135.7465)
		(end 117.862962 135.7465)
		(width 0.5)
		(layer "B.Cu")
		(net 78)
	)
	(segment
		(start 108.942962 133.4915)
		(end 108.112962 133.4915)
		(width 0.254)
		(layer "B.Cu")
		(net 78)
	)
	(segment
		(start 116.292962 135.7465)
		(end 113.677962 135.7465)
		(width 0.75)
		(layer "B.Cu")
		(net 78)
	)
	(segment
		(start 108.942962 133.4915)
		(end 110.042962 133.4915)
		(width 0.254)
		(layer "In3.Cu")
		(net 78)
	)
	(segment
		(start 114.117962 137.5665)
		(end 114.757962 137.5665)
		(width 0.254)
		(layer "In3.Cu")
		(net 78)
	)
	(segment
		(start 110.042962 133.4915)
		(end 114.117962 137.5665)
		(width 0.254)
		(layer "In3.Cu")
		(net 78)
	)
	(segment
		(start 59.003962 131.141032)
		(end 59.003962 131.891968)
		(width 0.153)
		(layer "F.Cu")
		(net 79)
	)
	(segment
		(start 60.536071 133.141233)
		(end 60.53607 133.141234)
		(width 0.153)
		(layer "F.Cu")
		(net 79)
	)
	(segment
		(start 71.217494 144.1055)
		(end 76.73061 144.1055)
		(width 0.153)
		(layer "F.Cu")
		(net 79)
	)
	(segment
		(start 59.303494 130.8415)
		(end 59.003962 131.141032)
		(width 0.153)
		(layer "F.Cu")
		(net 79)
	)
	(segment
		(start 60.818912 133.706918)
		(end 71.217494 144.1055)
		(width 0.153)
		(layer "F.Cu")
		(net 79)
	)
	(segment
		(start 61.033136 133.209852)
		(end 61.033137 133.209851)
		(width 0.153)
		(layer "F.Cu")
		(net 79)
	)
	(segment
		(start 59.003962 131.891968)
		(end 60.253228 133.141234)
		(width 0.153)
		(layer "F.Cu")
		(net 79)
	)
	(segment
		(start 61.033137 132.92701)
		(end 61.033137 132.927009)
		(width 0.153)
		(layer "F.Cu")
		(net 79)
	)
	(segment
		(start 61.033137 133.209851)
		(end 60.818913 133.424076)
		(width 0.153)
		(layer "F.Cu")
		(net 79)
	)
	(segment
		(start 60.324512 131.631)
		(end 59.535012 130.8415)
		(width 0.153)
		(layer "F.Cu")
		(net 79)
	)
	(segment
		(start 59.535012 130.8415)
		(end 59.303494 130.8415)
		(width 0.153)
		(layer "F.Cu")
		(net 79)
	)
	(segment
		(start 77.94111 145.316)
		(end 78.473961 145.316)
		(width 0.153)
		(layer "F.Cu")
		(net 79)
	)
	(segment
		(start 60.53607 133.141234)
		(end 60.750295 132.92701)
		(width 0.153)
		(layer "F.Cu")
		(net 79)
	)
	(segment
		(start 60.818913 133.706918)
		(end 60.818912 133.706918)
		(width 0.153)
		(layer "F.Cu")
		(net 79)
	)
	(segment
		(start 76.73061 144.1055)
		(end 77.94111 145.316)
		(width 0.153)
		(layer "F.Cu")
		(net 79)
	)
	(arc
		(start 60.750295 132.92701)
		(mid 60.891715 132.868431)
		(end 61.033137 132.92701)
		(width 0.153)
		(layer "F.Cu")
		(net 79)
	)
	(arc
		(start 60.818913 133.424076)
		(mid 60.760334 133.565496)
		(end 60.818913 133.706918)
		(width 0.153)
		(layer "F.Cu")
		(net 79)
	)
	(arc
		(start 60.253228 133.141234)
		(mid 60.39465 133.199812)
		(end 60.536071 133.141233)
		(width 0.153)
		(layer "F.Cu")
		(net 79)
	)
	(arc
		(start 61.033137 132.927009)
		(mid 61.091715 133.068431)
		(end 61.033136 133.209852)
		(width 0.153)
		(layer "F.Cu")
		(net 79)
	)
	(segment
		(start 80.867462 145.316)
		(end 81.554961 145.316)
		(width 0.153)
		(layer "F.Cu")
		(net 80)
	)
	(segment
		(start 67.781146 135.504684)
		(end 73.131962 140.8555)
		(width 0.153)
		(layer "F.Cu")
		(net 80)
	)
	(segment
		(start 67.781146 135.504685)
		(end 67.781146 135.504684)
		(width 0.153)
		(layer "F.Cu")
		(net 80)
	)
	(segment
		(start 66.792962 130.5415)
		(end 66.792962 132.41111)
		(width 0.153)
		(layer "F.Cu")
		(net 80)
	)
	(segment
		(start 67.944512 130.59305)
		(end 67.767962 130.4165)
		(width 0.153)
		(layer "F.Cu")
		(net 80)
	)
	(segment
		(start 73.131962 140.8555)
		(end 78.206572 140.8555)
		(width 0.153)
		(layer "F.Cu")
		(net 80)
	)
	(segment
		(start 80.753962 145.2025)
		(end 80.867462 145.316)
		(width 0.153)
		(layer "F.Cu")
		(net 80)
	)
	(segment
		(start 67.498305 134.938999)
		(end 67.790844 134.646461)
		(width 0.153)
		(layer "F.Cu")
		(net 80)
	)
	(segment
		(start 65.837962 133.36611)
		(end 65.837962 133.5615)
		(width 0.153)
		(layer "F.Cu")
		(net 80)
	)
	(segment
		(start 68.073685 134.929303)
		(end 67.781147 135.221842)
		(width 0.153)
		(layer "F.Cu")
		(net 80)
	)
	(segment
		(start 66.792962 132.41111)
		(end 65.837962 133.36611)
		(width 0.153)
		(layer "F.Cu")
		(net 80)
	)
	(segment
		(start 67.944512 131.631)
		(end 67.944512 130.59305)
		(width 0.153)
		(layer "F.Cu")
		(net 80)
	)
	(segment
		(start 68.073687 134.64646)
		(end 68.073686 134.64646)
		(width 0.153)
		(layer "F.Cu")
		(net 80)
	)
	(segment
		(start 78.206572 140.8555)
		(end 80.753962 143.40289)
		(width 0.153)
		(layer "F.Cu")
		(net 80)
	)
	(segment
		(start 67.767962 130.4165)
		(end 66.917962 130.4165)
		(width 0.153)
		(locked yes)
		(layer "F.Cu")
		(net 80)
	)
	(segment
		(start 80.753962 143.40289)
		(end 80.753962 145.2025)
		(width 0.153)
		(layer "F.Cu")
		(net 80)
	)
	(segment
		(start 66.917962 130.4165)
		(end 66.792962 130.5415)
		(width 0.153)
		(layer "F.Cu")
		(net 80)
	)
	(segment
		(start 65.837962 133.5615)
		(end 67.215462 134.939)
		(width 0.153)
		(layer "F.Cu")
		(net 80)
	)
	(arc
		(start 67.781147 135.221842)
		(mid 67.722568 135.363263)
		(end 67.781146 135.504685)
		(width 0.153)
		(layer "F.Cu")
		(net 80)
	)
	(arc
		(start 67.790844 134.646461)
		(mid 67.932265 134.587882)
		(end 68.073687 134.64646)
		(width 0.153)
		(layer "F.Cu")
		(net 80)
	)
	(arc
		(start 67.215462 134.939)
		(mid 67.356884 134.997578)
		(end 67.498305 134.938999)
		(width 0.153)
		(layer "F.Cu")
		(net 80)
	)
	(arc
		(start 68.073686 134.64646)
		(mid 68.132264 134.787882)
		(end 68.073685 134.929303)
		(width 0.153)
		(layer "F.Cu")
		(net 80)
	)
	(segment
		(start 71.067962 144.4665)
		(end 58.642962 132.0415)
		(width 0.153)
		(layer "F.Cu")
		(net 81)
	)
	(segment
		(start 78.473961 145.717)
		(end 78.059462 145.717)
		(width 0.153)
		(layer "F.Cu")
		(net 81)
	)
	(segment
		(start 77.815079 145.7005)
		(end 76.581079 144.4665)
		(width 0.153)
		(layer "F.Cu")
		(net 81)
	)
	(segment
		(start 59.054512 130.57995)
		(end 59.054512 129.092)
		(width 0.153)
		(layer "F.Cu")
		(net 81)
	)
	(segment
		(start 78.042962 145.7005)
		(end 77.815079 145.7005)
		(width 0.153)
		(layer "F.Cu")
		(net 81)
	)
	(segment
		(start 58.642962 130.9915)
		(end 59.054512 130.57995)
		(width 0.153)
		(layer "F.Cu")
		(net 81)
	)
	(segment
		(start 76.581079 144.4665)
		(end 71.067962 144.4665)
		(width 0.153)
		(layer "F.Cu")
		(net 81)
	)
	(segment
		(start 78.059462 145.717)
		(end 78.042962 145.7005)
		(width 0.153)
		(layer "F.Cu")
		(net 81)
	)
	(segment
		(start 58.642962 132.0415)
		(end 58.642962 130.9915)
		(width 0.153)
		(layer "F.Cu")
		(net 81)
	)
	(segment
		(start 81.02996 145.717)
		(end 81.554961 145.717)
		(width 0.153)
		(layer "F.Cu")
		(net 82)
	)
	(segment
		(start 65.457962 133.692031)
		(end 72.982431 141.2165)
		(width 0.153)
		(layer "F.Cu")
		(net 82)
	)
	(segment
		(start 81.00996 145.697)
		(end 81.02996 145.717)
		(width 0.153)
		(layer "F.Cu")
		(net 82)
	)
	(segment
		(start 65.457962 133.24689)
		(end 65.457962 133.692031)
		(width 0.153)
		(layer "F.Cu")
		(net 82)
	)
	(segment
		(start 65.12234 129.092)
		(end 66.431962 130.401622)
		(width 0.153)
		(layer "F.Cu")
		(net 82)
	)
	(segment
		(start 66.431962 130.401622)
		(end 66.431962 132.27289)
		(width 0.153)
		(layer "F.Cu")
		(net 82)
	)
	(segment
		(start 80.731082 145.697)
		(end 81.00996 145.697)
		(width 0.153)
		(layer "F.Cu")
		(net 82)
	)
	(segment
		(start 66.431962 132.27289)
		(end 65.457962 133.24689)
		(width 0.153)
		(layer "F.Cu")
		(net 82)
	)
	(segment
		(start 78.068352 141.2165)
		(end 80.392962 143.54111)
		(width 0.153)
		(layer "F.Cu")
		(net 82)
	)
	(segment
		(start 80.392962 145.35888)
		(end 80.731082 145.697)
		(width 0.153)
		(layer "F.Cu")
		(net 82)
	)
	(segment
		(start 80.392962 143.54111)
		(end 80.392962 145.35888)
		(width 0.153)
		(layer "F.Cu")
		(net 82)
	)
	(segment
		(start 64.134512 129.092)
		(end 65.12234 129.092)
		(width 0.153)
		(layer "F.Cu")
		(net 82)
	)
	(segment
		(start 72.982431 141.2165)
		(end 78.068352 141.2165)
		(width 0.153)
		(layer "F.Cu")
		(net 82)
	)
	(segment
		(start 77.332429 142.7915)
		(end 71.982431 142.7915)
		(width 0.153)
		(layer "F.Cu")
		(net 83)
	)
	(segment
		(start 79.017962 146.537)
		(end 79.135744 146.537)
		(width 0.153)
		(layer "F.Cu")
		(net 83)
	)
	(segment
		(start 78.998962 146.518)
		(end 79.017962 146.537)
		(width 0.153)
		(layer "F.Cu")
		(net 83)
	)
	(segment
		(start 78.473961 146.518)
		(end 78.998962 146.518)
		(width 0.153)
		(layer "F.Cu")
		(net 83)
	)
	(segment
		(start 71.982431 142.7915)
		(end 61.467962 132.277031)
		(width 0.153)
		(layer "F.Cu")
		(net 83)
	)
	(segment
		(start 79.242962 146.429782)
		(end 79.242962 144.702033)
		(width 0.153)
		(layer "F.Cu")
		(net 83)
	)
	(segment
		(start 61.467962 132.277031)
		(end 61.467962 130.880968)
		(width 0.153)
		(layer "F.Cu")
		(net 83)
	)
	(segment
		(start 61.467962 130.880968)
		(end 61.593512 130.755419)
		(width 0.153)
		(layer "F.Cu")
		(net 83)
	)
	(segment
		(start 79.135744 146.537)
		(end 79.242962 146.429782)
		(width 0.153)
		(layer "F.Cu")
		(net 83)
	)
	(segment
		(start 79.242962 144.702033)
		(end 77.332429 142.7915)
		(width 0.153)
		(layer "F.Cu")
		(net 83)
	)
	(segment
		(start 61.593512 130.755419)
		(end 61.593512 129.092)
		(width 0.153)
		(layer "F.Cu")
		(net 83)
	)
	(segment
		(start 82.079962 146.518)
		(end 82.102962 146.541)
		(width 0.153)
		(layer "F.Cu")
		(net 84)
	)
	(segment
		(start 71.142696 135.639393)
		(end 71.489239 135.292849)
		(width 0.153)
		(layer "F.Cu")
		(net 84)
	)
	(segment
		(start 69.106962 134.566032)
		(end 69.106962 130.9165)
		(width 0.153)
		(layer "F.Cu")
		(net 84)
	)
	(segment
		(start 71.037398 134.841006)
		(end 70.690853 135.18755)
		(width 0.153)
		(layer "F.Cu")
		(net 84)
	)
	(segment
		(start 82.492962 146.2785)
		(end 82.492962 143.402032)
		(width 0.153)
		(layer "F.Cu")
		(net 84)
	)
	(segment
		(start 74.207431 139.6665)
		(end 71.142696 136.601765)
		(width 0.153)
		(layer "F.Cu")
		(net 84)
	)
	(segment
		(start 82.172696 143.081766)
		(end 82.008176 143.081766)
		(width 0.153)
		(layer "F.Cu")
		(net 84)
	)
	(segment
		(start 69.72848 135.187551)
		(end 69.106962 134.566032)
		(width 0.153)
		(layer "F.Cu")
		(net 84)
	)
	(segment
		(start 71.48924 134.841008)
		(end 71.489239 134.841007)
		(width 0.153)
		(layer "F.Cu")
		(net 84)
	)
	(segment
		(start 82.102962 146.541)
		(end 82.230462 146.541)
		(width 0.153)
		(layer "F.Cu")
		(net 84)
	)
	(segment
		(start 69.214512 130.80895)
		(end 69.214512 129.092)
		(width 0.153)
		(layer "F.Cu")
		(net 84)
	)
	(segment
		(start 81.554961 146.518)
		(end 82.079962 146.518)
		(width 0.153)
		(layer "F.Cu")
		(net 84)
	)
	(segment
		(start 81.807592 142.881182)
		(end 81.807591 142.716662)
		(width 0.153)
		(layer "F.Cu")
		(net 84)
	)
	(segment
		(start 82.492962 143.402032)
		(end 82.172696 143.081766)
		(width 0.153)
		(layer "F.Cu")
		(net 84)
	)
	(segment
		(start 69.106962 130.9165)
		(end 69.214512 130.80895)
		(width 0.153)
		(layer "F.Cu")
		(net 84)
	)
	(segment
		(start 82.230462 146.541)
		(end 82.492962 146.2785)
		(width 0.153)
		(layer "F.Cu")
		(net 84)
	)
	(segment
		(start 81.807591 142.716662)
		(end 78.75743 139.6665)
		(width 0.153)
		(layer "F.Cu")
		(net 84)
	)
	(segment
		(start 82.008176 143.081766)
		(end 81.807592 142.881182)
		(width 0.153)
		(layer "F.Cu")
		(net 84)
	)
	(segment
		(start 78.75743 139.6665)
		(end 74.207431 139.6665)
		(width 0.153)
		(layer "F.Cu")
		(net 84)
	)
	(arc
		(start 70.690853 135.18755)
		(mid 70.209667 135.386864)
		(end 69.72848 135.187551)
		(width 0.153)
		(layer "F.Cu")
		(net 84)
	)
	(arc
		(start 71.142696 136.601765)
		(mid 70.943362 136.120585)
		(end 71.142696 135.639393)
		(width 0.153)
		(layer "F.Cu")
		(net 84)
	)
	(arc
		(start 71.489239 135.292849)
		(mid 71.582819 135.066929)
		(end 71.48924 134.841008)
		(width 0.153)
		(layer "F.Cu")
		(net 84)
	)
	(arc
		(start 71.489239 134.841007)
		(mid 71.263319 134.747427)
		(end 71.037398 134.841006)
		(width 0.153)
		(layer "F.Cu")
		(net 84)
	)
	(segment
		(start 61.926962 130.9325)
		(end 61.828962 131.0305)
		(width 0.153)
		(layer "F.Cu")
		(net 85)
	)
	(segment
		(start 77.48196 142.4305)
		(end 79.603962 144.552501)
		(width 0.153)
		(layer "F.Cu")
		(net 85)
	)
	(segment
		(start 79.192962 146.898)
		(end 79.011962 146.898)
		(width 0.15)
		(layer "F.Cu")
		(net 85)
	)
	(segment
		(start 79.603962 144.552501)
		(end 79.603962 146.579314)
		(width 0.153)
		(layer "F.Cu")
		(net 85)
	)
	(segment
		(start 61.828962 132.1275)
		(end 72.131962 142.4305)
		(width 0.153)
		(layer "F.Cu")
		(net 85)
	)
	(segment
		(start 61.828962 131.0305)
		(end 61.828962 132.1275)
		(width 0.153)
		(layer "F.Cu")
		(net 85)
	)
	(segment
		(start 79.011962 146.898)
		(end 78.992962 146.917)
		(width 0.15)
		(layer "F.Cu")
		(net 85)
	)
	(segment
		(start 62.865512 131.631)
		(end 62.167012 130.9325)
		(width 0.153)
		(layer "F.Cu")
		(net 85)
	)
	(segment
		(start 79.285275 146.898)
		(end 79.192962 146.898)
		(width 0.153)
		(layer "F.Cu")
		(net 85)
	)
	(segment
		(start 79.603962 146.579314)
		(end 79.285275 146.898)
		(width 0.153)
		(layer "F.Cu")
		(net 85)
	)
	(segment
		(start 62.167012 130.9325)
		(end 61.926962 130.9325)
		(width 0.153)
		(layer "F.Cu")
		(net 85)
	)
	(segment
		(start 78.992962 146.917)
		(end 78.473961 146.917)
		(width 0.153)
		(layer "F.Cu")
		(net 85)
	)
	(segment
		(start 72.131962 142.4305)
		(end 77.48196 142.4305)
		(width 0.153)
		(layer "F.Cu")
		(net 85)
	)
	(segment
		(start 111.466308 162.4815)
		(end 110.264635 163.683173)
		(width 0.15)
		(layer "F.Cu")
		(net 86)
	)
	(segment
		(start 110.264635 164.156935)
		(end 111.097029 164.989329)
		(width 0.15)
		(layer "F.Cu")
		(net 86)
	)
	(segment
		(start 106.86081 167.086998)
		(end 90.190461 167.086998)
		(width 0.15)
		(layer "F.Cu")
		(net 86)
	)
	(segment
		(start 108.850423 165.097389)
		(end 108.85042 165.097388)
		(width 0.15)
		(layer "F.Cu")
		(net 86)
	)
	(segment
		(start 109.682825 167.344007)
		(end 109.682824 167.344009)
		(width 0.15)
		(layer "F.Cu")
		(net 86)
	)
	(segment
		(start 108.850421 165.09739)
		(end 108.850423 165.097389)
		(width 0.15)
		(layer "F.Cu")
		(net 86)
	)
	(segment
		(start 111.91446 162.4815)
		(end 111.466308 162.4815)
		(width 0.15)
		(layer "F.Cu")
		(net 86)
	)
	(segment
		(start 111.097029 165.929781)
		(end 111.097028 165.929783)
		(width 0.15)
		(layer "F.Cu")
		(net 86)
	)
	(segment
		(start 112.473961 162.516)
		(end 111.94896 162.516)
		(width 0.15)
		(layer "F.Cu")
		(net 86)
	)
	(segment
		(start 110.156576 165.929783)
		(end 109.324183 165.09739)
		(width 0.15)
		(layer "F.Cu")
		(net 86)
	)
	(segment
		(start 111.94896 162.516)
		(end 111.91446 162.4815)
		(width 0.15)
		(layer "F.Cu")
		(net 86)
	)
	(segment
		(start 108.85042 165.57115)
		(end 109.682825 166.403555)
		(width 0.15)
		(layer "F.Cu")
		(net 86)
	)
	(segment
		(start 107.436206 166.511603)
		(end 106.86081 167.086998)
		(width 0.15)
		(layer "F.Cu")
		(net 86)
	)
	(segment
		(start 90.190461 167.086998)
		(end 90.027962 167.249497)
		(width 0.15)
		(layer "F.Cu")
		(net 86)
	)
	(segment
		(start 108.742372 167.344009)
		(end 107.909968 166.511605)
		(width 0.15)
		(layer "F.Cu")
		(net 86)
	)
	(segment
		(start 107.436206 166.511605)
		(end 107.436206 166.511603)
		(width 0.15)
		(layer "F.Cu")
		(net 86)
	)
	(via
		(at 90.027962 167.249497)
		(size 0.45)
		(drill 0.1)
		(layers "F.Cu" "B.Cu")
		(net 86)
	)
	(arc
		(start 109.324183 165.09739)
		(mid 109.087302 164.999271)
		(end 108.850421 165.09739)
		(width 0.15)
		(layer "F.Cu")
		(net 86)
	)
	(arc
		(start 110.264635 163.683173)
		(mid 110.166516 163.920054)
		(end 110.264635 164.156935)
		(width 0.15)
		(layer "F.Cu")
		(net 86)
	)
	(arc
		(start 111.097029 164.989329)
		(mid 111.291803 165.459555)
		(end 111.097029 165.929781)
		(width 0.15)
		(layer "F.Cu")
		(net 86)
	)
	(arc
		(start 107.909968 166.511605)
		(mid 107.673087 166.413486)
		(end 107.436206 166.511605)
		(width 0.15)
		(layer "F.Cu")
		(net 86)
	)
	(arc
		(start 108.85042 165.097388)
		(mid 108.752301 165.334269)
		(end 108.85042 165.57115)
		(width 0.15)
		(layer "F.Cu")
		(net 86)
	)
	(arc
		(start 111.097028 165.929783)
		(mid 110.626802 166.124557)
		(end 110.156576 165.929783)
		(width 0.15)
		(layer "F.Cu")
		(net 86)
	)
	(arc
		(start 109.682825 166.403555)
		(mid 109.877599 166.873781)
		(end 109.682825 167.344007)
		(width 0.15)
		(layer "F.Cu")
		(net 86)
	)
	(arc
		(start 109.682824 167.344009)
		(mid 109.212598 167.538783)
		(end 108.742372 167.344009)
		(width 0.15)
		(layer "F.Cu")
		(net 86)
	)
	(segment
		(start 90.691183 169.764)
		(end 90.700183 169.773)
		(width 0.15)
		(layer "B.Cu")
		(net 86)
	)
	(segment
		(start 89.118462 169.6785)
		(end 89.892462 169.6785)
		(width 0.15)
		(layer "B.Cu")
		(net 86)
	)
	(segment
		(start 88.422962 168.3865)
		(end 88.469913 168.3865)
		(width 0.15)
		(layer "B.Cu")
		(net 86)
	)
	(segment
		(start 90.828462 169.773)
		(end 90.912962 169.6885)
		(width 0.15)
		(layer "B.Cu")
		(net 86)
	)
	(segment
		(start 88.422962 169.1865)
		(end 88.469903 169.1865)
		(width 0.15)
		(layer "B.Cu")
		(net 86)
	)
	(segment
		(start 88.222962 167.784846)
		(end 88.92081 167.086998)
		(width 0.15)
		(layer "B.Cu")
		(net 86)
	)
	(segment
		(start 88.92081 167.086998)
		(end 89.865463 167.086998)
		(width 0.15)
		(layer "B.Cu")
		(net 86)
	)
	(segment
		(start 89.893462 169.6795)
		(end 90.249713 169.6795)
		(width 0.15)
		(layer "B.Cu")
		(net 86)
	)
	(segment
		(start 90.334213 169.764)
		(end 90.691183 169.764)
		(width 0.15)
		(layer "B.Cu")
		(net 86)
	)
	(segment
		(start 88.677211 169.7635)
		(end 88.478308 169.7635)
		(width 0.15)
		(layer "B.Cu")
		(net 86)
	)
	(segment
		(start 90.700183 169.773)
		(end 90.828462 169.773)
		(width 0.15)
		(layer "B.Cu")
		(net 86)
	)
	(segment
		(start 89.865463 167.086998)
		(end 90.027962 167.249497)
		(width 0.15)
		(layer "B.Cu")
		(net 86)
	)
	(segment
		(start 88.478308 169.7635)
		(end 88.222962 169.508154)
		(width 0.15)
		(layer "B.Cu")
		(net 86)
	)
	(segment
		(start 88.762211 169.6785)
		(end 88.677211 169.7635)
		(width 0.15)
		(layer "B.Cu")
		(net 86)
	)
	(segment
		(start 88.469913 167.9865)
		(end 88.422962 167.9865)
		(width 0.15)
		(layer "B.Cu")
		(net 86)
	)
	(segment
		(start 89.118462 169.6785)
		(end 88.762211 169.6785)
		(width 0.15)
		(layer "B.Cu")
		(net 86)
	)
	(segment
		(start 88.469903 168.7865)
		(end 88.422962 168.7865)
		(width 0.15)
		(layer "B.Cu")
		(net 86)
	)
	(segment
		(start 88.222962 169.508154)
		(end 88.222962 169.3865)
		(width 0.15)
		(layer "B.Cu")
		(net 86)
	)
	(segment
		(start 88.222962 167.7865)
		(end 88.222962 167.784846)
		(width 0.15)
		(layer "B.Cu")
		(net 86)
	)
	(segment
		(start 90.249713 169.6795)
		(end 90.334213 169.764)
		(width 0.15)
		(layer "B.Cu")
		(net 86)
	)
	(arc
		(start 88.222962 168.5865)
		(mid 88.281541 168.445079)
		(end 88.422962 168.3865)
		(width 0.15)
		(layer "B.Cu")
		(net 86)
	)
	(arc
		(start 88.669903 168.9865)
		(mid 88.611324 168.845079)
		(end 88.469903 168.7865)
		(width 0.15)
		(layer "B.Cu")
		(net 86)
	)
	(arc
		(start 88.469903 169.1865)
		(mid 88.611324 169.127921)
		(end 88.669903 168.9865)
		(width 0.15)
		(layer "B.Cu")
		(net 86)
	)
	(arc
		(start 88.422962 167.9865)
		(mid 88.281541 167.927921)
		(end 88.222962 167.7865)
		(width 0.15)
		(layer "B.Cu")
		(net 86)
	)
	(arc
		(start 88.469913 168.3865)
		(mid 88.611334 168.327921)
		(end 88.669913 168.1865)
		(width 0.15)
		(layer "B.Cu")
		(net 86)
	)
	(arc
		(start 88.222962 169.3865)
		(mid 88.281541 169.245079)
		(end 88.422962 169.1865)
		(width 0.15)
		(layer "B.Cu")
		(net 86)
	)
	(arc
		(start 88.669913 168.1865)
		(mid 88.611334 168.045079)
		(end 88.469913 167.9865)
		(width 0.15)
		(layer "B.Cu")
		(net 86)
	)
	(arc
		(start 88.422962 168.7865)
		(mid 88.281541 168.727921)
		(end 88.222962 168.5865)
		(width 0.15)
		(layer "B.Cu")
		(net 86)
	)
	(segment
		(start 88.280461 174.604001)
		(end 90.314179 174.604001)
		(width 0.15)
		(layer "F.Cu")
		(net 87)
	)
	(segment
		(start 88.117962 174.7665)
		(end 88.280461 174.604001)
		(width 0.15)
		(layer "F.Cu")
		(net 87)
	)
	(segment
		(start 113.375808 163.351)
		(end 113.033962 163.351)
		(width 0.15)
		(layer "F.Cu")
		(net 87)
	)
	(segment
		(start 114.042962 164.018154)
		(end 113.375808 163.351)
		(width 0.15)
		(layer "F.Cu")
		(net 87)
	)
	(segment
		(start 107.489635 171.067721)
		(end 106.743082 170.321168)
		(width 0.15)
		(layer "F.Cu")
		(net 87)
	)
	(segment
		(start 108.903851 170.593961)
		(end 108.90385 170.593959)
		(width 0.15)
		(layer "F.Cu")
		(net 87)
	)
	(segment
		(start 106.743083 169.847406)
		(end 106.743083 169.847407)
		(width 0.15)
		(layer "F.Cu")
		(net 87)
	)
	(segment
		(start 113.033962 163.351)
		(end 112.998962 163.316)
		(width 0.15)
		(layer "F.Cu")
		(net 87)
	)
	(segment
		(start 106.743082 169.847406)
		(end 106.743083 169.847406)
		(width 0.15)
		(layer "F.Cu")
		(net 87)
	)
	(segment
		(start 90.314179 174.604001)
		(end 90.321678 174.6115)
		(width 0.15)
		(layer "F.Cu")
		(net 87)
	)
	(segment
		(start 112.998962 163.316)
		(end 112.473961 163.316)
		(width 0.15)
		(layer "F.Cu")
		(net 87)
	)
	(segment
		(start 104.886308 174.6115)
		(end 107.489635 172.008173)
		(width 0.15)
		(layer "F.Cu")
		(net 87)
	)
	(segment
		(start 108.90385 170.593959)
		(end 114.042962 165.454846)
		(width 0.15)
		(layer "F.Cu")
		(net 87)
	)
	(segment
		(start 107.216845 169.847407)
		(end 107.963399 170.593961)
		(width 0.15)
		(layer "F.Cu")
		(net 87)
	)
	(segment
		(start 114.042962 165.454846)
		(end 114.042962 164.018154)
		(width 0.15)
		(layer "F.Cu")
		(net 87)
	)
	(segment
		(start 90.321678 174.6115)
		(end 104.886308 174.6115)
		(width 0.15)
		(layer "F.Cu")
		(net 87)
	)
	(via
		(at 88.117962 174.7665)
		(size 0.45)
		(drill 0.1)
		(layers "F.Cu" "B.Cu")
		(net 87)
	)
	(arc
		(start 107.963399 170.593961)
		(mid 108.433625 170.788735)
		(end 108.903851 170.593961)
		(width 0.15)
		(layer "F.Cu")
		(net 87)
	)
	(arc
		(start 106.743083 169.847407)
		(mid 106.979964 169.749288)
		(end 107.216845 169.847407)
		(width 0.15)
		(layer "F.Cu")
		(net 87)
	)
	(arc
		(start 106.743082 170.321168)
		(mid 106.644963 170.084287)
		(end 106.743082 169.847406)
		(width 0.15)
		(layer "F.Cu")
		(net 87)
	)
	(arc
		(start 107.489635 172.008173)
		(mid 107.684409 171.537947)
		(end 107.489635 171.067721)
		(width 0.15)
		(layer "F.Cu")
		(net 87)
	)
	(segment
		(start 88.280461 174.604001)
		(end 88.117962 174.7665)
		(width 0.15)
		(layer "B.Cu")
		(net 87)
	)
	(segment
		(start 89.893462 174.6915)
		(end 89.118462 174.6915)
		(width 0.15)
		(layer "B.Cu")
		(net 87)
	)
	(segment
		(start 88.677211 174.6065)
		(end 88.331678 174.6065)
		(width 0.15)
		(layer "B.Cu")
		(net 87)
	)
	(segment
		(start 88.329179 174.604001)
		(end 88.280461 174.604001)
		(width 0.15)
		(layer "B.Cu")
		(net 87)
	)
	(segment
		(start 90.827962 174.6025)
		(end 90.912962 174.6875)
		(width 0.15)
		(layer "B.Cu")
		(net 87)
	)
	(segment
		(start 90.334713 174.6065)
		(end 90.77625 174.6065)
		(width 0.15)
		(layer "B.Cu")
		(net 87)
	)
	(segment
		(start 90.78025 174.6025)
		(end 90.827962 174.6025)
		(width 0.15)
		(layer "B.Cu")
		(net 87)
	)
	(segment
		(start 90.77625 174.6065)
		(end 90.78025 174.6025)
		(width 0.15)
		(layer "B.Cu")
		(net 87)
	)
	(segment
		(start 89.118462 174.6915)
		(end 88.762211 174.6915)
		(width 0.15)
		(layer "B.Cu")
		(net 87)
	)
	(segment
		(start 90.249713 174.6915)
		(end 90.334713 174.6065)
		(width 0.15)
		(layer "B.Cu")
		(net 87)
	)
	(segment
		(start 88.762211 174.6915)
		(end 88.677211 174.6065)
		(width 0.15)
		(layer "B.Cu")
		(net 87)
	)
	(segment
		(start 88.331678 174.6065)
		(end 88.329179 174.604001)
		(width 0.15)
		(layer "B.Cu")
		(net 87)
	)
	(segment
		(start 89.893462 174.6915)
		(end 90.249713 174.6915)
		(width 0.15)
		(layer "B.Cu")
		(net 87)
	)
	(segment
		(start 71.744505 134.585741)
		(end 71.744504 134.585741)
		(width 0.153)
		(layer "F.Cu")
		(net 88)
	)
	(segment
		(start 69.577488 133.426975)
		(end 69.577487 133.426975)
		(width 0.153)
		(layer "F.Cu")
		(net 88)
	)
	(segment
		(start 82.853962 146.428032)
		(end 82.387994 146.894)
		(width 0.153)
		(layer "F.Cu")
		(net 88)
	)
	(segment
		(start 69.687013 133.71745)
		(end 69.687013 133.5365)
		(width 0.153)
		(layer "F.Cu")
		(net 88)
	)
	(segment
		(start 69.983746 134.932285)
		(end 69.467962 134.4165)
		(width 0.153)
		(layer "F.Cu")
		(net 88)
	)
	(segment
		(start 82.853962 143.2525)
		(end 78.905462 139.304)
		(width 0.153)
		(layer "F.Cu")
		(net 88)
	)
	(segment
		(start 69.467962 134.4165)
		(end 69.467962 133.9365)
		(width 0.153)
		(layer "F.Cu")
		(net 88)
	)
	(segment
		(start 70.167962 130.7665)
		(end 70.483512 131.08205)
		(width 0.153)
		(layer "F.Cu")
		(net 88)
	)
	(segment
		(start 82.102962 146.894)
		(end 82.079962 146.917)
		(width 0.153)
		(layer "F.Cu")
		(net 88)
	)
	(segment
		(start 70.782131 134.58574)
		(end 70.782131 134.585741)
		(width 0.153)
		(layer "F.Cu")
		(net 88)
	)
	(segment
		(start 70.782131 134.585741)
		(end 70.435587 134.932284)
		(width 0.153)
		(layer "F.Cu")
		(net 88)
	)
	(segment
		(start 78.905462 139.304)
		(end 74.355462 139.304)
		(width 0.153)
		(layer "F.Cu")
		(net 88)
	)
	(segment
		(start 69.767962 130.7665)
		(end 70.167962 130.7665)
		(width 0.153)
		(layer "F.Cu")
		(net 88)
	)
	(segment
		(start 69.467962 131.0665)
		(end 69.767962 130.7665)
		(width 0.153)
		(layer "F.Cu")
		(net 88)
	)
	(segment
		(start 82.079962 146.917)
		(end 81.554961 146.917)
		(width 0.153)
		(layer "F.Cu")
		(net 88)
	)
	(segment
		(start 69.577487 133.826975)
		(end 69.577488 133.826975)
		(width 0.153)
		(layer "F.Cu")
		(net 88)
	)
	(segment
		(start 69.467962 133.31745)
		(end 69.467962 131.0665)
		(width 0.153)
		(layer "F.Cu")
		(net 88)
	)
	(segment
		(start 82.387994 146.894)
		(end 82.102962 146.894)
		(width 0.153)
		(layer "F.Cu")
		(net 88)
	)
	(segment
		(start 82.853962 146.428032)
		(end 82.853962 143.2525)
		(width 0.153)
		(layer "F.Cu")
		(net 88)
	)
	(segment
		(start 71.397961 135.894658)
		(end 71.744504 135.548114)
		(width 0.153)
		(layer "F.Cu")
		(net 88)
	)
	(segment
		(start 74.355462 139.304)
		(end 71.397961 136.3465)
		(width 0.153)
		(locked yes)
		(layer "F.Cu")
		(net 88)
	)
	(arc
		(start 70.435587 134.932284)
		(mid 70.209667 135.025864)
		(end 69.983746 134.932285)
		(width 0.153)
		(layer "F.Cu")
		(net 88)
	)
	(arc
		(start 69.467962 133.9365)
		(mid 69.500041 133.859054)
		(end 69.577487 133.826975)
		(width 0.153)
		(layer "F.Cu")
		(net 88)
	)
	(arc
		(start 69.577488 133.826975)
		(mid 69.654934 133.794896)
		(end 69.687013 133.71745)
		(width 0.153)
		(layer "F.Cu")
		(net 88)
	)
	(arc
		(start 69.687013 133.5365)
		(mid 69.654934 133.459054)
		(end 69.577488 133.426975)
		(width 0.153)
		(layer "F.Cu")
		(net 88)
	)
	(arc
		(start 69.577487 133.426975)
		(mid 69.500041 133.394896)
		(end 69.467962 133.31745)
		(width 0.153)
		(layer "F.Cu")
		(net 88)
	)
	(arc
		(start 71.744504 135.548114)
		(mid 71.943818 135.066928)
		(end 71.744505 134.585741)
		(width 0.153)
		(layer "F.Cu")
		(net 88)
	)
	(arc
		(start 71.397961 136.3465)
		(mid 71.304381 136.120579)
		(end 71.397961 135.894658)
		(width 0.153)
		(layer "F.Cu")
		(net 88)
	)
	(arc
		(start 71.744504 134.585741)
		(mid 71.263318 134.386427)
		(end 70.782131 134.58574)
		(width 0.153)
		(layer "F.Cu")
		(net 88)
	)
	(segment
		(start 69.192962 167.7665)
		(end 69.192962 164.1165)
		(width 0.254)
		(layer "F.Cu")
		(net 89)
	)
	(segment
		(start 69.192962 164.1165)
		(end 66.987962 161.9115)
		(width 0.254)
		(layer "F.Cu")
		(net 89)
	)
	(segment
		(start 66.987962 161.9115)
		(end 66.987962 161.1865)
		(width 0.254)
		(layer "F.Cu")
		(net 89)
	)
	(via
		(at 66.977962 161.1765)
		(size 0.45)
		(drill 0.1)
		(layers "F.Cu" "B.Cu")
		(net 89)
	)
	(via
		(at 69.192962 167.7665)
		(size 0.45)
		(drill 0.1)
		(layers "F.Cu" "B.Cu")
		(net 89)
	)
	(segment
		(start 69.192962 166.2065)
		(end 69.192962 167.7665)
		(width 0.75)
		(layer "B.Cu")
		(net 89)
	)
	(segment
		(start 69.512962 165.8865)
		(end 72.112962 165.8865)
		(width 0.75)
		(layer "B.Cu")
		(net 89)
	)
	(segment
		(start 69.512962 165.8865)
		(end 69.192962 166.2065)
		(width 0.75)
		(layer "B.Cu")
		(net 89)
	)
	(segment
		(start 66.207962 161.1865)
		(end 66.987962 161.1865)
		(width 0.254)
		(layer "B.Cu")
		(net 89)
	)
	(segment
		(start 72.117962 165.8915)
		(end 73.617962 165.8915)
		(width 0.6)
		(layer "B.Cu")
		(net 89)
	)
	(segment
		(start 48.277962 129.0765)
		(end 48.177962 129.0765)
		(width 0.254)
		(layer "F.Cu")
		(net 90)
	)
	(segment
		(start 46.607962 128.7265)
		(end 46.607962 128.6765)
		(width 0.254)
		(layer "F.Cu")
		(net 90)
	)
	(segment
		(start 49.911962 130.7665)
		(end 50.561962 131.4165)
		(width 0.254)
		(layer "F.Cu")
		(net 90)
	)
	(segment
		(start 46.057962 132.8315)
		(end 46.057962 129.7915)
		(width 0.254)
		(layer "F.Cu")
		(net 90)
	)
	(segment
		(start 49.261962 129.0895)
		(end 49.261962 130.0855)
		(width 0.254)
		(layer "F.Cu")
		(net 90)
	)
	(segment
		(start 48.290962 129.0895)
		(end 48.277962 129.0765)
		(width 0.254)
		(layer "F.Cu")
		(net 90)
	)
	(segment
		(start 47.767962 127.5165)
		(end 48.457962 127.5165)
		(width 0.254)
		(layer "F.Cu")
		(net 90)
	)
	(segment
		(start 49.911962 129.0895)
		(end 49.911962 127.4805)
		(width 0.254)
		(layer "F.Cu")
		(net 90)
	)
	(segment
		(start 49.261962 129.0895)
		(end 48.290962 129.0895)
		(width 0.254)
		(layer "F.Cu")
		(net 90)
	)
	(segment
		(start 46.557962 128.7265)
		(end 46.607962 128.7265)
		(width 0.254)
		(layer "F.Cu")
		(net 90)
	)
	(segment
		(start 48.177962 129.0765)
		(end 48.177962 128.9765)
		(width 0.254)
		(layer "F.Cu")
		(net 90)
	)
	(segment
		(start 49.861962 126.0665)
		(end 49.861962 127.4305)
		(width 0.5)
		(layer "F.Cu")
		(net 90)
	)
	(segment
		(start 49.911962 129.0895)
		(end 49.911962 130.7665)
		(width 0.254)
		(layer "F.Cu")
		(net 90)
	)
	(segment
		(start 49.261962 128.0425)
		(end 49.867962 127.4365)
		(width 0.254)
		(layer "F.Cu")
		(net 90)
	)
	(segment
		(start 49.261962 130.0855)
		(end 49.892962 130.7165)
		(width 0.254)
		(layer "F.Cu")
		(net 90)
	)
	(segment
		(start 49.827962 127.4765)
		(end 48.497962 127.4765)
		(width 0.254)
		(layer "F.Cu")
		(net 90)
	)
	(segment
		(start 46.057962 129.7915)
		(end 46.057962 129.2265)
		(width 0.254)
		(layer "F.Cu")
		(net 90)
	)
	(segment
		(start 46.607962 128.6765)
		(end 47.767962 127.5165)
		(width 0.254)
		(layer "F.Cu")
		(net 90)
	)
	(segment
		(start 49.861962 125.2405)
		(end 49.861962 126.0665)
		(width 0.254)
		(layer "F.Cu")
		(net 90)
	)
	(segment
		(start 48.457962 127.5165)
		(end 48.497962 127.4765)
		(width 0.254)
		(layer "F.Cu")
		(net 90)
	)
	(segment
		(start 49.261962 129.0895)
		(end 49.261962 128.0425)
		(width 0.254)
		(layer "F.Cu")
		(net 90)
	)
	(segment
		(start 48.177962 128.9765)
		(end 48.277962 129.0765)
		(width 0.254)
		(layer "F.Cu")
		(net 90)
	)
	(segment
		(start 49.867962 127.4365)
		(end 49.827962 127.4765)
		(width 0.254)
		(layer "F.Cu")
		(net 90)
	)
	(segment
		(start 46.057962 129.2265)
		(end 46.557962 128.7265)
		(width 0.254)
		(layer "F.Cu")
		(net 90)
	)
	(via
		(at 48.747962 126.7365)
		(size 0.45)
		(drill 0.1)
		(layers "F.Cu" "B.Cu")
		(net 90)
	)
	(via
		(at 51.292962 132.1165)
		(size 0.45)
		(drill 0.1)
		(layers "F.Cu" "B.Cu")
		(net 90)
	)
	(via
		(at 48.497962 127.4765)
		(size 0.45)
		(drill 0.1)
		(layers "F.Cu" "B.Cu")
		(net 90)
	)
	(via
		(at 46.042962 133.5665)
		(size 0.45)
		(drill 0.1)
		(layers "F.Cu" "B.Cu")
		(net 90)
	)
	(via
		(at 49.892962 132.1165)
		(size 0.45)
		(drill 0.1)
		(layers "F.Cu" "B.Cu")
		(net 90)
	)
	(via
		(at 50.592962 131.4165)
		(size 0.45)
		(drill 0.1)
		(layers "F.Cu" "B.Cu")
		(net 90)
	)
	(via
		(at 49.892962 131.4165)
		(size 0.45)
		(drill 0.1)
		(layers "F.Cu" "B.Cu")
		(net 90)
	)
	(via
		(at 52.317962 126.0165)
		(size 0.45)
		(drill 0.1)
		(layers "F.Cu" "B.Cu")
		(free yes)
		(net 90)
	)
	(via
		(at 50.592962 130.7165)
		(size 0.45)
		(drill 0.1)
		(layers "F.Cu" "B.Cu")
		(net 90)
	)
	(via
		(at 48.177962 129.0765)
		(size 0.45)
		(drill 0.1)
		(layers "F.Cu" "B.Cu")
		(net 90)
	)
	(via
		(at 51.292962 130.7165)
		(size 0.45)
		(drill 0.1)
		(layers "F.Cu" "B.Cu")
		(net 90)
	)
	(via
		(at 49.892962 130.7165)
		(size 0.45)
		(drill 0.1)
		(layers "F.Cu" "B.Cu")
		(net 90)
	)
	(via
		(at 51.292962 131.4165)
		(size 0.45)
		(drill 0.1)
		(layers "F.Cu" "B.Cu")
		(net 90)
	)
	(via
		(at 49.877962 124.2665)
		(size 0.45)
		(drill 0.1)
		(layers "F.Cu" "B.Cu")
		(free yes)
		(net 90)
	)
	(via
		(at 49.861962 126.0665)
		(size 0.45)
		(drill 0.1)
		(layers "F.Cu" "B.Cu")
		(net 90)
	)
	(via
		(at 50.592962 132.1165)
		(size 0.45)
		(drill 0.1)
		(layers "F.Cu" "B.Cu")
		(net 90)
	)
	(via
		(at 46.607962 128.7265)
		(size 0.45)
		(drill 0.1)
		(layers "F.Cu" "B.Cu")
		(net 90)
	)
	(segment
		(start 53.392962 124.2015)
		(end 53.392962 116.0915)
		(width 0.5)
		(layer "B.Cu")
		(net 90)
	)
	(segment
		(start 56.638962 113.8915)
		(end 58.354962 113.8915)
		(width 0.5)
		(layer "B.Cu")
		(net 90)
	)
	(segment
		(start 55.690962 113.7935)
		(end 56.767962 113.7935)
		(width 0.5)
		(layer "B.Cu")
		(net 90)
	)
	(segment
		(start 51.527962 126.0665)
		(end 53.392962 124.2015)
		(width 0.5)
		(layer "B.Cu")
		(net 90)
	)
	(segment
		(start 49.861962 126.0665)
		(end 51.527962 126.0665)
		(width 0.5)
		(layer "B.Cu")
		(net 90)
	)
	(segment
		(start 53.392962 116.0915)
		(end 55.690962 113.7935)
		(width 0.5)
		(layer "B.Cu")
		(net 90)
	)
	(segment
		(start 66.674512 129.092)
		(end 66.674512 130.362)
		(width 0.2)
		(layer "B.Cu")
		(net 91)
	)
	(segment
		(start 65.933962 132.15945)
		(end 65.933962 133.9165)
		(width 0.2)
		(layer "B.Cu")
		(net 91)
	)
	(segment
		(start 65.405512 131.631)
		(end 65.933962 132.15945)
		(width 0.2)
		(layer "B.Cu")
		(net 91)
	)
	(segment
		(start 66.674512 130.362)
		(end 65.405512 131.631)
		(width 0.2)
		(layer "B.Cu")
		(net 91)
	)
	(segment
		(start 72.426962 129.9365)
		(end 72.426962 128.9705)
		(width 0.254)
		(layer "B.Cu")
		(net 92)
	)
	(segment
		(start 72.412962 128.9565)
		(end 72.412962 125.98755)
		(width 0.254)
		(layer "B.Cu")
		(net 92)
	)
	(segment
		(start 56.920512 127.271722)
		(end 57.50529 127.8565)
		(width 0.2)
		(layer "In2.Cu")
		(net 92)
	)
	(segment
		(start 71.797962 127.8565)
		(end 72.619512 127.03495)
		(width 0.2)
		(layer "In2.Cu")
		(net 92)
	)
	(segment
		(start 72.619512 127.03495)
		(end 72.619512 125.781)
		(width 0.2)
		(layer "In2.Cu")
		(net 92)
	)
	(segment
		(start 57.50529 127.8565)
		(end 71.797962 127.8565)
		(width 0.2)
		(layer "In2.Cu")
		(net 92)
	)
	(segment
		(start 56.920512 125.781)
		(end 56.920512 127.271722)
		(width 0.2)
		(layer "In2.Cu")
		(net 92)
	)
	(segment
		(start 71.03 176.88)
		(end 71.053678 176.856322)
		(width 0.2)
		(layer "F.Cu")
		(net 93)
	)
	(segment
		(start 71.817962 175.9575)
		(end 71.817962 174.7915)
		(width 0.2)
		(layer "F.Cu")
		(net 93)
	)
	(segment
		(start 71.053678 176.856322)
		(end 71.053678 176.701284)
		(width 0.2)
		(layer "F.Cu")
		(net 93)
	)
	(segment
		(start 71.053678 176.701284)
		(end 71.722462 176.0325)
		(width 0.2)
		(layer "F.Cu")
		(net 93)
	)
	(segment
		(start 71.791962 176.0325)
		(end 72.317962 175.5065)
		(width 0.2)
		(layer "F.Cu")
		(net 93)
	)
	(segment
		(start 72.317962 175.5065)
		(end 72.317962 174.7915)
		(width 0.2)
		(layer "F.Cu")
		(net 93)
	)
	(segment
		(start 74.542962 174.0665)
		(end 75.458962 174.0665)
		(width 0.2)
		(layer "F.Cu")
		(net 93)
	)
	(segment
		(start 75.742962 175.0415)
		(end 75.742962 174.4485)
		(width 0.2)
		(layer "F.Cu")
		(net 93)
	)
	(segment
		(start 75.458962 174.0665)
		(end 75.758962 174.3665)
		(width 0.2)
		(layer "F.Cu")
		(net 93)
	)
	(segment
		(start 71.742962 176.0325)
		(end 71.791962 176.0325)
		(width 0.2)
		(layer "F.Cu")
		(net 93)
	)
	(segment
		(start 71.03 176.91)
		(end 71.03 176.88)
		(width 0.2)
		(layer "F.Cu")
		(net 93)
	)
	(via
		(at 75.742962 175.0415)
		(size 0.45)
		(drill 0.1)
		(layers "F.Cu" "B.Cu")
		(net 93)
	)
	(via
		(at 71.03 176.91)
		(size 0.45)
		(drill 0.1)
		(layers "F.Cu" "B.Cu")
		(net 93)
	)
	(segment
		(start 71.04 176.859393)
		(end 71.107893 176.7915)
		(width 0.2)
		(layer "In3.Cu")
		(net 93)
	)
	(segment
		(start 71.04 176.9)
		(end 71.04 176.859393)
		(width 0.2)
		(layer "In3.Cu")
		(net 93)
	)
	(segment
		(start 73.992962 176.7915)
		(end 75.742962 175.0415)
		(width 0.2)
		(layer "In3.Cu")
		(net 93)
	)
	(segment
		(start 71.03 176.91)
		(end 71.04 176.9)
		(width 0.2)
		(layer "In3.Cu")
		(net 93)
	)
	(segment
		(start 71.107893 176.7915)
		(end 73.992962 176.7915)
		(width 0.2)
		(layer "In3.Cu")
		(net 93)
	)
	(segment
		(start 69.817962 174.7915)
		(end 69.817962 176.3325)
		(width 0.2)
		(layer "F.Cu")
		(net 94)
	)
	(segment
		(start 68.592962 173.0665)
		(end 66.976962 173.0665)
		(width 0.2)
		(layer "F.Cu")
		(net 94)
	)
	(segment
		(start 69.759276 176.3325)
		(end 69.276602 176.815174)
		(width 0.2)
		(layer "F.Cu")
		(net 94)
	)
	(segment
		(start 66.976962 173.0665)
		(end 66.626962 172.7165)
		(width 0.2)
		(layer "F.Cu")
		(net 94)
	)
	(segment
		(start 67.767962 171.0665)
		(end 68.592962 171.0665)
		(width 0.2)
		(layer "F.Cu")
		(net 94)
	)
	(segment
		(start 66.138971 172.162454)
		(end 66.626962 172.650445)
		(width 0.2)
		(layer "F.Cu")
		(net 94)
	)
	(via
		(at 69.276602 176.815174)
		(size 0.45)
		(drill 0.1)
		(layers "F.Cu" "B.Cu")
		(net 94)
	)
	(via
		(at 66.138971 172.162454)
		(size 0.45)
		(drill 0.1)
		(layers "F.Cu" "B.Cu")
		(net 94)
	)
	(via
		(at 67.767962 171.0665)
		(size 0.45)
		(drill 0.1)
		(layers "F.Cu" "B.Cu")
		(net 94)
	)
	(segment
		(start 67.234925 171.0665)
		(end 67.767962 171.0665)
		(width 0.254)
		(layer "In3.Cu")
		(net 94)
	)
	(segment
		(start 67.767962 171.0665)
		(end 69.267962 172.5665)
		(width 0.254)
		(layer "In3.Cu")
		(net 94)
	)
	(segment
		(start 69.267962 176.806534)
		(end 69.276602 176.815174)
		(width 0.254)
		(layer "In3.Cu")
		(net 94)
	)
	(segment
		(start 69.267962 172.5665)
		(end 69.267962 176.806534)
		(width 0.254)
		(layer "In3.Cu")
		(net 94)
	)
	(segment
		(start 66.138971 172.162454)
		(end 67.234925 171.0665)
		(width 0.254)
		(layer "In3.Cu")
		(net 94)
	)
	(segment
		(start 67.567962 172.5665)
		(end 66.767962 171.7665)
		(width 0.2)
		(layer "F.Cu")
		(net 95)
	)
	(segment
		(start 68.592962 172.5665)
		(end 67.567962 172.5665)
		(width 0.2)
		(layer "F.Cu")
		(net 95)
	)
	(segment
		(start 117.032962 164.884846)
		(end 105.811307 176.106501)
		(width 0.15)
		(layer "F.Cu")
		(net 96)
	)
	(segment
		(start 116.475808 163.351)
		(end 117.032962 163.908154)
		(width 0.15)
		(layer "F.Cu")
		(net 96)
	)
	(segment
		(start 88.277961 176.106501)
		(end 88.117962 176.2665)
		(width 0.15)
		(layer "F.Cu")
		(net 96)
	)
	(segment
		(start 117.032962 163.908154)
		(end 117.032962 164.884846)
		(width 0.15)
		(layer "F.Cu")
		(net 96)
	)
	(segment
		(start 116.114962 163.351)
		(end 116.475808 163.351)
		(width 0.15)
		(layer "F.Cu")
		(net 96)
	)
	(segment
		(start 115.554961 163.316)
		(end 116.079962 163.316)
		(width 0.15)
		(layer "F.Cu")
		(net 96)
	)
	(segment
		(start 116.079962 163.316)
		(end 116.114962 163.351)
		(width 0.15)
		(layer "F.Cu")
		(net 96)
	)
	(segment
		(start 105.811307 176.106501)
		(end 88.277961 176.106501)
		(width 0.15)
		(layer "F.Cu")
		(net 96)
	)
	(via
		(at 88.117962 176.2665)
		(size 0.45)
		(drill 0.1)
		(layers "F.Cu" "B.Cu")
		(net 96)
	)
	(segment
		(start 90.827962 176.1025)
		(end 90.790759 176.1025)
		(width 0.15)
		(layer "B.Cu")
		(net 96)
	)
	(segment
		(start 88.277962 176.1065)
		(end 88.677211 176.1065)
		(width 0.15)
		(layer "B.Cu")
		(net 96)
	)
	(segment
		(start 90.334213 176.107)
		(end 90.249713 176.1915)
		(width 0.15)
		(layer "B.Cu")
		(net 96)
	)
	(segment
		(start 88.677211 176.1065)
		(end 88.762211 176.1915)
		(width 0.15)
		(layer "B.Cu")
		(net 96)
	)
	(segment
		(start 90.786259 176.107)
		(end 90.334213 176.107)
		(width 0.15)
		(layer "B.Cu")
		(net 96)
	)
	(segment
		(start 90.249713 176.1915)
		(end 89.893462 176.1915)
		(width 0.15)
		(layer "B.Cu")
		(net 96)
	)
	(segment
		(start 90.790759 176.1025)
		(end 90.786259 176.107)
		(width 0.15)
		(layer "B.Cu")
		(net 96)
	)
	(segment
		(start 88.762211 176.1915)
		(end 89.118462 176.1915)
		(width 0.15)
		(layer "B.Cu")
		(net 96)
	)
	(segment
		(start 90.912962 176.1875)
		(end 90.827962 176.1025)
		(width 0.15)
		(layer "B.Cu")
		(net 96)
	)
	(segment
		(start 89.893462 176.1915)
		(end 89.118462 176.1915)
		(width 0.15)
		(layer "B.Cu")
		(net 96)
	)
	(segment
		(start 88.117962 176.2665)
		(end 88.277962 176.1065)
		(width 0.15)
		(layer "B.Cu")
		(net 96)
	)
	(segment
		(start 113.712962 165.318154)
		(end 113.556289 165.474827)
		(width 0.15)
		(layer "F.Cu")
		(net 97)
	)
	(segment
		(start 106.509739 169.61406)
		(end 106.509737 169.614061)
		(width 0.15)
		(layer "F.Cu")
		(net 97)
	)
	(segment
		(start 112.998962 163.716)
		(end 113.033962 163.681)
		(width 0.15)
		(layer "F.Cu")
		(net 97)
	)
	(segment
		(start 112.473961 163.716)
		(end 112.998962 163.716)
		(width 0.15)
		(layer "F.Cu")
		(net 97)
	)
	(segment
		(start 88.280461 174.273999)
		(end 88.117962 174.1115)
		(width 0.15)
		(layer "F.Cu")
		(net 97)
	)
	(segment
		(start 107.25629 171.774828)
		(end 104.749616 174.2815)
		(width 0.15)
		(layer "F.Cu")
		(net 97)
	)
	(segment
		(start 90.447962 174.2815)
		(end 90.440461 174.273999)
		(width 0.15)
		(layer "F.Cu")
		(net 97)
	)
	(segment
		(start 113.273445 165.474827)
		(end 113.273446 165.474827)
		(width 0.15)
		(layer "F.Cu")
		(net 97)
	)
	(segment
		(start 113.273446 165.474827)
		(end 113.048279 165.24966)
		(width 0.15)
		(layer "F.Cu")
		(net 97)
	)
	(segment
		(start 112.990603 166.04051)
		(end 112.679719 166.351397)
		(width 0.15)
		(layer "F.Cu")
		(net 97)
	)
	(segment
		(start 108.196745 170.360614)
		(end 107.450191 169.61406)
		(width 0.15)
		(layer "F.Cu")
		(net 97)
	)
	(segment
		(start 112.765437 165.532502)
		(end 112.990603 165.757668)
		(width 0.15)
		(layer "F.Cu")
		(net 97)
	)
	(segment
		(start 112.679719 166.351397)
		(end 108.670504 170.360613)
		(width 0.15)
		(layer "F.Cu")
		(net 97)
	)
	(segment
		(start 113.239116 163.681)
		(end 113.712962 164.154846)
		(width 0.15)
		(layer "F.Cu")
		(net 97)
	)
	(segment
		(start 106.509737 170.554513)
		(end 107.25629 171.301066)
		(width 0.15)
		(layer "F.Cu")
		(net 97)
	)
	(segment
		(start 90.440461 174.273999)
		(end 88.280461 174.273999)
		(width 0.15)
		(layer "F.Cu")
		(net 97)
	)
	(segment
		(start 104.749616 174.2815)
		(end 90.447962 174.2815)
		(width 0.15)
		(layer "F.Cu")
		(net 97)
	)
	(segment
		(start 112.765436 165.249661)
		(end 112.765437 165.24966)
		(width 0.15)
		(layer "F.Cu")
		(net 97)
	)
	(segment
		(start 113.712962 164.154846)
		(end 113.712962 165.318154)
		(width 0.15)
		(layer "F.Cu")
		(net 97)
	)
	(segment
		(start 112.990602 166.040511)
		(end 112.990603 166.04051)
		(width 0.15)
		(layer "F.Cu")
		(net 97)
	)
	(segment
		(start 113.033962 163.681)
		(end 113.239116 163.681)
		(width 0.15)
		(layer "F.Cu")
		(net 97)
	)
	(segment
		(start 108.670504 170.360613)
		(end 108.670507 170.360614)
		(width 0.15)
		(layer "F.Cu")
		(net 97)
	)
	(via
		(at 88.117962 174.1115)
		(size 0.45)
		(drill 0.1)
		(layers "F.Cu" "B.Cu")
		(net 97)
	)
	(arc
		(start 107.450191 169.61406)
		(mid 106.979965 169.419286)
		(end 106.509739 169.61406)
		(width 0.15)
		(layer "F.Cu")
		(net 97)
	)
	(arc
		(start 108.670507 170.360614)
		(mid 108.433626 170.458733)
		(end 108.196745 170.360614)
		(width 0.15)
		(layer "F.Cu")
		(net 97)
	)
	(arc
		(start 113.556289 165.474827)
		(mid 113.414867 165.533406)
		(end 113.273445 165.474827)
		(width 0.15)
		(layer "F.Cu")
		(net 97)
	)
	(arc
		(start 106.509737 169.614061)
		(mid 106.314963 170.084287)
		(end 106.509737 170.554513)
		(width 0.15)
		(layer "F.Cu")
		(net 97)
	)
	(arc
		(start 107.25629 171.301066)
		(mid 107.354409 171.537947)
		(end 107.25629 171.774828)
		(width 0.15)
		(layer "F.Cu")
		(net 97)
	)
	(arc
		(start 112.990603 165.757668)
		(mid 113.049181 165.89909)
		(end 112.990602 166.040511)
		(width 0.15)
		(layer "F.Cu")
		(net 97)
	)
	(arc
		(start 113.048279 165.24966)
		(mid 112.906857 165.191082)
		(end 112.765436 165.249661)
		(width 0.15)
		(layer "F.Cu")
		(net 97)
	)
	(arc
		(start 112.765437 165.24966)
		(mid 112.706859 165.391081)
		(end 112.765437 165.532502)
		(width 0.15)
		(layer "F.Cu")
		(net 97)
	)
	(segment
		(start 90.334713 174.2765)
		(end 90.649966 174.2765)
		(width 0.15)
		(layer "B.Cu")
		(net 97)
	)
	(segment
		(start 88.457962 174.2765)
		(end 88.455461 174.273999)
		(width 0.15)
		(layer "B.Cu")
		(net 97)
	)
	(segment
		(start 90.649966 174.2765)
		(end 90.653966 174.2725)
		(width 0.15)
		(layer "B.Cu")
		(net 97)
	)
	(segment
		(start 88.762211 174.1915)
		(end 88.677211 174.2765)
		(width 0.15)
		(layer "B.Cu")
		(net 97)
	)
	(segment
		(start 88.455461 174.273999)
		(end 88.280461 174.273999)
		(width 0.15)
		(layer "B.Cu")
		(net 97)
	)
	(segment
		(start 90.653966 174.2725)
		(end 90.827962 174.2725)
		(width 0.15)
		(layer "B.Cu")
		(net 97)
	)
	(segment
		(start 90.249713 174.1915)
		(end 90.334713 174.2765)
		(width 0.15)
		(layer "B.Cu")
		(net 97)
	)
	(segment
		(start 89.118462 174.1915)
		(end 88.762211 174.1915)
		(width 0.15)
		(layer "B.Cu")
		(net 97)
	)
	(segment
		(start 89.893462 174.1915)
		(end 89.118462 174.1915)
		(width 0.15)
		(layer "B.Cu")
		(net 97)
	)
	(segment
		(start 90.827962 174.2725)
		(end 90.912962 174.1875)
		(width 0.15)
		(layer "B.Cu")
		(net 97)
	)
	(segment
		(start 88.280461 174.273999)
		(end 88.117962 174.1115)
		(width 0.15)
		(layer "B.Cu")
		(net 97)
	)
	(segment
		(start 89.893462 174.1915)
		(end 90.249713 174.1915)
		(width 0.15)
		(layer "B.Cu")
		(net 97)
	)
	(segment
		(start 88.677211 174.2765)
		(end 88.457962 174.2765)
		(width 0.15)
		(layer "B.Cu")
		(net 97)
	)
	(segment
		(start 116.702962 164.044846)
		(end 116.702962 164.748154)
		(width 0.15)
		(layer "F.Cu")
		(net 98)
	)
	(segment
		(start 116.114962 163.681)
		(end 116.339116 163.681)
		(width 0.15)
		(layer "F.Cu")
		(net 98)
	)
	(segment
		(start 105.674617 175.776499)
		(end 88.277961 175.776499)
		(width 0.15)
		(layer "F.Cu")
		(net 98)
	)
	(segment
		(start 116.079962 163.716)
		(end 116.114962 163.681)
		(width 0.15)
		(layer "F.Cu")
		(net 98)
	)
	(segment
		(start 115.285433 165.149656)
		(end 115.285432 165.149656)
		(width 0.15)
		(layer "F.Cu")
		(net 98)
	)
	(segment
		(start 115.510602 165.94051)
		(end 115.510602 165.940511)
		(width 0.15)
		(layer "F.Cu")
		(net 98)
	)
	(segment
		(start 115.285432 165.432498)
		(end 115.510602 165.657668)
		(width 0.15)
		(layer "F.Cu")
		(net 98)
	)
	(segment
		(start 115.793445 165.374827)
		(end 115.793446 165.374827)
		(width 0.15)
		(layer "F.Cu")
		(net 98)
	)
	(segment
		(start 116.339116 163.681)
		(end 116.702962 164.044846)
		(width 0.15)
		(layer "F.Cu")
		(net 98)
	)
	(segment
		(start 116.702962 164.748154)
		(end 116.076289 165.374827)
		(width 0.15)
		(layer "F.Cu")
		(net 98)
	)
	(segment
		(start 115.510602 165.940511)
		(end 115.40071 166.050406)
		(width 0.15)
		(layer "F.Cu")
		(net 98)
	)
	(segment
		(start 88.277961 175.776499)
		(end 88.117962 175.6165)
		(width 0.15)
		(layer "F.Cu")
		(net 98)
	)
	(segment
		(start 115.40071 166.050406)
		(end 105.674617 175.776499)
		(width 0.15)
		(layer "F.Cu")
		(net 98)
	)
	(segment
		(start 115.554961 163.716)
		(end 116.079962 163.716)
		(width 0.15)
		(layer "F.Cu")
		(net 98)
	)
	(segment
		(start 115.793446 165.374827)
		(end 115.568275 165.149656)
		(width 0.15)
		(layer "F.Cu")
		(net 98)
	)
	(via
		(at 88.117962 175.6165)
		(size 0.45)
		(drill 0.1)
		(layers "F.Cu" "B.Cu")
		(net 98)
	)
	(arc
		(start 115.568275 165.149656)
		(mid 115.426854 165.091078)
		(end 115.285433 165.149656)
		(width 0.15)
		(layer "F.Cu")
		(net 98)
	)
	(arc
		(start 115.285432 165.149656)
		(mid 115.226854 165.291077)
		(end 115.285432 165.432498)
		(width 0.15)
		(layer "F.Cu")
		(net 98)
	)
	(arc
		(start 116.076289 165.374827)
		(mid 115.934867 165.433406)
		(end 115.793445 165.374827)
		(width 0.15)
		(layer "F.Cu")
		(net 98)
	)
	(arc
		(start 115.510602 165.657668)
		(mid 115.56918 165.799089)
		(end 115.510602 165.94051)
		(width 0.15)
		(layer "F.Cu")
		(net 98)
	)
	(segment
		(start 90.912962 175.6875)
		(end 90.827962 175.7725)
		(width 0.15)
		(layer "B.Cu")
		(net 98)
	)
	(segment
		(start 90.334213 175.777)
		(end 90.659975 175.777)
		(width 0.15)
		(layer "B.Cu")
		(net 98)
	)
	(segment
		(start 88.117962 175.6165)
		(end 88.277962 175.7765)
		(width 0.15)
		(layer "B.Cu")
		(net 98)
	)
	(segment
		(start 90.249713 175.6925)
		(end 90.334213 175.777)
		(width 0.15)
		(layer "B.Cu")
		(net 98)
	)
	(segment
		(start 88.677211 175.7765)
		(end 88.762211 175.6915)
		(width 0.15)
		(layer "B.Cu")
		(net 98)
	)
	(segment
		(start 88.762211 175.6915)
		(end 89.118462 175.6915)
		(width 0.15)
		(layer "B.Cu")
		(net 98)
	)
	(segment
		(start 90.664475 175.7725)
		(end 90.659975 175.777)
		(width 0.15)
		(layer "B.Cu")
		(net 98)
	)
	(segment
		(start 88.277962 175.7765)
		(end 88.677211 175.7765)
		(width 0.15)
		(layer "B.Cu")
		(net 98)
	)
	(segment
		(start 90.827962 175.7725)
		(end 90.664475 175.7725)
		(width 0.15)
		(layer "B.Cu")
		(net 98)
	)
	(segment
		(start 89.118462 175.6915)
		(end 89.892462 175.6915)
		(width 0.15)
		(layer "B.Cu")
		(net 98)
	)
	(segment
		(start 89.893462 175.6925)
		(end 90.249713 175.6925)
		(width 0.15)
		(layer "B.Cu")
		(net 98)
	)
	(segment
		(start 73.317962 176.40688)
		(end 74.113582 177.2025)
		(width 0.2)
		(layer "F.Cu")
		(net 99)
	)
	(segment
		(start 73.317962 174.7915)
		(end 73.317962 176.40688)
		(width 0.2)
		(layer "F.Cu")
		(net 99)
	)
	(segment
		(start 74.133962 178.2415)
		(end 74.133962 177.2995)
		(width 0.2)
		(layer "F.Cu")
		(net 99)
	)
	(segment
		(start 74.113582 177.2025)
		(end 74.138582 177.2025)
		(width 0.2)
		(layer "F.Cu")
		(net 99)
	)
	(segment
		(start 61.117962 178.1715)
		(end 62.117962 178.1715)
		(width 0.254)
		(layer "F.Cu")
		(net 100)
	)
	(segment
		(start 63.137962 178.2005)
		(end 62.146962 178.2005)
		(width 0.254)
		(layer "F.Cu")
		(net 100)
	)
	(segment
		(start 59.4755 177.3255)
		(end 60.3215 178.1715)
		(width 0.254)
		(layer "F.Cu")
		(net 100)
	)
	(segment
		(start 63.133962 178.2005)
		(end 63.133962 179.1505)
		(width 0.254)
		(layer "F.Cu")
		(net 100)
	)
	(segment
		(start 61.117962 178.1715)
		(end 61.117962 178.9865)
		(width 0.254)
		(layer "F.Cu")
		(net 100)
	)
	(segment
		(start 59.472962 177.3255)
		(end 59.4755 177.3255)
		(width 0.254)
		(layer "F.Cu")
		(net 100)
	)
	(segment
		(start 60.3215 178.1715)
		(end 61.117962 178.1715)
		(width 0.254)
		(layer "F.Cu")
		(net 100)
	)
	(segment
		(start 61.117962 178.9865)
		(end 60.962962 179.1415)
		(width 0.254)
		(layer "F.Cu")
		(net 100)
	)
	(segment
		(start 62.146962 178.2005)
		(end 62.117962 178.1715)
		(width 0.254)
		(layer "F.Cu")
		(net 100)
	)
	(segment
		(start 70.317962 175.598627)
		(end 70.317962 174.7915)
		(width 0.2)
		(layer "F.Cu")
		(net 101)
	)
	(segment
		(start 61.926962 179.1415)
		(end 62.261068 178.807394)
		(width 0.254)
		(layer "F.Cu")
		(net 101)
	)
	(segment
		(start 70.267962 175.648627)
		(end 70.317962 175.598627)
		(width 0.2)
		(layer "F.Cu")
		(net 101)
	)
	(segment
		(start 62.261068 178.807394)
		(end 62.516281 178.807394)
		(width 0.254)
		(layer "F.Cu")
		(net 101)
	)
	(via
		(at 70.267962 175.648627)
		(size 0.45)
		(drill 0.1)
		(layers "F.Cu" "B.Cu")
		(net 101)
	)
	(via
		(at 62.516281 178.807394)
		(size 0.45)
		(drill 0.1)
		(layers "F.Cu" "B.Cu")
		(net 101)
	)
	(segment
		(start 65.802068 178.807394)
		(end 62.516281 178.807394)
		(width 0.254)
		(layer "In2.Cu")
		(net 101)
	)
	(segment
		(start 70.267962 175.648627)
		(end 68.960835 175.648627)
		(width 0.254)
		(layer "In2.Cu")
		(net 101)
	)
	(segment
		(start 68.960835 175.648627)
		(end 65.802068 178.807394)
		(width 0.254)
		(layer "In2.Cu")
		(net 101)
	)
	(segment
		(start 65.727962 178.1665)
		(end 65.727962 177.1975)
		(width 0.254)
		(layer "B.Cu")
		(net 102)
	)
	(segment
		(start 67.73836 172.0665)
		(end 68.592962 172.0665)
		(width 0.2)
		(layer "F.Cu")
		(net 103)
	)
	(via
		(at 67.73836 172.0665)
		(size 0.45)
		(drill 0.1)
		(layers "F.Cu" "B.Cu")
		(net 103)
	)
	(segment
		(start 67.73836 176.155102)
		(end 67.73836 172.0665)
		(width 0.254)
		(layer "B.Cu")
		(net 103)
	)
	(segment
		(start 66.701962 177.1915)
		(end 67.73836 176.155102)
		(width 0.254)
		(layer "B.Cu")
		(net 103)
	)
	(segment
		(start 65.733962 176.2415)
		(end 65.733962 175.2975)
		(width 0.254)
		(layer "B.Cu")
		(net 104)
	)
	(segment
		(start 67.435376 171.561422)
		(end 67.440454 171.5665)
		(width 0.2)
		(layer "F.Cu")
		(net 105)
	)
	(segment
		(start 67.440454 171.5665)
		(end 68.592962 171.5665)
		(width 0.2)
		(layer "F.Cu")
		(net 105)
	)
	(via
		(at 67.435376 171.561422)
		(size 0.45)
		(drill 0.1)
		(layers "F.Cu" "B.Cu")
		(net 105)
	)
	(segment
		(start 66.701962 172.294836)
		(end 67.435376 171.561422)
		(width 0.254)
		(layer "B.Cu")
		(net 105)
	)
	(segment
		(start 66.701962 176.2415)
		(end 66.701962 172.294836)
		(width 0.254)
		(layer "B.Cu")
		(net 105)
	)
	(segment
		(start 60.4845 175.2455)
		(end 59.472962 176.257038)
		(width 0.254)
		(layer "F.Cu")
		(net 106)
	)
	(segment
		(start 62.117962 175.2455)
		(end 63.117962 175.2455)
		(width 0.254)
		(layer "F.Cu")
		(net 106)
	)
	(segment
		(start 63.117962 175.2455)
		(end 63.137962 175.2255)
		(width 0.254)
		(layer "F.Cu")
		(net 106)
	)
	(segment
		(start 61.117962 175.2455)
		(end 60.4845 175.2455)
		(width 0.254)
		(layer "F.Cu")
		(net 106)
	)
	(segment
		(start 59.472962 176.257038)
		(end 59.472962 176.3255)
		(width 0.254)
		(layer "F.Cu")
		(net 106)
	)
	(segment
		(start 61.117962 175.2455)
		(end 61.117962 174.4215)
		(width 0.254)
		(layer "F.Cu")
		(net 106)
	)
	(segment
		(start 63.137962 175.2255)
		(end 63.137962 174.249462)
		(width 0.254)
		(layer "F.Cu")
		(net 106)
	)
	(segment
		(start 63.137962 174.249462)
		(end 63.13 174.2415)
		(width 0.254)
		(layer "F.Cu")
		(net 106)
	)
	(segment
		(start 62.117962 175.2455)
		(end 61.117962 175.2455)
		(width 0.254)
		(layer "F.Cu")
		(net 106)
	)
	(segment
		(start 61.117962 174.4215)
		(end 60.962962 174.2665)
		(width 0.254)
		(layer "F.Cu")
		(net 106)
	)
	(segment
		(start 62.309938 174.653476)
		(end 62.525633 174.653476)
		(width 0.254)
		(layer "F.Cu")
		(net 107)
	)
	(segment
		(start 61.922962 174.2665)
		(end 62.309938 174.653476)
		(width 0.254)
		(layer "F.Cu")
		(net 107)
	)
	(segment
		(start 70.817962 175.909702)
		(end 70.817962 174.7915)
		(width 0.2)
		(layer "F.Cu")
		(net 107)
	)
	(via
		(at 70.817962 175.909702)
		(size 0.45)
		(drill 0.1)
		(layers "F.Cu" "B.Cu")
		(net 107)
	)
	(via
		(at 62.525633 174.653476)
		(size 0.45)
		(drill 0.1)
		(layers "F.Cu" "B.Cu")
		(net 107)
	)
	(segment
		(start 70.817962 175.909702)
		(end 70.817962 175.48525)
		(width 0.254)
		(layer "In2.Cu")
		(net 107)
	)
	(segment
		(start 70.817962 175.48525)
		(end 69.986188 174.653476)
		(width 0.254)
		(layer "In2.Cu")
		(net 107)
	)
	(segment
		(start 69.986188 174.653476)
		(end 62.525633 174.653476)
		(width 0.254)
		(layer "In2.Cu")
		(net 107)
	)
	(segment
		(start 74.065962 174.7915)
		(end 75.503962 176.2295)
		(width 0.2)
		(layer "F.Cu")
		(net 108)
	)
	(segment
		(start 76.617962 176.1325)
		(end 75.600962 176.1325)
		(width 0.2)
		(layer "F.Cu")
		(net 108)
	)
	(segment
		(start 73.817962 174.7915)
		(end 74.065962 174.7915)
		(width 0.2)
		(layer "F.Cu")
		(net 108)
	)
	(segment
		(start 64.101962 177.6005)
		(end 64.092962 177.5915)
		(width 0.254)
		(layer "F.Cu")
		(net 109)
	)
	(segment
		(start 65.092962 178.1845)
		(end 66.624962 178.1845)
		(width 0.254)
		(layer "F.Cu")
		(net 109)
	)
	(segment
		(start 67.352962 177.4565)
		(end 68.3235 177.4565)
		(width 0.254)
		(layer "F.Cu")
		(net 109)
	)
	(segment
		(start 68.3235 177.4565)
		(end 68.35 177.43)
		(width 0.254)
		(layer "F.Cu")
		(net 109)
	)
	(segment
		(start 66.624962 178.1845)
		(end 67.352962 177.4565)
		(width 0.254)
		(layer "F.Cu")
		(net 109)
	)
	(segment
		(start 64.101962 178.2005)
		(end 65.076962 178.2005)
		(width 0.254)
		(layer "F.Cu")
		(net 109)
	)
	(segment
		(start 64.101962 178.2005)
		(end 64.101962 177.6005)
		(width 0.254)
		(layer "F.Cu")
		(net 109)
	)
	(segment
		(start 64.101962 179.1505)
		(end 64.101962 178.2005)
		(width 0.254)
		(layer "F.Cu")
		(net 109)
	)
	(via
		(at 64.092962 177.5915)
		(size 0.45)
		(drill 0.1)
		(layers "F.Cu" "B.Cu")
		(net 109)
	)
	(segment
		(start 64.092962 177.5915)
		(end 64.182962 177.5915)
		(width 0.254)
		(layer "B.Cu")
		(net 109)
	)
	(segment
		(start 64.182962 177.5915)
		(end 64.757962 178.1665)
		(width 0.254)
		(layer "B.Cu")
		(net 109)
	)
	(segment
		(start 64.101962 174.2255)
		(end 64.101962 175.2255)
		(width 0.254)
		(layer "F.Cu")
		(net 110)
	)
	(segment
		(start 64.101962 175.2255)
		(end 65.083962 175.2255)
		(width 0.254)
		(layer "F.Cu")
		(net 110)
	)
	(segment
		(start 65.092962 175.2165)
		(end 66.092962 175.2165)
		(width 0.254)
		(layer "F.Cu")
		(net 110)
	)
	(segment
		(start 64.101962 175.7825)
		(end 64.092962 175.7915)
		(width 0.254)
		(layer "F.Cu")
		(net 110)
	)
	(segment
		(start 64.101962 175.2255)
		(end 64.101962 175.7825)
		(width 0.254)
		(layer "F.Cu")
		(net 110)
	)
	(segment
		(start 66.092962 175.2165)
		(end 66.092962 173.9665)
		(width 0.254)
		(layer "F.Cu")
		(net 110)
	)
	(via
		(at 64.092962 175.7915)
		(size 0.45)
		(drill 0.1)
		(layers "F.Cu" "B.Cu")
		(net 110)
	)
	(segment
		(start 64.092962 175.7915)
		(end 64.257962 175.7915)
		(width 0.254)
		(layer "B.Cu")
		(net 110)
	)
	(segment
		(start 64.257962 175.7915)
		(end 64.757962 175.2915)
		(width 0.254)
		(layer "B.Cu")
		(net 110)
	)
	(segment
		(start 89.226962 123.1415)
		(end 89.226962 123.8505)
		(width 0.254)
		(layer "B.Cu")
		(net 111)
	)
	(segment
		(start 89.226962 123.8505)
		(end 90.017962 124.6415)
		(width 0.254)
		(layer "B.Cu")
		(net 111)
	)
	(segment
		(start 88.258962 123.1415)
		(end 88.258962 124.3115)
		(width 0.254)
		(layer "B.Cu")
		(net 112)
	)
	(segment
		(start 82.322962 124.4715)
		(end 83.287962 124.4715)
		(width 0.2)
		(layer "F.Cu")
		(net 113)
	)
	(via
		(at 89.667962 128.2415)
		(size 0.45)
		(drill 0.1)
		(layers "F.Cu" "B.Cu")
		(net 113)
	)
	(via
		(at 83.292962 124.4665)
		(size 0.45)
		(drill 0.1)
		(layers "F.Cu" "B.Cu")
		(net 113)
	)
	(segment
		(start 84.182962 123.7165)
		(end 83.667962 123.7165)
		(width 0.2)
		(layer "B.Cu")
		(net 113)
	)
	(segment
		(start 83.292962 124.0915)
		(end 83.292962 124.4665)
		(width 0.2)
		(layer "B.Cu")
		(net 113)
	)
	(segment
		(start 90.667962 127.9965)
		(end 90.667962 126.9915)
		(width 0.35)
		(layer "B.Cu")
		(net 113)
	)
	(segment
		(start 92.067962 128.8565)
		(end 90.677962 128.8565)
		(width 0.254)
		(layer "B.Cu")
		(net 113)
	)
	(segment
		(start 89.667962 128.6415)
		(end 89.667962 128.2415)
		(width 0.2)
		(layer "B.Cu")
		(net 113)
	)
	(segment
		(start 89.892962 128.8665)
		(end 89.667962 128.6415)
		(width 0.2)
		(layer "B.Cu")
		(net 113)
	)
	(segment
		(start 90.667962 128.8665)
		(end 90.667962 127.9965)
		(width 0.35)
		(layer "B.Cu")
		(net 113)
	)
	(segment
		(start 90.677962 128.0065)
		(end 90.677962 130.7365)
		(width 0.35)
		(layer "B.Cu")
		(net 113)
	)
	(segment
		(start 83.667962 123.7165)
		(end 83.292962 124.0915)
		(width 0.2)
		(layer "B.Cu")
		(net 113)
	)
	(segment
		(start 90.667962 128.8665)
		(end 89.892962 128.8665)
		(width 0.2)
		(layer "B.Cu")
		(net 113)
	)
	(segment
		(start 90.667962 127.9965)
		(end 90.677962 128.0065)
		(width 0.35)
		(layer "B.Cu")
		(net 113)
	)
	(segment
		(start 89.667962 128.1415)
		(end 85.992962 124.4665)
		(width 0.2)
		(layer "In2.Cu")
		(net 113)
	)
	(segment
		(start 89.667962 128.2415)
		(end 89.667962 128.1415)
		(width 0.2)
		(layer "In2.Cu")
		(net 113)
	)
	(segment
		(start 85.992962 124.4665)
		(end 83.292962 124.4665)
		(width 0.2)
		(layer "In2.Cu")
		(net 113)
	)
	(segment
		(start 89.667962 143.2665)
		(end 89.667962 144.324368)
		(width 0.2)
		(layer "F.Cu")
		(net 114)
	)
	(segment
		(start 87.467962 146.0825)
		(end 88.676962 146.0825)
		(width 0.2)
		(layer "F.Cu")
		(net 114)
	)
	(segment
		(start 89.667962 142.657236)
		(end 89.667962 143.2665)
		(width 0.15)
		(layer "F.Cu")
		(net 114)
	)
	(segment
		(start 89.667962 144.324368)
		(end 88.693962 145.298368)
		(width 0.2)
		(layer "F.Cu")
		(net 114)
	)
	(segment
		(start 88.693962 145.298368)
		(end 88.693962 145.606236)
		(width 0.2)
		(layer "F.Cu")
		(net 114)
	)
	(segment
		(start 89.692962 147.4165)
		(end 90.327226 148.050764)
		(width 0.2)
		(layer "F.Cu")
		(net 115)
	)
	(segment
		(start 90.067962 143.2665)
		(end 90.067962 144.956236)
		(width 0.2)
		(layer "F.Cu")
		(net 115)
	)
	(segment
		(start 90.067962 144.956236)
		(end 89.692962 145.331236)
		(width 0.2)
		(layer "F.Cu")
		(net 115)
	)
	(segment
		(start 90.067962 142.657236)
		(end 90.067962 143.2665)
		(width 0.15)
		(layer "F.Cu")
		(net 115)
	)
	(segment
		(start 91.692962 148.7255)
		(end 91.332962 148.3655)
		(width 0.2)
		(layer "F.Cu")
		(net 115)
	)
	(segment
		(start 91.332962 148.3655)
		(end 90.492962 148.3655)
		(width 0.2)
		(layer "F.Cu")
		(net 115)
	)
	(segment
		(start 89.692962 145.331236)
		(end 89.692962 147.4165)
		(width 0.2)
		(layer "F.Cu")
		(net 115)
	)
	(segment
		(start 61.367962 113.8965)
		(end 62.597962 113.8965)
		(width 0.5)
		(layer "B.Cu")
		(net 116)
	)
	(segment
		(start 65.187962 118.3365)
		(end 65.187962 119.7165)
		(width 0.5)
		(layer "B.Cu")
		(net 116)
	)
	(segment
		(start 62.597962 113.8965)
		(end 63.492962 114.7915)
		(width 0.5)
		(layer "B.Cu")
		(net 116)
	)
	(segment
		(start 63.492962 116.6415)
		(end 65.187962 118.3365)
		(width 0.5)
		(layer "B.Cu")
		(net 116)
	)
	(segment
		(start 61.367962 113.8965)
		(end 60.138962 113.8965)
		(width 0.5)
		(layer "B.Cu")
		(net 116)
	)
	(segment
		(start 63.492962 114.7915)
		(end 63.492962 116.6415)
		(width 0.5)
		(layer "B.Cu")
		(net 116)
	)
	(segment
		(start 61.367962 116.4365)
		(end 60.188962 116.4365)
		(width 0.5)
		(layer "B.Cu")
		(net 117)
	)
	(segment
		(start 62.287962 116.4365)
		(end 61.367962 116.4365)
		(width 0.5)
		(layer "B.Cu")
		(net 117)
	)
	(segment
		(start 62.647962 119.7165)
		(end 62.647962 116.7965)
		(width 0.5)
		(layer "B.Cu")
		(net 117)
	)
	(segment
		(start 62.647962 116.7965)
		(end 62.287962 116.4365)
		(width 0.5)
		(layer "B.Cu")
		(net 117)
	)
	(segment
		(start 88.367962 163.0565)
		(end 88.367962 162.6465)
		(width 0.127)
		(layer "F.Cu")
		(net 118)
	)
	(segment
		(start 100.229962 151.47505)
		(end 98.696412 149.9415)
		(width 0.127)
		(layer "F.Cu")
		(net 118)
	)
	(segment
		(start 100.151412 156.20226)
		(end 100.229962 156.12371)
		(width 0.127)
		(layer "F.Cu")
		(net 118)
	)
	(segment
		(start 100.229962 156.12371)
		(end 100.229962 151.47505)
		(width 0.127)
		(layer "F.Cu")
		(net 118)
	)
	(segment
		(start 100.151412 156.213572)
		(end 100.151412 156.20226)
		(width 0.127)
		(layer "F.Cu")
		(net 118)
	)
	(segment
		(start 94.878484 161.4865)
		(end 100.151412 156.213572)
		(width 0.127)
		(layer "F.Cu")
		(net 118)
	)
	(segment
		(start 89.527962 161.4865)
		(end 94.878484 161.4865)
		(width 0.127)
		(layer "F.Cu")
		(net 118)
	)
	(segment
		(start 88.367962 162.6465)
		(end 89.527962 161.4865)
		(width 0.127)
		(layer "F.Cu")
		(net 118)
	)
	(segment
		(start 98.696412 149.9415)
		(end 97.167962 149.9415)
		(width 0.127)
		(layer "F.Cu")
		(net 118)
	)
	(via
		(at 88.367962 163.0565)
		(size 0.45)
		(drill 0.1)
		(layers "F.Cu" "B.Cu")
		(net 118)
	)
	(segment
		(start 127.367962 167.9915)
		(end 127.467962 168.0915)
		(width 0.15)
		(layer "B.Cu")
		(net 118)
	)
	(segment
		(start 93.967962 178.5465)
		(end 93.967962 165.2565)
		(width 0.127)
		(layer "B.Cu")
		(net 118)
	)
	(segment
		(start 127.282962 168.4515)
		(end 126.5185 168.4515)
		(width 0.15)
		(layer "B.Cu")
		(net 118)
	)
	(segment
		(start 126.855462 167.9915)
		(end 127.367962 167.9915)
		(width 0.15)
		(layer "B.Cu")
		(net 118)
	)
	(segment
		(start 104.3 176.6)
		(end 102.0635 178.8365)
		(width 0.127)
		(layer "B.Cu")
		(net 118)
	)
	(segment
		(start 106.7 171.9)
		(end 104.3 174.3)
		(width 0.127)
		(layer "B.Cu")
		(net 118)
	)
	(segment
		(start 92.467962 163.7565)
		(end 87.752962 163.7565)
		(width 0.127)
		(layer "B.Cu")
		(net 118)
	)
	(segment
		(start 126.855462 167.9915)
		(end 126.080462 167.9915)
		(width 0.15)
		(layer "B.Cu")
		(net 118)
	)
	(segment
		(start 127.467962 168.2665)
		(end 127.282962 168.4515)
		(width 0.15)
		(layer "B.Cu")
		(net 118)
	)
	(segment
		(start 125.542962 167.9915)
		(end 126.080462 167.9915)
		(width 0.15)
		(layer "B.Cu")
		(net 118)
	)
	(segment
		(start 93.967962 165.2565)
		(end 92.467962 163.7565)
		(width 0.127)
		(layer "B.Cu")
		(net 118)
	)
	(segment
		(start 102.0635 178.8365)
		(end 94.257962 178.8365)
		(width 0.127)
		(layer "B.Cu")
		(net 118)
	)
	(segment
		(start 88.367962 163.0565)
		(end 88.367962 163.0765)
		(width 0.127)
		(layer "B.Cu")
		(net 118)
	)
	(segment
		(start 88.367962 163.0765)
		(end 87.752962 163.6915)
		(width 0.127)
		(layer "B.Cu")
		(net 118)
	)
	(segment
		(start 127.467962 168.0915)
		(end 127.467962 168.2665)
		(width 0.15)
		(layer "B.Cu")
		(net 118)
	)
	(segment
		(start 121.634462 171.9)
		(end 106.7 171.9)
		(width 0.127)
		(layer "B.Cu")
		(net 118)
	)
	(segment
		(start 126.5185 168.4515)
		(end 125.92 169.05)
		(width 0.15)
		(layer "B.Cu")
		(net 118)
	)
	(segment
		(start 104.3 174.3)
		(end 104.3 176.6)
		(width 0.127)
		(layer "B.Cu")
		(net 118)
	)
	(segment
		(start 94.257962 178.8365)
		(end 93.967962 178.5465)
		(width 0.127)
		(layer "B.Cu")
		(net 118)
	)
	(segment
		(start 121.634462 171.9)
		(end 125.542962 167.9915)
		(width 0.15)
		(layer "B.Cu")
		(net 118)
	)
	(segment
		(start 113.367962 122.5605)
		(end 113.367962 120.805103)
		(width 0.2)
		(layer "F.Cu")
		(net 119)
	)
	(segment
		(start 113.367962 120.805103)
		(end 114.056565 120.1165)
		(width 0.2)
		(layer "F.Cu")
		(net 119)
	)
	(segment
		(start 114.056565 120.1165)
		(end 114.292962 120.1165)
		(width 0.2)
		(layer "F.Cu")
		(net 119)
	)
	(via
		(at 114.292962 120.1165)
		(size 0.45)
		(drill 0.1)
		(layers "F.Cu" "B.Cu")
		(net 119)
	)
	(segment
		(start 114.301962 118.3665)
		(end 114.301962 119.4585)
		(width 0.15)
		(layer "B.Cu")
		(net 119)
	)
	(segment
		(start 114.293962 117.2665)
		(end 114.293962 118.3585)
		(width 0.15)
		(layer "B.Cu")
		(net 119)
	)
	(segment
		(start 114.292962 120.1165)
		(end 114.292962 119.4915)
		(width 0.2)
		(layer "B.Cu")
		(net 119)
	)
	(segment
		(start 84.421962 164.386972)
		(end 88.842434 159.9665)
		(width 0.127)
		(layer "F.Cu")
		(net 120)
	)
	(segment
		(start 85.573962 171.928354)
		(end 84.421962 170.776354)
		(width 0.127)
		(layer "F.Cu")
		(net 120)
	)
	(segment
		(start 84.421962 170.776354)
		(end 84.421962 164.386972)
		(width 0.127)
		(layer "F.Cu")
		(net 120)
	)
	(segment
		(start 101.242962 177.2415)
		(end 101.014566 177.2415)
		(width 0.127)
		(layer "F.Cu")
		(net 120)
	)
	(segment
		(start 98.067962 156.14459)
		(end 98.067962 154.7415)
		(width 0.127)
		(layer "F.Cu")
		(net 120)
	)
	(segment
		(start 101.367962 177.3665)
		(end 101.242962 177.2415)
		(width 0.127)
		(layer "F.Cu")
		(net 120)
	)
	(segment
		(start 87.665962 177.1895)
		(end 85.573962 175.0975)
		(width 0.127)
		(layer "F.Cu")
		(net 120)
	)
	(segment
		(start 88.842434 159.9665)
		(end 94.246052 159.9665)
		(width 0.127)
		(layer "F.Cu")
		(net 120)
	)
	(segment
		(start 85.573962 175.0975)
		(end 85.573962 171.928354)
		(width 0.127)
		(layer "F.Cu")
		(net 120)
	)
	(segment
		(start 100.962566 177.1895)
		(end 87.665962 177.1895)
		(width 0.127)
		(layer "F.Cu")
		(net 120)
	)
	(segment
		(start 94.246052 159.9665)
		(end 98.067962 156.14459)
		(width 0.127)
		(layer "F.Cu")
		(net 120)
	)
	(segment
		(start 101.014566 177.2415)
		(end 100.962566 177.1895)
		(width 0.127)
		(layer "F.Cu")
		(net 120)
	)
	(via
		(at 101.367962 177.3665)
		(size 0.45)
		(drill 0.1)
		(layers "F.Cu" "B.Cu")
		(net 120)
	)
	(segment
		(start 101.367962 177.3665)
		(end 102.417962 177.3665)
		(width 0.127)
		(layer "B.Cu")
		(net 120)
	)
	(segment
		(start 100.042962 172.2915)
		(end 100.155962 172.1785)
		(width 0.15)
		(layer "B.Cu")
		(net 120)
	)
	(segment
		(start 103.492962 173.0415)
		(end 102.629962 172.1785)
		(width 0.127)
		(layer "B.Cu")
		(net 120)
	)
	(segment
		(start 102.629962 172.1785)
		(end 101.468462 172.1785)
		(width 0.127)
		(layer "B.Cu")
		(net 120)
	)
	(segment
		(start 103.492962 176.2915)
		(end 103.492962 173.0415)
		(width 0.127)
		(layer "B.Cu")
		(net 120)
	)
	(segment
		(start 101.468462 172.1785)
		(end 100.693462 172.1785)
		(width 0.15)
		(layer "B.Cu")
		(net 120)
	)
	(segment
		(start 100.155962 172.1785)
		(end 100.693462 172.1785)
		(width 0.15)
		(layer "B.Cu")
		(net 120)
	)
	(segment
		(start 102.417962 177.3665)
		(end 103.492962 176.2915)
		(width 0.127)
		(layer "B.Cu")
		(net 120)
	)
	(segment
		(start 99.467962 172.2915)
		(end 100.042962 172.2915)
		(width 0.15)
		(layer "B.Cu")
		(net 120)
	)
	(segment
		(start 88.738052 159.7145)
		(end 94.14167 159.7145)
		(width 0.127)
		(layer "F.Cu")
		(net 121)
	)
	(segment
		(start 100.858184 177.4415)
		(end 87.56158 177.4415)
		(width 0.127)
		(layer "F.Cu")
		(net 121)
	)
	(segment
		(start 101.196684 177.78)
		(end 100.858184 177.4415)
		(width 0.127)
		(layer "F.Cu")
		(net 121)
	)
	(segment
		(start 84.169962 170.880736)
		(end 84.169962 164.28259)
		(width 0.127)
		(layer "F.Cu")
		(net 121)
	)
	(segment
		(start 85.321962 172.032736)
		(end 84.169962 170.880736)
		(width 0.127)
		(layer "F.Cu")
		(net 121)
	)
	(segment
		(start 94.14167 159.7145)
		(end 97.167962 156.688208)
		(width 0.127)
		(layer "F.Cu")
		(net 121)
	)
	(segment
		(start 101.78832 177.78)
		(end 101.196684 177.78)
		(width 0.127)
		(layer "F.Cu")
		(net 121)
	)
	(segment
		(start 97.167962 156.688208)
		(end 97.167962 155.6415)
		(width 0.127)
		(layer "F.Cu")
		(net 121)
	)
	(segment
		(start 87.56158 177.4415)
		(end 85.321962 175.201882)
		(width 0.127)
		(layer "F.Cu")
		(net 121)
	)
	(segment
		(start 84.169962 164.28259)
		(end 88.738052 159.7145)
		(width 0.127)
		(layer "F.Cu")
		(net 121)
	)
	(segment
		(start 85.321962 175.201882)
		(end 85.321962 172.032736)
		(width 0.127)
		(layer "F.Cu")
		(net 121)
	)
	(via
		(at 101.78832 177.78)
		(size 0.45)
		(drill 0.1)
		(layers "F.Cu" "B.Cu")
		(net 121)
	)
	(segment
		(start 102.486344 171.6785)
		(end 101.468462 171.6785)
		(width 0.127)
		(layer "B.Cu")
		(net 121)
	)
	(segment
		(start 103.744962 172.937118)
		(end 102.486344 171.6785)
		(width 0.127)
		(layer "B.Cu")
		(net 121)
	)
	(segment
		(start 100.693462 171.6785)
		(end 99.492462 171.6785)
		(width 0.15)
		(layer "B.Cu")
		(net 121)
	)
	(segment
		(start 101.78832 177.78)
		(end 102.360844 177.78)
		(width 0.127)
		(layer "B.Cu")
		(net 121)
	)
	(segment
		(start 101.468462 171.6785)
		(end 100.693462 171.6785)
		(width 0.15)
		(layer "B.Cu")
		(net 121)
	)
	(segment
		(start 103.744962 176.395882)
		(end 103.744962 172.937118)
		(width 0.127)
		(layer "B.Cu")
		(net 121)
	)
	(segment
		(start 102.360844 177.78)
		(end 103.744962 176.395882)
		(width 0.127)
		(layer "B.Cu")
		(net 121)
	)
	(segment
		(start 94.350434 160.2185)
		(end 98.967962 155.600972)
		(width 0.127)
		(layer "F.Cu")
		(net 122)
	)
	(segment
		(start 98.967962 155.600972)
		(end 98.967962 154.3915)
		(width 0.127)
		(layer "F.Cu")
		(net 122)
	)
	(segment
		(start 98.667962 154.0915)
		(end 98.067962 154.0915)
		(width 0.127)
		(layer "F.Cu")
		(net 122)
	)
	(segment
		(start 84.673962 170.671972)
		(end 84.673962 164.491354)
		(width 0.127)
		(layer "F.Cu")
		(net 122)
	)
	(segment
		(start 87.25049 173.2485)
		(end 84.673962 170.671972)
		(width 0.127)
		(layer "F.Cu")
		(net 122)
	)
	(segment
		(start 97.747962 171.0065)
		(end 95.505962 173.2485)
		(width 0.127)
		(layer "F.Cu")
		(net 122)
	)
	(segment
		(start 98.967962 154.3915)
		(end 98.667962 154.0915)
		(width 0.127)
		(layer "F.Cu")
		(net 122)
	)
	(segment
		(start 84.673962 164.491354)
		(end 88.946816 160.2185)
		(width 0.127)
		(layer "F.Cu")
		(net 122)
	)
	(segment
		(start 88.946816 160.2185)
		(end 94.350434 160.2185)
		(width 0.127)
		(layer "F.Cu")
		(net 122)
	)
	(segment
		(start 95.505962 173.2485)
		(end 87.25049 173.2485)
		(width 0.127)
		(layer "F.Cu")
		(net 122)
	)
	(segment
		(start 102.227962 171.0065)
		(end 97.747962 171.0065)
		(width 0.127)
		(layer "F.Cu")
		(net 122)
	)
	(via
		(at 102.227962 171.0065)
		(size 0.45)
		(drill 0.1)
		(layers "F.Cu" "B.Cu")
		(net 122)
	)
	(segment
		(start 102.099962 170.8785)
		(end 102.227962 171.0065)
		(width 0.127)
		(layer "B.Cu")
		(net 122)
	)
	(segment
		(start 100.693462 170.8785)
		(end 101.468462 170.8785)
		(width 0.15)
		(layer "B.Cu")
		(net 122)
	)
	(segment
		(start 99.467962 170.879)
		(end 100.692962 170.879)
		(width 0.15)
		(layer "B.Cu")
		(net 122)
	)
	(segment
		(start 101.468462 170.8785)
		(end 102.099962 170.8785)
		(width 0.127)
		(layer "B.Cu")
		(net 122)
	)
	(segment
		(start 84.925962 170.56759)
		(end 84.925962 164.595736)
		(width 0.127)
		(layer "F.Cu")
		(net 123)
	)
	(segment
		(start 102.467962 170.3665)
		(end 102.457962 170.3765)
		(width 0.127)
		(layer "F.Cu")
		(net 123)
	)
	(segment
		(start 98.02158 170.3765)
		(end 95.40158 172.9965)
		(width 0.127)
		(layer "F.Cu")
		(net 123)
	)
	(segment
		(start 102.457962 170.3765)
		(end 98.02158 170.3765)
		(width 0.127)
		(layer "F.Cu")
		(net 123)
	)
	(segment
		(start 98.667962 153.4415)
		(end 98.067962 153.4415)
		(width 0.127)
		(layer "F.Cu")
		(net 123)
	)
	(segment
		(start 95.40158 172.9965)
		(end 87.354872 172.9965)
		(width 0.127)
		(layer "F.Cu")
		(net 123)
	)
	(segment
		(start 99.219962 155.705354)
		(end 99.219962 153.9935)
		(width 0.127)
		(layer "F.Cu")
		(net 123)
	)
	(segment
		(start 94.454816 160.4705)
		(end 99.219962 155.705354)
		(width 0.127)
		(layer "F.Cu")
		(net 123)
	)
	(segment
		(start 87.354872 172.9965)
		(end 84.925962 170.56759)
		(width 0.127)
		(layer "F.Cu")
		(net 123)
	)
	(segment
		(start 99.219962 153.9935)
		(end 98.667962 153.4415)
		(width 0.127)
		(layer "F.Cu")
		(net 123)
	)
	(segment
		(start 84.925962 164.595736)
		(end 89.051198 160.4705)
		(width 0.127)
		(layer "F.Cu")
		(net 123)
	)
	(segment
		(start 89.051198 160.4705)
		(end 94.454816 160.4705)
		(width 0.127)
		(layer "F.Cu")
		(net 123)
	)
	(via
		(at 102.467962 170.3665)
		(size 0.45)
		(drill 0.1)
		(layers "F.Cu" "B.Cu")
		(net 123)
	)
	(segment
		(start 101.468462 170.3795)
		(end 100.694462 170.3795)
		(width 0.15)
		(layer "B.Cu")
		(net 123)
	)
	(segment
		(start 102.454962 170.3795)
		(end 101.468462 170.3795)
		(width 0.127)
		(layer "B.Cu")
		(net 123)
	)
	(segment
		(start 102.467962 170.3665)
		(end 102.454962 170.3795)
		(width 0.127)
		(layer "B.Cu")
		(net 123)
	)
	(segment
		(start 100.129962 170.3785)
		(end 100.693462 170.3785)
		(width 0.15)
		(layer "B.Cu")
		(net 123)
	)
	(segment
		(start 99.467962 170.2415)
		(end 99.992962 170.2415)
		(width 0.15)
		(layer "B.Cu")
		(net 123)
	)
	(segment
		(start 99.992962 170.2415)
		(end 100.129962 170.3785)
		(width 0.15)
		(layer "B.Cu")
		(net 123)
	)
	(segment
		(start 76.017962 155.5515)
		(end 76.692962 156.2265)
		(width 0.127)
		(layer "F.Cu")
		(net 124)
	)
	(segment
		(start 76.017962 155.5415)
		(end 76.017962 155.5515)
		(width 0.127)
		(layer "F.Cu")
		(net 124)
	)
	(via
		(at 102.417962 169.3665)
		(size 0.45)
		(drill 0.1)
		(layers "F.Cu" "B.Cu")
		(net 124)
	)
	(via
		(at 76.017962 155.5415)
		(size 0.45)
		(drill 0.1)
		(layers "F.Cu" "B.Cu")
		(net 124)
	)
	(segment
		(start 99.905461 169.7415)
		(end 99.467962 169.7415)
		(width 0.15)
		(layer "B.Cu")
		(net 124)
	)
	(segment
		(start 100.693462 169.3785)
		(end 100.268461 169.3785)
		(width 0.15)
		(layer "B.Cu")
		(net 124)
	)
	(segment
		(start 102.405962 169.3785)
		(end 101.468462 169.3785)
		(width 0.127)
		(layer "B.Cu")
		(net 124)
	)
	(segment
		(start 101.468462 169.3785)
		(end 100.693462 169.3785)
		(width 0.15)
		(layer "B.Cu")
		(net 124)
	)
	(segment
		(start 100.268461 169.3785)
		(end 99.905461 169.7415)
		(width 0.15)
		(layer "B.Cu")
		(net 124)
	)
	(segment
		(start 102.417962 169.3665)
		(end 102.405962 169.3785)
		(width 0.127)
		(layer "B.Cu")
		(net 124)
	)
	(segment
		(start 86.736462 169.605)
		(end 100.489462 169.605)
		(width 0.127)
		(layer "In2.Cu")
		(net 124)
	)
	(segment
		(start 76.017962 155.5415)
		(end 75.863962 155.6955)
		(width 0.127)
		(layer "In2.Cu")
		(net 124)
	)
	(segment
		(start 100.727962 169.3665)
		(end 102.417962 169.3665)
		(width 0.127)
		(layer "In2.Cu")
		(net 124)
	)
	(segment
		(start 100.489462 169.605)
		(end 100.727962 169.3665)
		(width 0.127)
		(layer "In2.Cu")
		(net 124)
	)
	(segment
		(start 77.733038 164.0605)
		(end 81.191962 164.0605)
		(width 0.127)
		(layer "In2.Cu")
		(net 124)
	)
	(segment
		(start 81.191962 164.0605)
		(end 86.736462 169.605)
		(width 0.127)
		(layer "In2.Cu")
		(net 124)
	)
	(segment
		(start 75.863962 162.191424)
		(end 77.733038 164.0605)
		(width 0.127)
		(layer "In2.Cu")
		(net 124)
	)
	(segment
		(start 75.863962 155.6955)
		(end 75.863962 162.191424)
		(width 0.127)
		(layer "In2.Cu")
		(net 124)
	)
	(segment
		(start 85.177962 170.463208)
		(end 85.177962 164.700118)
		(width 0.127)
		(layer "F.Cu")
		(net 125)
	)
	(segment
		(start 98.817962 152.7915)
		(end 98.067962 152.7915)
		(width 0.127)
		(layer "F.Cu")
		(net 125)
	)
	(segment
		(start 99.471962 155.809736)
		(end 99.471962 153.4455)
		(width 0.127)
		(layer "F.Cu")
		(net 125)
	)
	(segment
		(start 95.315198 172.7265)
		(end 87.441254 172.7265)
		(width 0.127)
		(layer "F.Cu")
		(net 125)
	)
	(segment
		(start 89.15558 160.7225)
		(end 94.559198 160.7225)
		(width 0.127)
		(layer "F.Cu")
		(net 125)
	)
	(segment
		(start 87.441254 172.7265)
		(end 85.177962 170.463208)
		(width 0.127)
		(layer "F.Cu")
		(net 125)
	)
	(segment
		(start 85.177962 164.700118)
		(end 89.15558 160.7225)
		(width 0.127)
		(layer "F.Cu")
		(net 125)
	)
	(segment
		(start 100.43158 167.610118)
		(end 95.315198 172.7265)
		(width 0.127)
		(layer "F.Cu")
		(net 125)
	)
	(segment
		(start 94.559198 160.7225)
		(end 99.471962 155.809736)
		(width 0.127)
		(layer "F.Cu")
		(net 125)
	)
	(segment
		(start 99.471962 153.4455)
		(end 98.817962 152.7915)
		(width 0.127)
		(layer "F.Cu")
		(net 125)
	)
	(segment
		(start 100.43158 167.583)
		(end 100.43158 167.610118)
		(width 0.127)
		(layer "F.Cu")
		(net 125)
	)
	(via
		(at 100.43158 167.583)
		(size 0.45)
		(drill 0.1)
		(layers "F.Cu" "B.Cu")
		(net 125)
	)
	(segment
		(start 101.468462 168.619882)
		(end 101.468462 168.8785)
		(width 0.127)
		(layer "B.Cu")
		(net 125)
	)
	(segment
		(start 100.43158 167.583)
		(end 101.468462 168.619882)
		(width 0.127)
		(layer "B.Cu")
		(net 125)
	)
	(segment
		(start 100.693462 168.8785)
		(end 100.217962 168.8785)
		(width 0.15)
		(layer "B.Cu")
		(net 125)
	)
	(segment
		(start 99.992462 169.104)
		(end 100.217962 168.8785)
		(width 0.15)
		(layer "B.Cu")
		(net 125)
	)
	(segment
		(start 101.468462 168.8785)
		(end 100.693462 168.8785)
		(width 0.15)
		(layer "B.Cu")
		(net 125)
	)
	(segment
		(start 99.467962 169.104)
		(end 99.992462 169.104)
		(width 0.15)
		(layer "B.Cu")
		(net 125)
	)
	(segment
		(start 56.317962 136.3415)
		(end 52.913962 139.7455)
		(width 0.2)
		(layer "F.Cu")
		(net 126)
	)
	(segment
		(start 56.382962 135.7915)
		(end 55.844962 135.7915)
		(width 0.2)
		(layer "F.Cu")
		(net 126)
	)
	(segment
		(start 56.392962 135.7815)
		(end 56.392962 134.9265)
		(width 0.2)
		(layer "F.Cu")
		(net 126)
	)
	(segment
		(start 55.844962 135.7915)
		(end 55.369962 135.3165)
		(width 0.2)
		(layer "F.Cu")
		(net 126)
	)
	(segment
		(start 55.369962 135.3165)
		(end 55.369962 133.8335)
		(width 0.2)
		(layer "F.Cu")
		(net 126)
	)
	(segment
		(start 56.317962 135.7665)
		(end 56.317962 136.3415)
		(width 0.2)
		(layer "F.Cu")
		(net 126)
	)
	(segment
		(start 100.682962 133.8915)
		(end 100.682962 132.9415)
		(width 0.254)
		(layer "F.Cu")
		(net 127)
	)
	(segment
		(start 100.716962 130.8165)
		(end 100.716962 130.0155)
		(width 0.254)
		(layer "F.Cu")
		(net 127)
	)
	(segment
		(start 99.758962 129.0575)
		(end 99.758962 128.4165)
		(width 0.254)
		(layer "F.Cu")
		(net 127)
	)
	(segment
		(start 100.708962 131.9915)
		(end 100.708962 130.8245)
		(width 0.254)
		(layer "F.Cu")
		(net 127)
	)
	(segment
		(start 100.716962 130.0155)
		(end 99.758962 129.0575)
		(width 0.254)
		(layer "F.Cu")
		(net 127)
	)
	(segment
		(start 100.682962 132.9415)
		(end 100.682962 132.0175)
		(width 0.254)
		(layer "F.Cu")
		(net 127)
	)
	(segment
		(start 81.554961 165.153499)
		(end 82.617962 166.2165)
		(width 0.127)
		(layer "F.Cu")
		(net 128)
	)
	(segment
		(start 81.554961 164.517)
		(end 81.554961 165.153499)
		(width 0.127)
		(layer "F.Cu")
		(net 128)
	)
	(via
		(at 82.617962 166.2165)
		(size 0.45)
		(drill 0.1)
		(layers "F.Cu" "B.Cu")
		(net 128)
	)
	(segment
		(start 76.467962 158.6865)
		(end 76.822962 159.0415)
		(width 0.15)
		(layer "F.Cu")
		(net 129)
	)
	(segment
		(start 76.822962 159.0415)
		(end 77.200184 159.0415)
		(width 0.15)
		(layer "F.Cu")
		(net 129)
	)
	(segment
		(start 77.474684 159.316)
		(end 78.473961 159.316)
		(width 0.15)
		(layer "F.Cu")
		(net 129)
	)
	(segment
		(start 77.200184 159.0415)
		(end 77.474684 159.316)
		(width 0.15)
		(layer "F.Cu")
		(net 129)
	)
	(segment
		(start 80.274316 159.716)
		(end 81.554961 159.716)
		(width 0.127)
		(layer "F.Cu")
		(net 130)
	)
	(segment
		(start 79.173963 163.0235)
		(end 79.236962 162.960501)
		(width 0.127)
		(layer "F.Cu")
		(net 130)
	)
	(segment
		(start 79.236962 162.960501)
		(end 79.236962 160.753354)
		(width 0.127)
		(layer "F.Cu")
		(net 130)
	)
	(segment
		(start 79.236962 160.753354)
		(end 80.274316 159.716)
		(width 0.127)
		(layer "F.Cu")
		(net 130)
	)
	(via
		(at 79.173963 163.0235)
		(size 0.45)
		(drill 0.1)
		(layers "F.Cu" "B.Cu")
		(net 130)
	)
	(segment
		(start 86.18274 165.6065)
		(end 86.782962 165.006278)
		(width 0.127)
		(layer "B.Cu")
		(net 130)
	)
	(segment
		(start 86.782962 165.006278)
		(end 86.782962 163.7565)
		(width 0.127)
		(layer "B.Cu")
		(net 130)
	)
	(segment
		(start 78.842962 163.354501)
		(end 78.842962 164.7915)
		(width 0.127)
		(layer "B.Cu")
		(net 130)
	)
	(segment
		(start 79.657962 165.6065)
		(end 86.18274 165.6065)
		(width 0.127)
		(layer "B.Cu")
		(net 130)
	)
	(segment
		(start 78.842962 164.7915)
		(end 79.657962 165.6065)
		(width 0.127)
		(layer "B.Cu")
		(net 130)
	)
	(segment
		(start 79.173963 163.0235)
		(end 78.842962 163.354501)
		(width 0.127)
		(layer "B.Cu")
		(net 130)
	)
	(segment
		(start 82.502462 161.316)
		(end 81.554961 161.316)
		(width 0.127)
		(layer "F.Cu")
		(net 132)
	)
	(segment
		(start 82.504462 161.715)
		(end 81.554961 161.715)
		(width 0.127)
		(layer "F.Cu")
		(net 132)
	)
	(segment
		(start 80.417962 161.3415)
		(end 80.443462 161.316)
		(width 0.127)
		(layer "F.Cu")
		(net 132)
	)
	(segment
		(start 76.467962 159.6465)
		(end 76.987962 159.6465)
		(width 0.15)
		(layer "F.Cu")
		(net 132)
	)
	(segment
		(start 76.987962 159.6465)
		(end 77.092962 159.5415)
		(width 0.15)
		(layer "F.Cu")
		(net 132)
	)
	(segment
		(start 80.443462 161.316)
		(end 81.554961 161.316)
		(width 0.127)
		(layer "F.Cu")
		(net 132)
	)
	(via
		(at 77.092962 159.5415)
		(size 0.45)
		(drill 0.1)
		(layers "F.Cu" "B.Cu")
		(net 132)
	)
	(via
		(at 80.417962 161.3415)
		(size 0.45)
		(drill 0.1)
		(layers "F.Cu" "B.Cu")
		(net 132)
	)
	(segment
		(start 78.892962 161.3415)
		(end 77.092962 159.5415)
		(width 0.127)
		(layer "In2.Cu")
		(net 132)
	)
	(segment
		(start 80.417962 161.3415)
		(end 78.892962 161.3415)
		(width 0.127)
		(layer "In2.Cu")
		(net 132)
	)
	(segment
		(start 77.317962 149.1765)
		(end 77.577462 148.917)
		(width 0.127)
		(layer "F.Cu")
		(net 137)
	)
	(segment
		(start 77.577462 148.917)
		(end 78.473961 148.917)
		(width 0.127)
		(layer "F.Cu")
		(net 137)
	)
	(segment
		(start 117.095 153.7565)
		(end 117.41 153.4415)
		(width 0.17)
		(layer "F.Cu")
		(net 139)
	)
	(segment
		(start 116.119962 153.757)
		(end 116.897962 153.757)
		(width 0.17)
		(layer "F.Cu")
		(net 139)
	)
	(segment
		(start 116.898462 153.7565)
		(end 117.095 153.7565)
		(width 0.17)
		(layer "F.Cu")
		(net 139)
	)
	(segment
		(start 115.554961 153.717)
		(end 116.079962 153.717)
		(width 0.17)
		(layer "F.Cu")
		(net 139)
	)
	(segment
		(start 116.897962 153.757)
		(end 116.898462 153.7565)
		(width 0.17)
		(layer "F.Cu")
		(net 139)
	)
	(segment
		(start 116.079962 153.717)
		(end 116.119962 153.757)
		(width 0.17)
		(layer "F.Cu")
		(net 139)
	)
	(segment
		(start 140.617962 131.7365)
		(end 140.617962 130.8865)
		(width 0.127)
		(layer "F.Cu")
		(net 140)
	)
	(via
		(at 140.617962 130.8865)
		(size 0.45)
		(drill 0.1)
		(layers "F.Cu" "B.Cu")
		(net 140)
	)
	(segment
		(start 142.207962 139.8965)
		(end 139.138962 142.9655)
		(width 0.127)
		(layer "B.Cu")
		(net 140)
	)
	(segment
		(start 142.207962 134.540338)
		(end 142.207962 139.8965)
		(width 0.127)
		(layer "B.Cu")
		(net 140)
	)
	(segment
		(start 140.617962 130.8865)
		(end 140.617962 132.950338)
		(width 0.127)
		(layer "B.Cu")
		(net 140)
	)
	(segment
		(start 139.138962 142.9655)
		(end 137.467962 142.9655)
		(width 0.127)
		(layer "B.Cu")
		(net 140)
	)
	(segment
		(start 140.617962 132.950338)
		(end 142.207962 134.540338)
		(width 0.127)
		(layer "B.Cu")
		(net 140)
	)
	(segment
		(start 139.667962 133.4165)
		(end 139.652962 133.4015)
		(width 0.127)
		(layer "F.Cu")
		(net 141)
	)
	(segment
		(start 139.652962 133.4015)
		(end 139.652962 132.6765)
		(width 0.127)
		(layer "F.Cu")
		(net 141)
	)
	(via
		(at 139.667962 133.4165)
		(size 0.45)
		(drill 0.1)
		(layers "F.Cu" "B.Cu")
		(net 141)
	)
	(segment
		(start 140.727742 133.4165)
		(end 141.731463 134.420221)
		(width 0.127)
		(layer "B.Cu")
		(net 141)
	)
	(segment
		(start 141.727962 139.991278)
		(end 139.25374 142.4655)
		(width 0.127)
		(layer "B.Cu")
		(net 141)
	)
	(segment
		(start 139.25374 142.4655)
		(end 137.467962 142.4655)
		(width 0.127)
		(layer "B.Cu")
		(net 141)
	)
	(segment
		(start 141.731463 134.420221)
		(end 141.731463 134.762777)
		(width 0.127)
		(layer "B.Cu")
		(net 141)
	)
	(segment
		(start 139.667962 133.4165)
		(end 140.727742 133.4165)
		(width 0.127)
		(layer "B.Cu")
		(net 141)
	)
	(segment
		(start 141.727962 134.766278)
		(end 141.727962 139.991278)
		(width 0.127)
		(layer "B.Cu")
		(net 141)
	)
	(segment
		(start 141.731463 134.762777)
		(end 141.727962 134.766278)
		(width 0.127)
		(layer "B.Cu")
		(net 141)
	)
	(segment
		(start 79.669962 164.0145)
		(end 80.217962 163.4665)
		(width 0.127)
		(layer "F.Cu")
		(net 142)
	)
	(segment
		(start 121.717962 119.7415)
		(end 121.892962 119.7415)
		(width 0.127)
		(layer "F.Cu")
		(net 142)
	)
	(segment
		(start 120.56 175.35)
		(end 118.999 176.911)
		(width 0.127)
		(layer "F.Cu")
		(net 142)
	)
	(segment
		(start 79.06024 165.255)
		(end 79.669962 164.645278)
		(width 0.127)
		(layer "F.Cu")
		(net 142)
	)
	(segment
		(start 98.721 144.013462)
		(end 98.467962 144.2665)
		(width 0.127)
		(layer "F.Cu")
		(net 142)
	)
	(segment
		(start 121.892962 119.7415)
		(end 121.987962 119.6465)
		(width 0.127)
		(layer "F.Cu")
		(net 142)
	)
	(segment
		(start 78.067962 164.966171)
		(end 78.063537 164.961746)
		(width 0.127)
		(layer "F.Cu")
		(net 142)
	)
	(segment
		(start 80.217962 163.4665)
		(end 80.217962 162.297882)
		(width 0.127)
		(layer "F.Cu")
		(net 142)
	)
	(segment
		(start 131.142962 120.0165)
		(end 131.342962 119.8165)
		(width 0.127)
		(layer "F.Cu")
		(net 142)
	)
	(segment
		(start 78.067962 165.255)
		(end 79.06024 165.255)
		(width 0.127)
		(layer "F.Cu")
		(net 142)
	)
	(segment
		(start 70.214462 167.428222)
		(end 70.817962 168.031722)
		(width 0.127)
		(layer "F.Cu")
		(net 142)
	)
	(segment
		(start 121.987962 118.509)
		(end 121.987962 117.9115)
		(width 0.15)
		(layer "F.Cu")
		(net 142)
	)
	(segment
		(start 87.604462 155.904327)
		(end 87.489688 155.789553)
		(width 0.127)
		(layer "F.Cu")
		(net 142)
	)
	(segment
		(start 130.818962 117.6425)
		(end 130.818962 116.7665)
		(width 0.15)
		(layer "F.Cu")
		(net 142)
	)
	(segment
		(start 91.192962 150.8415)
		(end 92.367962 150.8415)
		(width 0.127)
		(layer "F.Cu")
		(net 142)
	)
	(segment
		(start 131.342962 119.329)
		(end 131.342962 118.554)
		(width 0.15)
		(layer "F.Cu")
		(net 142)
	)
	(segment
		(start 78.067962 165.255)
		(end 78.067962 164.966171)
		(width 0.127)
		(layer "F.Cu")
		(net 142)
	)
	(segment
		(start 78.067962 165.255)
		(end 71.179462 165.255)
		(width 0.127)
		(layer "F.Cu")
		(net 142)
	)
	(segment
		(start 121.987962 119.6465)
		(end 121.987962 119.284)
		(width 0.127)
		(layer "F.Cu")
		(net 142)
	)
	(segment
		(start 121.367962 118.8565)
		(end 121.367962 119.3915)
		(width 0.127)
		(layer "F.Cu")
		(net 142)
	)
	(segment
		(start 98.721 143.219024)
		(end 98.721 144.013462)
		(width 0.127)
		(layer "F.Cu")
		(net 142)
	)
	(segment
		(start 79.740962 161.820882)
		(end 79.740962 160.962118)
		(width 0.127)
		(layer "F.Cu")
		(net 142)
	)
	(segment
		(start 121.367962 119.3915)
		(end 121.717962 119.7415)
		(width 0.127)
		(layer "F.Cu")
		(net 142)
	)
	(segment
		(start 87.604462 157.78)
		(end 87.604462 155.904327)
		(width 0.127)
		(layer "F.Cu")
		(net 142)
	)
	(segment
		(start 120.56 173.1)
		(end 120.56 175.35)
		(width 0.127)
		(layer "F.Cu")
		(net 142)
	)
	(segment
		(start 70.817962 168.031722)
		(end 70.817962 168.8415)
		(width 0.127)
		(layer "F.Cu")
		(net 142)
	)
	(segment
		(start 131.342962 118.554)
		(end 131.342962 118.1665)
		(width 0.15)
		(layer "F.Cu")
		(net 142)
	)
	(segment
		(start 98.467962 144.2665)
		(end 97.966962 144.2665)
		(width 0.127)
		(layer "F.Cu")
		(net 142)
	)
	(segment
		(start 79.740962 160.962118)
		(end 80.18708 160.516)
		(width 0.127)
		(layer "F.Cu")
		(net 142)
	)
	(segment
		(start 121.987962 117.9115)
		(end 121.318962 117.2425)
		(width 0.15)
		(layer "F.Cu")
		(net 142)
	)
	(segment
		(start 84.868462 160.516)
		(end 87.604462 157.78)
		(width 0.127)
		(layer "F.Cu")
		(net 142)
	)
	(segment
		(start 70.214462 166.22)
		(end 70.214462 167.428222)
		(width 0.127)
		(layer "F.Cu")
		(net 142)
	)
	(segment
		(start 81.554961 160.516)
		(end 84.868462 160.516)
		(width 0.127)
		(layer "F.Cu")
		(net 142)
	)
	(segment
		(start 79.669962 164.645278)
		(end 79.669962 164.0145)
		(width 0.127)
		(layer "F.Cu")
		(net 142)
	)
	(segment
		(start 80.18708 160.516)
		(end 81.554961 160.516)
		(width 0.127)
		(layer "F.Cu")
		(net 142)
	)
	(segment
		(start 80.217962 162.297882)
		(end 79.740962 161.820882)
		(width 0.127)
		(layer "F.Cu")
		(net 142)
	)
	(segment
		(start 121.987962 118.509)
		(end 121.987962 119.284)
		(width 0.15)
		(layer "F.Cu")
		(net 142)
	)
	(segment
		(start 131.342962 119.8165)
		(end 131.342962 119.329)
		(width 0.127)
		(layer "F.Cu")
		(net 142)
	)
	(segment
		(start 131.342962 118.1665)
		(end 130.818962 117.6425)
		(width 0.15)
		(layer "F.Cu")
		(net 142)
	)
	(segment
		(start 71.179462 165.255)
		(end 70.214462 166.22)
		(width 0.127)
		(layer "F.Cu")
		(net 142)
	)
	(via
		(at 131.142962 120.0165)
		(size 0.45)
		(drill 0.1)
		(layers "F.Cu" "B.Cu")
		(net 142)
	)
	(via
		(at 121.367962 118.8565)
		(size 0.45)
		(drill 0.1)
		(layers "F.Cu" "B.Cu")
		(net 142)
	)
	(via
		(at 102.527962 173.2065)
		(size 0.45)
		(drill 0.1)
		(layers "F.Cu" "B.Cu")
		(net 142)
	)
	(via
		(at 98.721 143.219024)
		(size 0.45)
		(drill 0.1)
		(layers "F.Cu" "B.Cu")
		(net 142)
	)
	(via
		(at 91.192962 150.8415)
		(size 0.45)
		(drill 0.1)
		(layers "F.Cu" "B.Cu")
		(net 142)
	)
	(via
		(at 118.999 176.911)
		(size 0.45)
		(drill 0.15)
		(layers "F.Cu" "B.Cu")
		(net 142)
	)
	(via
		(at 78.063537 164.961746)
		(size 0.45)
		(drill 0.1)
		(layers "F.Cu" "B.Cu")
		(net 142)
	)
	(via
		(at 87.489688 155.789553)
		(size 0.45)
		(drill 0.1)
		(layers "F.Cu" "B.Cu")
		(net 142)
	)
	(via
		(at 120.56 173.1)
		(size 0.45)
		(drill 0.15)
		(layers "F.Cu" "B.Cu")
		(net 142)
	)
	(via
		(at 138.527962 143.9665)
		(size 0.45)
		(drill 0.1)
		(layers "F.Cu" "B.Cu")
		(net 142)
	)
	(via
		(at 141.917962 155.7365)
		(size 0.45)
		(drill 0.1)
		(layers "F.Cu" "B.Cu")
		(net 142)
	)
	(segment
		(start 138.407962 143.9665)
		(end 138.527962 143.9665)
		(width 0.127)
		(layer "B.Cu")
		(net 142)
	)
	(segment
		(start 141.917962 155.7365)
		(end 142.027962 155.6265)
		(width 0.127)
		(layer "B.Cu")
		(net 142)
	)
	(segment
		(start 142.027962 155.6265)
		(end 142.027962 146.352882)
		(width 0.127)
		(layer "B.Cu")
		(net 142)
	)
	(segment
		(start 138.406962 143.9655)
		(end 137.467962 143.9655)
		(width 0.127)
		(layer "B.Cu")
		(net 142)
	)
	(segment
		(start 95.85208 150.726)
		(end 91.308462 150.726)
		(width 0.127)
		(layer "B.Cu")
		(net 142)
	)
	(segment
		(start 98.721 143.219024)
		(end 98.721 145.678684)
		(width 0.127)
		(layer "B.Cu")
		(net 142)
	)
	(segment
		(start 101.468462 173.1795)
		(end 100.694462 173.1795)
		(width 0.15)
		(layer "B.Cu")
		(net 142)
	)
	(segment
		(start 118.996 176.908)
		(end 118.999 176.911)
		(width 0.254)
		(layer "B.Cu")
		(net 142)
	)
	(segment
		(start 98.129462 146.270222)
		(end 98.129462 148.448618)
		(width 0.127)
		(layer "B.Cu")
		(net 142)
	)
	(segment
		(start 142.027962 146.352882)
		(end 139.64158 143.9665)
		(width 0.127)
		(layer "B.Cu")
		(net 142)
	)
	(segment
		(start 91.192962 150.8415)
		(end 90.997962 151.0365)
		(width 0.127)
		(layer "B.Cu")
		(net 142)
	)
	(segment
		(start 99.892962 172.7915)
		(end 100.279962 173.1785)
		(width 0.15)
		(layer "B.Cu")
		(net 142)
	)
	(segment
		(start 90.997962 151.0365)
		(end 90.097962 151.0365)
		(width 0.127)
		(layer "B.Cu")
		(net 142)
	)
	(segment
		(start 91.308462 150.726)
		(end 91.192962 150.8415)
		(width 0.127)
		(layer "B.Cu")
		(net 142)
	)
	(segment
		(start 87.489688 153.644774)
		(end 87.489688 155.789553)
		(width 0.127)
		(layer "B.Cu")
		(net 142)
	)
	(segment
		(start 139.64158 143.9665)
		(end 138.527962 143.9665)
		(width 0.127)
		(layer "B.Cu")
		(net 142)
	)
	(segment
		(start 98.129462 148.448618)
		(end 95.85208 150.726)
		(width 0.127)
		(layer "B.Cu")
		(net 142)
	)
	(segment
		(start 117.811 176.908)
		(end 118.996 176.908)
		(width 0.254)
		(layer "B.Cu")
		(net 142)
	)
	(segment
		(start 90.097962 151.0365)
		(end 87.489688 153.644774)
		(width 0.127)
		(layer "B.Cu")
		(net 142)
	)
	(segment
		(start 138.407962 143.9665)
		(end 138.406962 143.9655)
		(width 0.127)
		(layer "B.Cu")
		(net 142)
	)
	(segment
		(start 102.527962 173.2065)
		(end 102.500962 173.1795)
		(width 0.127)
		(layer "B.Cu")
		(net 142)
	)
	(segment
		(start 100.279962 173.1785)
		(end 100.693462 173.1785)
		(width 0.15)
		(layer "B.Cu")
		(net 142)
	)
	(segment
		(start 99.467962 172.7915)
		(end 99.892962 172.7915)
		(width 0.15)
		(layer "B.Cu")
		(net 142)
	)
	(segment
		(start 102.500962 173.1795)
		(end 101.468462 173.1795)
		(width 0.127)
		(layer "B.Cu")
		(net 142)
	)
	(segment
		(start 98.721 145.678684)
		(end 98.129462 146.270222)
		(width 0.127)
		(layer "B.Cu")
		(net 142)
	)
	(segment
		(start 88.357344 172.6245)
		(end 82.897344 167.1645)
		(width 0.127)
		(layer "In2.Cu")
		(net 142)
	)
	(segment
		(start 99.857962 173.2065)
		(end 99.275962 172.6245)
		(width 0.127)
		(layer "In2.Cu")
		(net 142)
	)
	(segment
		(start 102.527962 173.2065)
		(end 99.857962 173.2065)
		(width 0.127)
		(layer "In2.Cu")
		(net 142)
	)
	(segment
		(start 99.275962 172.6245)
		(end 88.357344 172.6245)
		(width 0.127)
		(layer "In2.Cu")
		(net 142)
	)
	(segment
		(start 78.468127 165.366335)
		(end 78.063537 164.961746)
		(width 0.127)
		(layer "In2.Cu")
		(net 142)
	)
	(segment
		(start 78.968127 166.380283)
		(end 78.468127 165.880283)
		(width 0.127)
		(layer "In2.Cu")
		(net 142)
	)
	(segment
		(start 79.752344 167.1645)
		(end 78.968127 166.380283)
		(width 0.127)
		(layer "In2.Cu")
		(net 142)
	)
	(segment
		(start 82.897344 167.1645)
		(end 79.752344 167.1645)
		(width 0.127)
		(layer "In2.Cu")
		(net 142)
	)
	(segment
		(start 78.468127 165.880283)
		(end 78.468127 165.366335)
		(width 0.127)
		(layer "In2.Cu")
		(net 142)
	)
	(segment
		(start 120.56 173.1)
		(end 121.71 173.1)
		(width 0.127)
		(layer "In3.Cu")
		(net 142)
	)
	(segment
		(start 139.05174 143.9665)
		(end 141.417962 141.600278)
		(width 0.127)
		(layer "In3.Cu")
		(net 142)
	)
	(segment
		(start 142.057962 126.6565)
		(end 134.964462 119.563)
		(width 0.127)
		(layer "In3.Cu")
		(net 142)
	)
	(segment
		(start 131.142962 120.0165)
		(end 131.227962 119.9315)
		(width 0.127)
		(layer "In3.Cu")
		(net 142)
	)
	(segment
		(start 120.56 173.1)
		(end 120.13 173.1)
		(width 0.127)
		(layer "In3.Cu")
		(net 142)
	)
	(segment
		(start 138.47544 166.559022)
		(end 138.47544 158.46264)
		(width 0.127)
		(layer "In3.Cu")
		(net 142)
	)
	(segment
		(start 134.964462 119.563)
		(end 131.227962 119.563)
		(width 0.127)
		(layer "In3.Cu")
		(net 142)
	)
	(segment
		(start 138.47544 158.46264)
		(end 141.04008 155.898)
		(width 0.127)
		(layer "In3.Cu")
		(net 142)
	)
	(segment
		(start 131.227962 119.9315)
		(end 131.227962 119.563)
		(width 0.127)
		(layer "In3.Cu")
		(net 142)
	)
	(segment
		(start 141.417962 137.1765)
		(end 142.057962 136.5365)
		(width 0.127)
		(layer "In3.Cu")
		(net 142)
	)
	(segment
		(start 124.277962 118.8565)
		(end 124.984462 119.563)
		(width 0.127)
		(layer "In3.Cu")
		(net 142)
	)
	(segment
		(start 118.9195 171.8895)
		(end 103.844962 171.8895)
		(width 0.127)
		(layer "In3.Cu")
		(net 142)
	)
	(segment
		(start 142.057962 136.5365)
		(end 142.057962 126.6565)
		(width 0.127)
		(layer "In3.Cu")
		(net 142)
	)
	(segment
		(start 120.13 173.1)
		(end 118.9195 171.8895)
		(width 0.127)
		(layer "In3.Cu")
		(net 142)
	)
	(segment
		(start 122.9205 171.8895)
		(end 133.144962 171.8895)
		(width 0.127)
		(layer "In3.Cu")
		(net 142)
	)
	(segment
		(start 121.367962 118.8565)
		(end 124.277962 118.8565)
		(width 0.127)
		(layer "In3.Cu")
		(net 142)
	)
	(segment
		(start 141.417962 141.600278)
		(end 141.417962 137.1765)
		(width 0.127)
		(layer "In3.Cu")
		(net 142)
	)
	(segment
		(start 138.527962 143.9665)
		(end 139.05174 143.9665)
		(width 0.127)
		(layer "In3.Cu")
		(net 142)
	)
	(segment
		(start 141.756462 155.898)
		(end 141.917962 155.7365)
		(width 0.127)
		(layer "In3.Cu")
		(net 142)
	)
	(segment
		(start 141.04008 155.898)
		(end 141.756462 155.898)
		(width 0.127)
		(layer "In3.Cu")
		(net 142)
	)
	(segment
		(start 121.71 173.1)
		(end 122.9205 171.8895)
		(width 0.127)
		(layer "In3.Cu")
		(net 142)
	)
	(segment
		(start 124.984462 119.563)
		(end 131.227962 119.563)
		(width 0.127)
		(layer "In3.Cu")
		(net 142)
	)
	(segment
		(start 103.844962 171.8895)
		(end 102.527962 173.2065)
		(width 0.127)
		(layer "In3.Cu")
		(net 142)
	)
	(segment
		(start 133.144962 171.8895)
		(end 138.47544 166.559022)
		(width 0.127)
		(layer "In3.Cu")
		(net 142)
	)
	(segment
		(start 98.918962 146.446912)
		(end 98.918962 145.3165)
		(width 0.127)
		(layer "F.Cu")
		(net 143)
	)
	(segment
		(start 72.257462 165.507)
		(end 77.897962 165.507)
		(width 0.127)
		(layer "F.Cu")
		(net 143)
	)
	(segment
		(start 81.009306 160.917)
		(end 80.895306 160.803)
		(width 0.127)
		(layer "F.Cu")
		(net 143)
	)
	(segment
		(start 80.469962 163.570882)
		(end 79.921962 164.118882)
		(width 0.127)
		(layer "F.Cu")
		(net 143)
	)
	(segment
		(start 122.342962 120.0165)
		(end 122.487962 119.8715)
		(width 0.127)
		(layer "F.Cu")
		(net 143)
	)
	(segment
		(start 122.319962 116.7665)
		(end 122.319962 117.6495)
		(width 0.15)
		(layer "F.Cu")
		(net 143)
	)
	(segment
		(start 79.921962 164.74966)
		(end 79.164622 165.507)
		(width 0.127)
		(layer "F.Cu")
		(net 143)
	)
	(segment
		(start 131.841962 118.554)
		(end 131.841962 116.7885)
		(width 0.15)
		(layer "F.Cu")
		(net 143)
	)
	(segment
		(start 122.486962 118.509)
		(end 122.486962 117.8165)
		(width 0.15)
		(layer "F.Cu")
		(net 143)
	)
	(segment
		(start 122.319962 117.6495)
		(end 122.486962 117.8165)
		(width 0.15)
		(layer "F.Cu")
		(net 143)
	)
	(segment
		(start 79.992962 161.0665)
		(end 79.992962 161.7165)
		(width 0.127)
		(layer "F.Cu")
		(net 143)
	)
	(segment
		(start 98.868962 145.2665)
		(end 98.918962 145.3165)
		(width 0.127)
		(layer "F.Cu")
		(net 143)
	)
	(segment
		(start 80.469962 162.1935)
		(end 80.469962 163.570882)
		(width 0.127)
		(layer "F.Cu")
		(net 143)
	)
	(segment
		(start 122.486962 118.509)
		(end 122.486962 119.283)
		(width 0.15)
		(layer "F.Cu")
		(net 143)
	)
	(segment
		(start 80.895306 160.803)
		(end 80.256462 160.803)
		(width 0.127)
		(layer "F.Cu")
		(net 143)
	)
	(segment
		(start 71.817962 168.0765)
		(end 71.867962 168.0265)
		(width 0.127)
		(layer "F.Cu")
		(net 143)
	)
	(segment
		(start 79.164622 165.507)
		(end 77.897962 165.507)
		(width 0.127)
		(layer "F.Cu")
		(net 143)
	)
	(segment
		(start 87.977962 155.3465)
		(end 87.977962 157.762882)
		(width 0.127)
		(layer "F.Cu")
		(net 143)
	)
	(segment
		(start 131.842962 119.8765)
		(end 131.842962 119.329)
		(width 0.127)
		(layer "F.Cu")
		(net 143)
	)
	(segment
		(start 131.842962 119.329)
		(end 131.842962 118.555)
		(width 0.15)
		(layer "F.Cu")
		(net 143)
	)
	(segment
		(start 97.966962 145.2665)
		(end 98.868962 145.2665)
		(width 0.127)
		(layer "F.Cu")
		(net 143)
	)
	(segment
		(start 121.4 173.7)
		(end 121.4 175.78)
		(width 0.127)
		(layer "F.Cu")
		(net 143)
	)
	(segment
		(start 79.921962 164.118882)
		(end 79.921962 164.74966)
		(width 0.127)
		(layer "F.Cu")
		(net 143)
	)
	(segment
		(start 91.207962 151.4915)
		(end 92.367962 151.4915)
		(width 0.127)
		(layer "F.Cu")
		(net 143)
	)
	(segment
		(start 71.817962 168.8415)
		(end 71.817962 168.0765)
		(width 0.127)
		(layer "F.Cu")
		(net 143)
	)
	(segment
		(start 121.4 175.78)
		(end 118.999 178.181)
		(width 0.127)
		(layer "F.Cu")
		(net 143)
	)
	(segment
		(start 81.554961 160.917)
		(end 81.009306 160.917)
		(width 0.127)
		(layer "F.Cu")
		(net 143)
	)
	(segment
		(start 78.048462 165.816)
		(end 78.047962 165.8165)
		(width 0.127)
		(layer "F.Cu")
		(net 143)
	)
	(segment
		(start 80.256462 160.803)
		(end 79.992962 161.0665)
		(width 0.127)
		(layer "F.Cu")
		(net 143)
	)
	(segment
		(start 84.823844 160.917)
		(end 81.554961 160.917)
		(width 0.127)
		(layer "F.Cu")
		(net 143)
	)
	(segment
		(start 87.977962 157.762882)
		(end 84.823844 160.917)
		(width 0.127)
		(layer "F.Cu")
		(net 143)
	)
	(segment
		(start 78.048462 165.507)
		(end 78.048462 165.816)
		(width 0.127)
		(layer "F.Cu")
		(net 143)
	)
	(segment
		(start 131.742962 119.9765)
		(end 131.842962 119.8765)
		(width 0.127)
		(layer "F.Cu")
		(net 143)
	)
	(segment
		(start 71.867962 165.8965)
		(end 72.257462 165.507)
		(width 0.127)
		(layer "F.Cu")
		(net 143)
	)
	(segment
		(start 98.852234 146.51364)
		(end 98.918962 146.446912)
		(width 0.127)
		(layer "F.Cu")
		(net 143)
	)
	(segment
		(start 77.897962 165.507)
		(end 78.048462 165.507)
		(width 0.127)
		(layer "F.Cu")
		(net 143)
	)
	(segment
		(start 71.867962 168.0265)
		(end 71.867962 165.8965)
		(width 0.127)
		(layer "F.Cu")
		(net 143)
	)
	(segment
		(start 79.992962 161.7165)
		(end 80.469962 162.1935)
		(width 0.127)
		(layer "F.Cu")
		(net 143)
	)
	(segment
		(start 122.487962 119.8715)
		(end 122.487962 119.284)
		(width 0.127)
		(layer "F.Cu")
		(net 143)
	)
	(via
		(at 142.467962 156.0415)
		(size 0.45)
		(drill 0.1)
		(layers "F.Cu" "B.Cu")
		(net 143)
	)
	(via
		(at 102.137962 173.6565)
		(size 0.45)
		(drill 0.1)
		(layers "F.Cu" "B.Cu")
		(net 143)
	)
	(via
		(at 91.207962 151.4915)
		(size 0.45)
		(drill 0.1)
		(layers "F.Cu" "B.Cu")
		(net 143)
	)
	(via
		(at 87.977962 155.3465)
		(size 0.45)
		(drill 0.1)
		(layers "F.Cu" "B.Cu")
		(net 143)
	)
	(via
		(at 121.4 173.7)
		(size 0.45)
		(drill 0.15)
		(layers "F.Cu" "B.Cu")
		(net 143)
	)
	(via
		(at 78.047962 165.8165)
		(size 0.45)
		(drill 0.1)
		(layers "F.Cu" "B.Cu")
		(net 143)
	)
	(via
		(at 118.999 178.181)
		(size 0.45)
		(drill 0.15)
		(layers "F.Cu" "B.Cu")
		(net 143)
	)
	(via
		(at 98.852234 146.51364)
		(size 0.45)
		(drill 0.1)
		(layers "F.Cu" "B.Cu")
		(net 143)
	)
	(via
		(at 131.742962 119.9765)
		(size 0.45)
		(drill 0.1)
		(layers "F.Cu" "B.Cu")
		(net 143)
	)
	(via
		(at 122.342962 120.0165)
		(size 0.45)
		(drill 0.1)
		(layers "F.Cu" "B.Cu")
		(net 143)
	)
	(via
		(at 138.967962 143.4655)
		(size 0.45)
		(drill 0.1)
		(layers "F.Cu" "B.Cu")
		(net 143)
	)
	(segment
		(start 91.207962 151.4915)
		(end 91.004962 151.2885)
		(width 0.127)
		(layer "B.Cu")
		(net 143)
	)
	(segment
		(start 142.331462 146.3)
		(end 139.496962 143.4655)
		(width 0.127)
		(layer "B.Cu")
		(net 143)
	)
	(segment
		(start 91.721462 150.978)
		(end 91.207962 151.4915)
		(width 0.127)
		(layer "B.Cu")
		(net 143)
	)
	(segment
		(start 118.996 178.178)
		(end 118.999 178.181)
		(width 0.254)
		(layer "B.Cu")
		(net 143)
	)
	(segment
		(start 90.211184 151.2885)
		(end 87.977962 153.521722)
		(width 0.127)
		(layer "B.Cu")
		(net 143)
	)
	(segment
		(start 99.943462 173.429)
		(end 100.192962 173.6785)
		(width 0.15)
		(layer "B.Cu")
		(net 143)
	)
	(segment
		(start 139.496962 143.4655)
		(end 138.967962 143.4655)
		(width 0.127)
		(layer "B.Cu")
		(net 143)
	)
	(segment
		(start 96.106462 150.978)
		(end 91.721462 150.978)
		(width 0.127)
		(layer "B.Cu")
		(net 143)
	)
	(segment
		(start 87.977962 153.521722)
		(end 87.977962 155.3465)
		(width 0.127)
		(layer "B.Cu")
		(net 143)
	)
	(segment
		(start 101.468462 173.6785)
		(end 100.693462 173.6785)
		(width 0.15)
		(layer "B.Cu")
		(net 143)
	)
	(segment
		(start 142.331462 155.905)
		(end 142.331462 146.3)
		(width 0.127)
		(layer "B.Cu")
		(net 143)
	)
	(segment
		(start 137.467962 143.4655)
		(end 138.967962 143.4655)
		(width 0.127)
		(layer "B.Cu")
		(net 143)
	)
	(segment
		(start 98.852234 146.51364)
		(end 98.852234 146.63555)
		(width 0.127)
		(layer "B.Cu")
		(net 143)
	)
	(segment
		(start 117.811 178.178)
		(end 118.996 178.178)
		(width 0.254)
		(layer "B.Cu")
		(net 143)
	)
	(segment
		(start 100.192962 173.6785)
		(end 100.693462 173.6785)
		(width 0.15)
		(layer "B.Cu")
		(net 143)
	)
	(segment
		(start 91.004962 151.2885)
		(end 90.211184 151.2885)
		(width 0.127)
		(layer "B.Cu")
		(net 143)
	)
	(segment
		(start 99.142962 147.9415)
		(end 96.106462 150.978)
		(width 0.127)
		(layer "B.Cu")
		(net 143)
	)
	(segment
		(start 99.467962 173.429)
		(end 99.943462 173.429)
		(width 0.15)
		(layer "B.Cu")
		(net 143)
	)
	(segment
		(start 102.115962 173.6785)
		(end 102.137962 173.6565)
		(width 0.127)
		(layer "B.Cu")
		(net 143)
	)
	(segment
		(start 101.468462 173.6785)
		(end 102.115962 173.6785)
		(width 0.127)
		(layer "B.Cu")
		(net 143)
	)
	(segment
		(start 142.467962 156.0415)
		(end 142.331462 155.905)
		(width 0.127)
		(layer "B.Cu")
		(net 143)
	)
	(segment
		(start 98.852234 146.63555)
		(end 99.142962 146.926278)
		(width 0.127)
		(layer "B.Cu")
		(net 143)
	)
	(segment
		(start 99.142962 146.926278)
		(end 99.142962 147.9415)
		(width 0.127)
		(layer "B.Cu")
		(net 143)
	)
	(segment
		(start 78.047962 165.8165)
		(end 79.647962 167.4165)
		(width 0.127)
		(layer "In2.Cu")
		(net 143)
	)
	(segment
		(start 99.95158 173.6565)
		(end 102.137962 173.6565)
		(width 0.127)
		(layer "In2.Cu")
		(net 143)
	)
	(segment
		(start 79.647962 167.4165)
		(end 82.792962 167.4165)
		(width 0.127)
		(layer "In2.Cu")
		(net 143)
	)
	(segment
		(start 99.17158 172.8765)
		(end 99.95158 173.6565)
		(width 0.127)
		(layer "In2.Cu")
		(net 143)
	)
	(segment
		(start 82.792962 167.4165)
		(end 88.252962 172.8765)
		(width 0.127)
		(layer "In2.Cu")
		(net 143)
	)
	(segment
		(start 88.252962 172.8765)
		(end 99.17158 172.8765)
		(width 0.127)
		(layer "In2.Cu")
		(net 143)
	)
	(segment
		(start 131.857962 120.0915)
		(end 131.857962 120.455)
		(width 0.127)
		(layer "In3.Cu")
		(net 143)
	)
	(segment
		(start 124.49358 119.4285)
		(end 125.52008 120.455)
		(width 0.127)
		(layer "In3.Cu")
		(net 143)
	)
	(segment
		(start 141.797962 136.440118)
		(end 141.797962 126.752882)
		(width 0.127)
		(layer "In3.Cu")
		(net 143)
	)
	(segment
		(start 141.144462 156.15)
		(end 142.359462 156.15)
		(width 0.127)
		(layer "In3.Cu")
		(net 143)
	)
	(segment
		(start 118.3615 172.1415)
		(end 104.232962 172.1415)
		(width 0.127)
		(layer "In3.Cu")
		(net 143)
	)
	(segment
		(start 121.91 173.7)
		(end 123.4685 172.1415)
		(width 0.127)
		(layer "In3.Cu")
		(net 143)
	)
	(segment
		(start 122.342962 119.880518)
		(end 122.79498 119.4285)
		(width 0.127)
		(layer "In3.Cu")
		(net 143)
	)
	(segment
		(start 138.72744 158.567022)
		(end 141.144462 156.15)
		(width 0.127)
		(layer "In3.Cu")
		(net 143)
	)
	(segment
		(start 122.79498 119.4285)
		(end 124.49358 119.4285)
		(width 0.127)
		(layer "In3.Cu")
		(net 143)
	)
	(segment
		(start 142.359462 156.15)
		(end 142.467962 156.0415)
		(width 0.127)
		(layer "In3.Cu")
		(net 143)
	)
	(segment
		(start 125.52008 120.455)
		(end 131.857962 120.455)
		(width 0.127)
		(layer "In3.Cu")
		(net 143)
	)
	(segment
		(start 122.342962 120.0165)
		(end 122.342962 119.880518)
		(width 0.127)
		(layer "In3.Cu")
		(net 143)
	)
	(segment
		(start 138.967962 143.4655)
		(end 141.165962 141.2675)
		(width 0.127)
		(layer "In3.Cu")
		(net 143)
	)
	(segment
		(start 141.165962 137.072118)
		(end 141.797962 136.440118)
		(width 0.127)
		(layer "In3.Cu")
		(net 143)
	)
	(segment
		(start 135.50008 120.455)
		(end 131.857962 120.455)
		(width 0.127)
		(layer "In3.Cu")
		(net 143)
	)
	(segment
		(start 131.742962 119.9765)
		(end 131.857962 120.0915)
		(width 0.127)
		(layer "In3.Cu")
		(net 143)
	)
	(segment
		(start 104.232962 172.1415)
		(end 102.717962 173.6565)
		(width 0.127)
		(layer "In3.Cu")
		(net 143)
	)
	(segment
		(start 119.92 173.7)
		(end 118.3615 172.1415)
		(width 0.127)
		(layer "In3.Cu")
		(net 143)
	)
	(segment
		(start 123.4685 172.1415)
		(end 133.249344 172.1415)
		(width 0.127)
		(layer "In3.Cu")
		(net 143)
	)
	(segment
		(start 141.797962 126.752882)
		(end 135.50008 120.455)
		(width 0.127)
		(layer "In3.Cu")
		(net 143)
	)
	(segment
		(start 121.4 173.7)
		(end 119.92 173.7)
		(width 0.127)
		(layer "In3.Cu")
		(net 143)
	)
	(segment
		(start 121.4 173.7)
		(end 121.91 173.7)
		(width 0.127)
		(layer "In3.Cu")
		(net 143)
	)
	(segment
		(start 141.165962 141.2675)
		(end 141.165962 137.072118)
		(width 0.127)
		(layer "In3.Cu")
		(net 143)
	)
	(segment
		(start 138.72744 166.663404)
		(end 138.72744 158.567022)
		(width 0.127)
		(layer "In3.Cu")
		(net 143)
	)
	(segment
		(start 102.717962 173.6565)
		(end 102.137962 173.6565)
		(width 0.127)
		(layer "In3.Cu")
		(net 143)
	)
	(segment
		(start 133.249344 172.1415)
		(end 138.72744 166.663404)
		(width 0.127)
		(layer "In3.Cu")
		(net 143)
	)
	(segment
		(start 115.018462 144.916)
		(end 114.842962 145.0915)
		(width 0.127)
		(layer "F.Cu")
		(net 144)
	)
	(segment
		(start 114.842962 145.0915)
		(end 114.842962 145.2665)
		(width 0.127)
		(layer "F.Cu")
		(net 144)
	)
	(segment
		(start 115.554961 144.916)
		(end 115.018462 144.916)
		(width 0.127)
		(layer "F.Cu")
		(net 144)
	)
	(via
		(at 119.917962 119.1415)
		(size 0.45)
		(drill 0.1)
		(layers "F.Cu" "B.Cu")
		(net 144)
	)
	(via
		(at 114.842962 145.2665)
		(size 0.45)
		(drill 0.1)
		(layers "F.Cu" "B.Cu")
		(net 144)
	)
	(segment
		(start 120.619962 121.268)
		(end 121.466462 121.268)
		(width 0.2)
		(layer "B.Cu")
		(net 144)
	)
	(segment
		(start 120.077962 118.6265)
		(end 120.041462 118.6265)
		(width 0.2)
		(layer "B.Cu")
		(net 144)
	)
	(segment
		(start 121.847962 120.8865)
		(end 121.847962 119.622)
		(width 0.2)
		(layer "B.Cu")
		(net 144)
	)
	(segment
		(start 121.619962 119.394)
		(end 120.845462 119.394)
		(width 0.2)
		(layer "B.Cu")
		(net 144)
	)
	(segment
		(start 120.041462 118.6265)
		(end 119.917962 118.75)
		(width 0.2)
		(layer "B.Cu")
		(net 144)
	)
	(segment
		(start 119.72 118.6265)
		(end 119.917962 118.6265)
		(width 0.2)
		(layer "B.Cu")
		(net 144)
	)
	(segment
		(start 121.847962 119.622)
		(end 121.619962 119.394)
		(width 0.2)
		(layer "B.Cu")
		(net 144)
	)
	(segment
		(start 121.466462 121.268)
		(end 121.847962 120.8865)
		(width 0.2)
		(layer "B.Cu")
		(net 144)
	)
	(segment
		(start 119.794462 118.6265)
		(end 119.917962 118.75)
		(width 0.2)
		(layer "B.Cu")
		(net 144)
	)
	(segment
		(start 120.845462 119.394)
		(end 120.077962 118.6265)
		(width 0.2)
		(layer "B.Cu")
		(net 144)
	)
	(segment
		(start 119.917962 118.6265)
		(end 119.917962 118.75)
		(width 0.2)
		(layer "B.Cu")
		(net 144)
	)
	(segment
		(start 120.077962 118.6265)
		(end 119.917962 118.6265)
		(width 0.2)
		(layer "B.Cu")
		(net 144)
	)
	(segment
		(start 118.892962 118.6265)
		(end 119.72 118.6265)
		(width 0.2)
		(layer "B.Cu")
		(net 144)
	)
	(segment
		(start 119.917962 118.75)
		(end 119.917962 119.1415)
		(width 0.2)
		(layer "B.Cu")
		(net 144)
	)
	(segment
		(start 119.72 118.6265)
		(end 119.794462 118.6265)
		(width 0.2)
		(layer "B.Cu")
		(net 144)
	)
	(segment
		(start 120.414462 139.695)
		(end 120.414462 119.638)
		(width 0.127)
		(layer "In2.Cu")
		(net 144)
	)
	(segment
		(start 114.842962 145.2665)
		(end 120.414462 139.695)
		(width 0.127)
		(layer "In2.Cu")
		(net 144)
	)
	(segment
		(start 120.414462 119.638)
		(end 119.917962 119.1415)
		(width 0.127)
		(layer "In2.Cu")
		(net 144)
	)
	(segment
		(start 111.852962 146.518)
		(end 112.473961 146.518)
		(width 0.127)
		(layer "F.Cu")
		(net 145)
	)
	(segment
		(start 111.517962 146.853)
		(end 111.852962 146.518)
		(width 0.127)
		(layer "F.Cu")
		(net 145)
	)
	(via
		(at 111.517962 146.853)
		(size 0.45)
		(drill 0.1)
		(layers "F.Cu" "B.Cu")
		(net 145)
	)
	(via
		(at 118.717962 121.2915)
		(size 0.45)
		(drill 0.1)
		(layers "F.Cu" "B.Cu")
		(net 145)
	)
	(segment
		(start 119.716462 121.768)
		(end 120.619962 121.768)
		(width 0.2)
		(layer "B.Cu")
		(net 145)
	)
	(segment
		(start 118.717962 121.6165)
		(end 119.082962 121.9815)
		(width 0.2)
		(layer "B.Cu")
		(net 145)
	)
	(segment
		(start 119.092962 121.9815)
		(end 119.502962 121.9815)
		(width 0.2)
		(layer "B.Cu")
		(net 145)
	)
	(segment
		(start 119.502962 121.9815)
		(end 119.716462 121.768)
		(width 0.2)
		(layer "B.Cu")
		(net 145)
	)
	(segment
		(start 118.717962 121.2915)
		(end 118.717962 121.6165)
		(width 0.2)
		(layer "B.Cu")
		(net 145)
	)
	(segment
		(start 119.781462 138.703)
		(end 119.781462 122.355)
		(width 0.127)
		(layer "In2.Cu")
		(net 145)
	)
	(segment
		(start 111.631462 146.853)
		(end 119.781462 138.703)
		(width 0.127)
		(layer "In2.Cu")
		(net 145)
	)
	(segment
		(start 119.781462 122.355)
		(end 118.717962 121.2915)
		(width 0.127)
		(layer "In2.Cu")
		(net 145)
	)
	(segment
		(start 111.517962 146.853)
		(end 111.631462 146.853)
		(width 0.127)
		(layer "In2.Cu")
		(net 145)
	)
	(segment
		(start 116.120462 154.0765)
		(end 117.095 154.0765)
		(width 0.17)
		(layer "F.Cu")
		(net 146)
	)
	(segment
		(start 115.554961 154.117)
		(end 116.079962 154.117)
		(width 0.17)
		(layer "F.Cu")
		(net 146)
	)
	(segment
		(start 116.079962 154.117)
		(end 116.120462 154.0765)
		(width 0.17)
		(layer "F.Cu")
		(net 146)
	)
	(segment
		(start 117.095 154.0765)
		(end 117.41 154.3915)
		(width 0.17)
		(layer "F.Cu")
		(net 146)
	)
	(segment
		(start 119.82 154.6415)
		(end 119.795 154.6415)
		(width 0.17)
		(layer "F.Cu")
		(net 147)
	)
	(segment
		(start 116.119462 154.9565)
		(end 116.079962 154.917)
		(width 0.17)
		(layer "F.Cu")
		(net 147)
	)
	(segment
		(start 119.795 154.6415)
		(end 119.48 154.9565)
		(width 0.17)
		(layer "F.Cu")
		(net 147)
	)
	(segment
		(start 119.48 154.9565)
		(end 116.119462 154.9565)
		(width 0.17)
		(layer "F.Cu")
		(net 147)
	)
	(segment
		(start 116.079962 154.917)
		(end 115.554961 154.917)
		(width 0.17)
		(layer "F.Cu")
		(net 147)
	)
	(segment
		(start 116.119462 155.2765)
		(end 116.079962 155.316)
		(width 0.17)
		(layer "F.Cu")
		(net 148)
	)
	(segment
		(start 119.82 155.5915)
		(end 119.795 155.5915)
		(width 0.17)
		(layer "F.Cu")
		(net 148)
	)
	(segment
		(start 119.48 155.2765)
		(end 116.119462 155.2765)
		(width 0.17)
		(layer "F.Cu")
		(net 148)
	)
	(segment
		(start 116.079962 155.316)
		(end 115.554961 155.316)
		(width 0.17)
		(layer "F.Cu")
		(net 148)
	)
	(segment
		(start 119.795 155.5915)
		(end 119.48 155.2765)
		(width 0.17)
		(layer "F.Cu")
		(net 148)
	)
	(segment
		(start 111.94896 156.115)
		(end 111.90796 156.156)
		(width 0.17)
		(layer "F.Cu")
		(net 149)
	)
	(segment
		(start 111.90796 156.156)
		(end 109.115504 156.156)
		(width 0.17)
		(layer "F.Cu")
		(net 149)
	)
	(segment
		(start 112.473961 156.115)
		(end 111.94896 156.115)
		(width 0.17)
		(layer "F.Cu")
		(net 149)
	)
	(segment
		(start 109.115004 156.1565)
		(end 108.92 156.1565)
		(width 0.17)
		(layer "F.Cu")
		(net 149)
	)
	(segment
		(start 108.92 156.1565)
		(end 108.605 155.8415)
		(width 0.17)
		(layer "F.Cu")
		(net 149)
	)
	(segment
		(start 109.115504 156.156)
		(end 109.115004 156.1565)
		(width 0.17)
		(layer "F.Cu")
		(net 149)
	)
	(segment
		(start 108.605 155.8415)
		(end 108.58 155.8415)
		(width 0.17)
		(layer "F.Cu")
		(net 149)
	)
	(segment
		(start 116.121462 156.1565)
		(end 117.055 156.1565)
		(width 0.17)
		(layer "F.Cu")
		(net 150)
	)
	(segment
		(start 115.554961 156.115)
		(end 116.079962 156.115)
		(width 0.17)
		(layer "F.Cu")
		(net 150)
	)
	(segment
		(start 117.055 156.1565)
		(end 117.37 155.8415)
		(width 0.17)
		(layer "F.Cu")
		(net 150)
	)
	(segment
		(start 116.079962 156.115)
		(end 116.121462 156.1565)
		(width 0.17)
		(layer "F.Cu")
		(net 150)
	)
	(segment
		(start 111.90796 156.476)
		(end 109.237962 156.476)
		(width 0.17)
		(layer "F.Cu")
		(net 151)
	)
	(segment
		(start 108.605 156.7915)
		(end 108.58 156.7915)
		(width 0.17)
		(layer "F.Cu")
		(net 151)
	)
	(segment
		(start 108.92 156.4765)
		(end 108.605 156.7915)
		(width 0.17)
		(layer "F.Cu")
		(net 151)
	)
	(segment
		(start 111.94896 156.517)
		(end 111.90796 156.476)
		(width 0.17)
		(layer "F.Cu")
		(net 151)
	)
	(segment
		(start 109.237462 156.4765)
		(end 108.92 156.4765)
		(width 0.17)
		(layer "F.Cu")
		(net 151)
	)
	(segment
		(start 112.473961 156.517)
		(end 111.94896 156.517)
		(width 0.17)
		(layer "F.Cu")
		(net 151)
	)
	(segment
		(start 109.237962 156.476)
		(end 109.237462 156.4765)
		(width 0.17)
		(layer "F.Cu")
		(net 151)
	)
	(segment
		(start 117.049206 156.476)
		(end 117.049706 156.4765)
		(width 0.17)
		(layer "F.Cu")
		(net 152)
	)
	(segment
		(start 116.120962 156.476)
		(end 117.049206 156.476)
		(width 0.17)
		(layer "F.Cu")
		(net 152)
	)
	(segment
		(start 117.055 156.4765)
		(end 117.37 156.7915)
		(width 0.17)
		(layer "F.Cu")
		(net 152)
	)
	(segment
		(start 115.554961 156.517)
		(end 116.079962 156.517)
		(width 0.17)
		(layer "F.Cu")
		(net 152)
	)
	(segment
		(start 116.079962 156.517)
		(end 116.120962 156.476)
		(width 0.17)
		(layer "F.Cu")
		(net 152)
	)
	(segment
		(start 112.002981 157.3565)
		(end 112.184461 157.3565)
		(width 0.17)
		(layer "F.Cu")
		(net 153)
	)
	(segment
		(start 111.771464 157.3665)
		(end 111.992981 157.3665)
		(width 0.17)
		(layer "F.Cu")
		(net 153)
	)
	(segment
		(start 112.223961 157.317)
		(end 112.473961 157.317)
		(width 0.17)
		(layer "F.Cu")
		(net 153)
	)
	(segment
		(start 111.431464 157.0515)
		(end 111.456464 157.0515)
		(width 0.17)
		(layer "F.Cu")
		(net 153)
	)
	(segment
		(start 112.184461 157.3565)
		(end 112.223961 157.317)
		(width 0.17)
		(layer "F.Cu")
		(net 153)
	)
	(segment
		(start 111.992981 157.3665)
		(end 112.002981 157.3565)
		(width 0.17)
		(layer "F.Cu")
		(net 153)
	)
	(segment
		(start 111.456464 157.0515)
		(end 111.771464 157.3665)
		(width 0.17)
		(layer "F.Cu")
		(net 153)
	)
	(segment
		(start 116.119462 157.3565)
		(end 116.079962 157.317)
		(width 0.17)
		(layer "F.Cu")
		(net 154)
	)
	(segment
		(start 119.505 157.3565)
		(end 116.119462 157.3565)
		(width 0.17)
		(layer "F.Cu")
		(net 154)
	)
	(segment
		(start 116.079962 157.317)
		(end 115.554961 157.317)
		(width 0.17)
		(layer "F.Cu")
		(net 154)
	)
	(segment
		(start 119.82 157.0415)
		(end 119.505 157.3565)
		(width 0.17)
		(layer "F.Cu")
		(net 154)
	)
	(segment
		(start 112.223961 157.716)
		(end 112.473961 157.716)
		(width 0.17)
		(layer "F.Cu")
		(net 155)
	)
	(segment
		(start 111.771464 157.6865)
		(end 112.115439 157.6865)
		(width 0.17)
		(layer "F.Cu")
		(net 155)
	)
	(segment
		(start 112.184461 157.6765)
		(end 112.223961 157.716)
		(width 0.17)
		(layer "F.Cu")
		(net 155)
	)
	(segment
		(start 111.456464 158.0015)
		(end 111.771464 157.6865)
		(width 0.17)
		(layer "F.Cu")
		(net 155)
	)
	(segment
		(start 112.125439 157.6765)
		(end 112.184461 157.6765)
		(width 0.17)
		(layer "F.Cu")
		(net 155)
	)
	(segment
		(start 111.431464 158.0015)
		(end 111.456464 158.0015)
		(width 0.17)
		(layer "F.Cu")
		(net 155)
	)
	(segment
		(start 112.115439 157.6865)
		(end 112.125439 157.6765)
		(width 0.17)
		(layer "F.Cu")
		(net 155)
	)
	(segment
		(start 119.505 157.6765)
		(end 116.119462 157.6765)
		(width 0.17)
		(layer "F.Cu")
		(net 156)
	)
	(segment
		(start 119.82 157.9915)
		(end 119.505 157.6765)
		(width 0.17)
		(layer "F.Cu")
		(net 156)
	)
	(segment
		(start 116.079962 157.716)
		(end 115.554961 157.716)
		(width 0.17)
		(layer "F.Cu")
		(net 156)
	)
	(segment
		(start 116.119462 157.6765)
		(end 116.079962 157.716)
		(width 0.17)
		(layer "F.Cu")
		(net 156)
	)
	(segment
		(start 121.12 157.6765)
		(end 124.254238 157.6765)
		(width 0.17)
		(layer "F.Cu")
		(net 158)
	)
	(segment
		(start 130.377962 132.748313)
		(end 130.896465 132.22981)
		(width 0.17)
		(layer "F.Cu")
		(net 158)
	)
	(segment
		(start 130.896465 132.22981)
		(end 131.12981 132.22981)
		(width 0.17)
		(layer "F.Cu")
		(net 158)
	)
	(segment
		(start 120.78 157.9915)
		(end 120.805 157.9915)
		(width 0.17)
		(layer "F.Cu")
		(net 158)
	)
	(segment
		(start 120.805 157.9915)
		(end 121.12 157.6765)
		(width 0.17)
		(layer "F.Cu")
		(net 158)
	)
	(segment
		(start 130.377962 151.552776)
		(end 130.377962 132.748313)
		(width 0.17)
		(layer "F.Cu")
		(net 158)
	)
	(segment
		(start 124.254238 157.6765)
		(end 130.377962 151.552776)
		(width 0.17)
		(layer "F.Cu")
		(net 158)
	)
	(via
		(at 131.12981 132.22981)
		(size 0.5)
		(drill 0.15)
		(layers "F.Cu" "B.Cu")
		(net 158)
	)
	(segment
		(start 128.167962 133.02)
		(end 129.330463 133.02)
		(width 0.17)
		(layer "B.Cu")
		(net 158)
	)
	(segment
		(start 129.330463 133.02)
		(end 129.420963 132.9295)
		(width 0.17)
		(layer "B.Cu")
		(net 158)
	)
	(segment
		(start 130.896465 132.22981)
		(end 131.12981 132.22981)
		(width 0.17)
		(layer "B.Cu")
		(net 158)
	)
	(segment
		(start 129.420963 132.9295)
		(end 130.196775 132.9295)
		(width 0.17)
		(layer "B.Cu")
		(net 158)
	)
	(segment
		(start 130.196775 132.9295)
		(end 130.896465 132.22981)
		(width 0.17)
		(layer "B.Cu")
		(net 158)
	)
	(segment
		(start 124.121686 157.3565)
		(end 124.731884 156.746302)
		(width 0.17)
		(layer "F.Cu")
		(net 159)
	)
	(segment
		(start 120.78 157.0415)
		(end 120.805 157.0415)
		(width 0.17)
		(layer "F.Cu")
		(net 159)
	)
	(segment
		(start 126.498416 154.97977)
		(end 130.057962 151.420224)
		(width 0.17)
		(layer "F.Cu")
		(net 159)
	)
	(segment
		(start 120.805 157.0415)
		(end 121.12 157.3565)
		(width 0.17)
		(layer "F.Cu")
		(net 159)
	)
	(segment
		(start 130.057962 132.615763)
		(end 130.67019 132.003535)
		(width 0.17)
		(layer "F.Cu")
		(net 159)
	)
	(segment
		(start 124.731884 156.089444)
		(end 124.82772 155.993609)
		(width 0.17)
		(layer "F.Cu")
		(net 159)
	)
	(segment
		(start 125.580414 155.897773)
		(end 126.498416 154.97977)
		(width 0.17)
		(layer "F.Cu")
		(net 159)
	)
	(segment
		(start 130.057962 151.420224)
		(end 130.057962 132.615763)
		(width 0.17)
		(layer "F.Cu")
		(net 159)
	)
	(segment
		(start 125.48458 155.993609)
		(end 125.580414 155.897773)
		(width 0.17)
		(layer "F.Cu")
		(net 159)
	)
	(segment
		(start 121.12 157.3565)
		(end 124.121686 157.3565)
		(width 0.17)
		(layer "F.Cu")
		(net 159)
	)
	(segment
		(start 130.67019 132.003535)
		(end 130.67019 131.77019)
		(width 0.17)
		(layer "F.Cu")
		(net 159)
	)
	(via
		(at 130.67019 131.77019)
		(size 0.5)
		(drill 0.15)
		(layers "F.Cu" "B.Cu")
		(net 159)
	)
	(arc
		(start 124.82772 155.993609)
		(mid 124.991934 155.92559)
		(end 125.15615 155.993609)
		(width 0.17)
		(layer "F.Cu")
		(net 159)
	)
	(arc
		(start 125.15615 155.993609)
		(mid 125.320364 156.06163)
		(end 125.48458 155.993609)
		(width 0.17)
		(layer "F.Cu")
		(net 159)
	)
	(arc
		(start 124.731885 156.417872)
		(mid 124.663866 156.253657)
		(end 124.731884 156.089444)
		(width 0.17)
		(layer "F.Cu")
		(net 159)
	)
	(arc
		(start 124.731884 156.746302)
		(mid 124.799904 156.582088)
		(end 124.731885 156.417872)
		(width 0.17)
		(layer "F.Cu")
		(net 159)
	)
	(segment
		(start 128.167962 132.519)
		(end 129.330463 132.519)
		(width 0.17)
		(layer "B.Cu")
		(net 159)
	)
	(segment
		(start 129.420963 132.6095)
		(end 130.064225 132.6095)
		(width 0.17)
		(layer "B.Cu")
		(net 159)
	)
	(segment
		(start 129.330463 132.519)
		(end 129.420963 132.6095)
		(width 0.17)
		(layer "B.Cu")
		(net 159)
	)
	(segment
		(start 130.064225 132.6095)
		(end 130.67019 132.003535)
		(width 0.17)
		(layer "B.Cu")
		(net 159)
	)
	(segment
		(start 130.67019 132.003535)
		(end 130.67019 131.77019)
		(width 0.17)
		(layer "B.Cu")
		(net 159)
	)
	(segment
		(start 110.471464 157.0515)
		(end 110.446464 157.0515)
		(width 0.17)
		(layer "F.Cu")
		(net 160)
	)
	(segment
		(start 110.038627 157.3665)
		(end 110.038626 157.366499)
		(width 0.17)
		(layer "F.Cu")
		(net 160)
	)
	(segment
		(start 110.131464 157.3665)
		(end 110.038627 157.3665)
		(width 0.17)
		(layer "F.Cu")
		(net 160)
	)
	(segment
		(start 110.446464 157.0515)
		(end 110.131464 157.3665)
		(width 0.17)
		(layer "F.Cu")
		(net 160)
	)
	(segment
		(start 109.979168 157.366499)
		(end 109.814169 157.2015)
		(width 0.17)
		(layer "F.Cu")
		(net 160)
	)
	(segment
		(start 110.038626 157.366499)
		(end 109.979168 157.366499)
		(width 0.17)
		(layer "F.Cu")
		(net 160)
	)
	(via
		(at 109.814169 157.2015)
		(size 0.5)
		(drill 0.15)
		(layers "F.Cu" "B.Cu")
		(net 160)
	)
	(segment
		(start 108.576948 155.020359)
		(end 108.474 155.020359)
		(width 0.17)
		(layer "B.Cu")
		(net 160)
	)
	(segment
		(start 108.31 146.050738)
		(end 112.674238 141.6865)
		(width 0.17)
		(layer "B.Cu")
		(net 160)
	)
	(segment
		(start 126.915461 131.429)
		(end 127.005461 131.519)
		(width 0.17)
		(layer "B.Cu")
		(net 160)
	)
	(segment
		(start 127.005461 131.519)
		(end 128.167962 131.519)
		(width 0.17)
		(layer "B.Cu")
		(net 160)
	)
	(segment
		(start 108.690945 156.086359)
		(end 108.690945 156.004359)
		(width 0.17)
		(layer "B.Cu")
		(net 160)
	)
	(segment
		(start 108.31 154.856359)
		(end 108.31 154.774359)
		(width 0.17)
		(layer "B.Cu")
		(net 160)
	)
	(segment
		(start 108.842775 157.366499)
		(end 108.31 156.833724)
		(width 0.17)
		(layer "B.Cu")
		(net 160)
	)
	(segment
		(start 125.337962 137.492776)
		(end 125.337962 131.972776)
		(width 0.17)
		(layer "B.Cu")
		(net 160)
	)
	(segment
		(start 108.31 153.534275)
		(end 108.31 146.050738)
		(width 0.17)
		(layer "B.Cu")
		(net 160)
	)
	(segment
		(start 108.474 156.250359)
		(end 108.526945 156.250359)
		(width 0.17)
		(layer "B.Cu")
		(net 160)
	)
	(segment
		(start 121.144238 141.6865)
		(end 125.337962 137.492776)
		(width 0.17)
		(layer "B.Cu")
		(net 160)
	)
	(segment
		(start 112.674238 141.6865)
		(end 121.144238 141.6865)
		(width 0.17)
		(layer "B.Cu")
		(net 160)
	)
	(segment
		(start 109.814169 157.2015)
		(end 109.64917 157.366499)
		(width 0.17)
		(layer "B.Cu")
		(net 160)
	)
	(segment
		(start 108.31 154.774359)
		(end 108.31 153.534275)
		(width 0.17)
		(layer "B.Cu")
		(net 160)
	)
	(segment
		(start 108.526945 155.840359)
		(end 108.474 155.840359)
		(width 0.17)
		(layer "B.Cu")
		(net 160)
	)
	(segment
		(start 108.31 155.676359)
		(end 108.31 155.594359)
		(width 0.17)
		(layer "B.Cu")
		(net 160)
	)
	(segment
		(start 108.474 155.430359)
		(end 108.576948 155.430359)
		(width 0.17)
		(layer "B.Cu")
		(net 160)
	)
	(segment
		(start 108.740948 155.266359)
		(end 108.740948 155.184359)
		(width 0.17)
		(layer "B.Cu")
		(net 160)
	)
	(segment
		(start 125.881738 131.429)
		(end 126.915461 131.429)
		(width 0.17)
		(layer "B.Cu")
		(net 160)
	)
	(segment
		(start 109.64917 157.366499)
		(end 108.842775 157.366499)
		(width 0.17)
		(layer "B.Cu")
		(net 160)
	)
	(segment
		(start 108.31 156.833724)
		(end 108.31 156.414359)
		(width 0.17)
		(layer "B.Cu")
		(net 160)
	)
	(segment
		(start 125.337962 131.972776)
		(end 125.881738 131.429)
		(width 0.17)
		(layer "B.Cu")
		(net 160)
	)
	(arc
		(start 108.740948 155.184359)
		(mid 108.692914 155.068393)
		(end 108.576948 155.020359)
		(width 0.17)
		(layer "B.Cu")
		(net 160)
	)
	(arc
		(start 108.690945 156.004359)
		(mid 108.642911 155.888393)
		(end 108.526945 155.840359)
		(width 0.17)
		(layer "B.Cu")
		(net 160)
	)
	(arc
		(start 108.526945 156.250359)
		(mid 108.642911 156.202325)
		(end 108.690945 156.086359)
		(width 0.17)
		(layer "B.Cu")
		(net 160)
	)
	(arc
		(start 108.576948 155.430359)
		(mid 108.692914 155.382325)
		(end 108.740948 155.266359)
		(width 0.17)
		(layer "B.Cu")
		(net 160)
	)
	(arc
		(start 108.474 155.020359)
		(mid 108.358034 154.972325)
		(end 108.31 154.856359)
		(width 0.17)
		(layer "B.Cu")
		(net 160)
	)
	(arc
		(start 108.31 155.594359)
		(mid 108.358034 155.478393)
		(end 108.474 155.430359)
		(width 0.17)
		(layer "B.Cu")
		(net 160)
	)
	(arc
		(start 108.31 156.414359)
		(mid 108.358034 156.298393)
		(end 108.474 156.250359)
		(width 0.17)
		(layer "B.Cu")
		(net 160)
	)
	(arc
		(start 108.474 155.840359)
		(mid 108.358034 155.792325)
		(end 108.31 155.676359)
		(width 0.17)
		(layer "B.Cu")
		(net 160)
	)
	(segment
		(start 110.131464 157.6865)
		(end 110.038627 157.6865)
		(width 0.17)
		(layer "F.Cu")
		(net 161)
	)
	(segment
		(start 109.979168 157.686501)
		(end 109.814169 157.8515)
		(width 0.17)
		(layer "F.Cu")
		(net 161)
	)
	(segment
		(start 110.038627 157.6865)
		(end 110.038626 157.686501)
		(width 0.17)
		(layer "F.Cu")
		(net 161)
	)
	(segment
		(start 110.038626 157.686501)
		(end 109.979168 157.686501)
		(width 0.17)
		(layer "F.Cu")
		(net 161)
	)
	(segment
		(start 110.446464 158.0015)
		(end 110.131464 157.6865)
		(width 0.17)
		(layer "F.Cu")
		(net 161)
	)
	(segment
		(start 110.471464 158.0015)
		(end 110.446464 158.0015)
		(width 0.17)
		(layer "F.Cu")
		(net 161)
	)
	(via
		(at 109.814169 157.8515)
		(size 0.5)
		(drill 0.15)
		(layers "F.Cu" "B.Cu")
		(net 161)
	)
	(segment
		(start 107.99 156.966276)
		(end 107.99 145.918186)
		(width 0.17)
		(layer "B.Cu")
		(net 161)
	)
	(segment
		(start 125.017962 137.360224)
		(end 125.017962 131.840224)
		(width 0.17)
		(layer "B.Cu")
		(net 161)
	)
	(segment
		(start 126.915461 131.109)
		(end 127.005461 131.019)
		(width 0.17)
		(layer "B.Cu")
		(net 161)
	)
	(segment
		(start 109.64917 157.686501)
		(end 108.710225 157.686501)
		(width 0.17)
		(layer "B.Cu")
		(net 161)
	)
	(segment
		(start 127.005461 131.019)
		(end 128.167962 131.019)
		(width 0.17)
		(layer "B.Cu")
		(net 161)
	)
	(segment
		(start 125.749186 131.109)
		(end 126.915461 131.109)
		(width 0.17)
		(layer "B.Cu")
		(net 161)
	)
	(segment
		(start 112.541686 141.3665)
		(end 121.011686 141.3665)
		(width 0.17)
		(layer "B.Cu")
		(net 161)
	)
	(segment
		(start 109.814169 157.8515)
		(end 109.64917 157.686501)
		(width 0.17)
		(layer "B.Cu")
		(net 161)
	)
	(segment
		(start 121.011686 141.3665)
		(end 125.017962 137.360224)
		(width 0.17)
		(layer "B.Cu")
		(net 161)
	)
	(segment
		(start 107.99 145.918186)
		(end 112.541686 141.3665)
		(width 0.17)
		(layer "B.Cu")
		(net 161)
	)
	(segment
		(start 125.017962 131.840224)
		(end 125.749186 131.109)
		(width 0.17)
		(layer "B.Cu")
		(net 161)
	)
	(segment
		(start 108.710225 157.686501)
		(end 107.99 156.966276)
		(width 0.17)
		(layer "B.Cu")
		(net 161)
	)
	(segment
		(start 107.62 155.8415)
		(end 107.595 155.8415)
		(width 0.17)
		(layer "F.Cu")
		(net 162)
	)
	(segment
		(start 107.28 156.1565)
		(end 107.176886 156.1565)
		(width 0.17)
		(layer "F.Cu")
		(net 162)
	)
	(segment
		(start 107.595 155.8415)
		(end 107.28 156.1565)
		(width 0.17)
		(layer "F.Cu")
		(net 162)
	)
	(segment
		(start 107.176886 156.1565)
		(end 106.85281 155.832424)
		(width 0.17)
		(layer "F.Cu")
		(net 162)
	)
	(segment
		(start 106.85281 155.832424)
		(end 106.85281 155.599079)
		(width 0.17)
		(layer "F.Cu")
		(net 162)
	)
	(via
		(at 106.85281 155.599079)
		(size 0.5)
		(drill 0.15)
		(layers "F.Cu" "B.Cu")
		(net 162)
	)
	(segment
		(start 106.85281 155.599079)
		(end 106.619465 155.599079)
		(width 0.17)
		(layer "B.Cu")
		(net 162)
	)
	(segment
		(start 106.51 154.594647)
		(end 106.51 154.714647)
		(width 0.17)
		(layer "B.Cu")
		(net 162)
	)
	(segment
		(start 107.006253 154.354647)
		(end 106.75 154.354647)
		(width 0.17)
		(layer "B.Cu")
		(net 162)
	)
	(segment
		(start 107.246253 153.994647)
		(end 107.246253 154.114647)
		(width 0.17)
		(layer "B.Cu")
		(net 162)
	)
	(segment
		(start 106.619465 155.599079)
		(end 106.51 155.489614)
		(width 0.17)
		(layer "B.Cu")
		(net 162)
	)
	(segment
		(start 111.644238 139.9265)
		(end 106.51 145.060738)
		(width 0.17)
		(layer "B.Cu")
		(net 162)
	)
	(segment
		(start 106.51 154.714647)
		(end 106.51 154.801835)
		(width 0.17)
		(layer "B.Cu")
		(net 162)
	)
	(segment
		(start 106.51 145.060738)
		(end 106.51 153.514647)
		(width 0.17)
		(layer "B.Cu")
		(net 162)
	)
	(segment
		(start 106.51 154.902397)
		(end 106.51 154.801835)
		(width 0.17)
		(layer "B.Cu")
		(net 162)
	)
	(segment
		(start 125.251738 129.929)
		(end 124.057962 131.122776)
		(width 0.17)
		(layer "B.Cu")
		(net 162)
	)
	(segment
		(start 126.915461 129.929)
		(end 125.251738 129.929)
		(width 0.17)
		(layer "B.Cu")
		(net 162)
	)
	(segment
		(start 120.604238 139.9265)
		(end 111.644238 139.9265)
		(width 0.17)
		(layer "B.Cu")
		(net 162)
	)
	(segment
		(start 106.51 155.489614)
		(end 106.51 154.902397)
		(width 0.17)
		(layer "B.Cu")
		(net 162)
	)
	(segment
		(start 124.057962 136.472776)
		(end 120.604238 139.9265)
		(width 0.17)
		(layer "B.Cu")
		(net 162)
	)
	(segment
		(start 127.005461 130.019)
		(end 126.915461 129.929)
		(width 0.17)
		(layer "B.Cu")
		(net 162)
	)
	(segment
		(start 106.75 153.754647)
		(end 107.006253 153.754647)
		(width 0.17)
		(layer "B.Cu")
		(net 162)
	)
	(segment
		(start 128.167962 130.019)
		(end 127.005461 130.019)
		(width 0.17)
		(layer "B.Cu")
		(net 162)
	)
	(segment
		(start 124.057962 131.122776)
		(end 124.057962 136.472776)
		(width 0.17)
		(layer "B.Cu")
		(net 162)
	)
	(arc
		(start 106.75 154.354647)
		(mid 106.580294 154.424941)
		(end 106.51 154.594647)
		(width 0.17)
		(layer "B.Cu")
		(net 162)
	)
	(arc
		(start 107.246253 154.114647)
		(mid 107.175959 154.284353)
		(end 107.006253 154.354647)
		(width 0.17)
		(layer "B.Cu")
		(net 162)
	)
	(arc
		(start 107.006253 153.754647)
		(mid 107.175959 153.824941)
		(end 107.246253 153.994647)
		(width 0.17)
		(layer "B.Cu")
		(net 162)
	)
	(arc
		(start 106.51 153.514647)
		(mid 106.580294 153.684353)
		(end 106.75 153.754647)
		(width 0.17)
		(layer "B.Cu")
		(net 162)
	)
	(segment
		(start 107.62 156.7915)
		(end 107.595 156.7915)
		(width 0.17)
		(layer "F.Cu")
		(net 163)
	)
	(segment
		(start 107.28 156.4765)
		(end 107.044336 156.4765)
		(width 0.17)
		(layer "F.Cu")
		(net 163)
	)
	(segment
		(start 107.044336 156.4765)
		(end 106.626535 156.058699)
		(width 0.17)
		(layer "F.Cu")
		(net 163)
	)
	(segment
		(start 106.626535 156.058699)
		(end 106.39319 156.058699)
		(width 0.17)
		(layer "F.Cu")
		(net 163)
	)
	(segment
		(start 107.595 156.7915)
		(end 107.28 156.4765)
		(width 0.17)
		(layer "F.Cu")
		(net 163)
	)
	(via
		(at 106.39319 156.058699)
		(size 0.5)
		(drill 0.15)
		(layers "F.Cu" "B.Cu")
		(net 163)
	)
	(segment
		(start 123.737962 136.340224)
		(end 123.737962 130.990224)
		(width 0.17)
		(layer "B.Cu")
		(net 163)
	)
	(segment
		(start 127.005461 129.519)
		(end 128.167962 129.519)
		(width 0.17)
		(layer "B.Cu")
		(net 163)
	)
	(segment
		(start 106.39319 156.058699)
		(end 106.39319 155.825354)
		(width 0.17)
		(layer "B.Cu")
		(net 163)
	)
	(segment
		(start 126.915461 129.609)
		(end 127.005461 129.519)
		(width 0.17)
		(layer "B.Cu")
		(net 163)
	)
	(segment
		(start 106.19 144.928186)
		(end 111.511686 139.6065)
		(width 0.17)
		(layer "B.Cu")
		(net 163)
	)
	(segment
		(start 106.19 155.622164)
		(end 106.19 154.902397)
		(width 0.17)
		(layer "B.Cu")
		(net 163)
	)
	(segment
		(start 106.19 154.801835)
		(end 106.19 144.928186)
		(width 0.17)
		(layer "B.Cu")
		(net 163)
	)
	(segment
		(start 111.511686 139.6065)
		(end 120.471686 139.6065)
		(width 0.17)
		(layer "B.Cu")
		(net 163)
	)
	(segment
		(start 123.737962 130.990224)
		(end 125.119186 129.609)
		(width 0.17)
		(layer "B.Cu")
		(net 163)
	)
	(segment
		(start 106.19 154.902397)
		(end 106.19 154.801835)
		(width 0.17)
		(layer "B.Cu")
		(net 163)
	)
	(segment
		(start 120.471686 139.6065)
		(end 123.737962 136.340224)
		(width 0.17)
		(layer "B.Cu")
		(net 163)
	)
	(segment
		(start 125.119186 129.609)
		(end 126.915461 129.609)
		(width 0.17)
		(layer "B.Cu")
		(net 163)
	)
	(segment
		(start 106.39319 155.825354)
		(end 106.19 155.622164)
		(width 0.17)
		(layer "B.Cu")
		(net 163)
	)
	(segment
		(start 129.342737 128.428001)
		(end 128.897962 128.872776)
		(width 0.17)
		(layer "F.Cu")
		(net 164)
	)
	(segment
		(start 129.342737 128.428001)
		(end 130.232631 128.428001)
		(width 0.17)
		(layer "F.Cu")
		(net 164)
	)
	(segment
		(start 128.897962 150.192776)
		(end 122.614238 156.4765)
		(width 0.17)
		(layer "F.Cu")
		(net 164)
	)
	(segment
		(start 118.705 156.4765)
		(end 118.39 156.7915)
		(width 0.17)
		(layer "F.Cu")
		(net 164)
	)
	(segment
		(start 130.232631 128.428001)
		(end 130.39763 128.593)
		(width 0.17)
		(layer "F.Cu")
		(net 164)
	)
	(segment
		(start 128.897962 128.872776)
		(end 128.897962 150.192776)
		(width 0.17)
		(layer "F.Cu")
		(net 164)
	)
	(segment
		(start 122.614238 156.4765)
		(end 118.705 156.4765)
		(width 0.17)
		(layer "F.Cu")
		(net 164)
	)
	(via
		(at 130.39763 128.593)
		(size 0.5)
		(drill 0.15)
		(layers "F.Cu" "B.Cu")
		(net 164)
	)
	(segment
		(start 129.420464 128.428001)
		(end 130.232631 128.428001)
		(width 0.17)
		(layer "B.Cu")
		(net 164)
	)
	(segment
		(start 129.420463 128.428)
		(end 129.420464 128.428001)
		(width 0.17)
		(layer "B.Cu")
		(net 164)
	)
	(segment
		(start 129.330463 128.518)
		(end 129.420463 128.428)
		(width 0.17)
		(layer "B.Cu")
		(net 164)
	)
	(segment
		(start 130.232631 128.428001)
		(end 130.39763 128.593)
		(width 0.17)
		(layer "B.Cu")
		(net 164)
	)
	(segment
		(start 128.167962 128.518)
		(end 129.330463 128.518)
		(width 0.17)
		(layer "B.Cu")
		(net 164)
	)
	(segment
		(start 129.210187 128.107999)
		(end 128.577962 128.740224)
		(width 0.17)
		(layer "F.Cu")
		(net 165)
	)
	(segment
		(start 130.232631 128.107999)
		(end 130.39763 127.943)
		(width 0.17)
		(layer "F.Cu")
		(net 165)
	)
	(segment
		(start 118.705 156.1565)
		(end 118.39 155.8415)
		(width 0.17)
		(layer "F.Cu")
		(net 165)
	)
	(segment
		(start 128.577962 128.740224)
		(end 128.577962 150.060224)
		(width 0.17)
		(layer "F.Cu")
		(net 165)
	)
	(segment
		(start 122.481686 156.1565)
		(end 118.705 156.1565)
		(width 0.17)
		(layer "F.Cu")
		(net 165)
	)
	(segment
		(start 128.577962 150.060224)
		(end 122.481686 156.1565)
		(width 0.17)
		(layer "F.Cu")
		(net 165)
	)
	(segment
		(start 129.210187 128.107999)
		(end 130.232631 128.107999)
		(width 0.17)
		(layer "F.Cu")
		(net 165)
	)
	(via
		(at 130.39763 127.943)
		(size 0.5)
		(drill 0.15)
		(layers "F.Cu" "B.Cu")
		(net 165)
	)
	(segment
		(start 129.420463 128.108)
		(end 129.420464 128.107999)
		(width 0.17)
		(layer "B.Cu")
		(net 165)
	)
	(segment
		(start 130.232631 128.107999)
		(end 130.39763 127.943)
		(width 0.17)
		(layer "B.Cu")
		(net 165)
	)
	(segment
		(start 129.330463 128.018)
		(end 129.420463 128.108)
		(width 0.17)
		(layer "B.Cu")
		(net 165)
	)
	(segment
		(start 128.167962 128.018)
		(end 129.330463 128.018)
		(width 0.17)
		(layer "B.Cu")
		(net 165)
	)
	(segment
		(start 129.420464 128.107999)
		(end 130.232631 128.107999)
		(width 0.17)
		(layer "B.Cu")
		(net 165)
	)
	(segment
		(start 122.099776 155.2765)
		(end 127.337962 150.038314)
		(width 0.17)
		(layer "F.Cu")
		(net 166)
	)
	(segment
		(start 121.12 155.2765)
		(end 122.099776 155.2765)
		(width 0.17)
		(layer "F.Cu")
		(net 166)
	)
	(segment
		(start 120.78 155.5915)
		(end 120.805 155.5915)
		(width 0.17)
		(layer "F.Cu")
		(net 166)
	)
	(segment
		(start 129.666484 126.928501)
		(end 129.831483 127.0935)
		(width 0.17)
		(layer "F.Cu")
		(net 166)
	)
	(segment
		(start 120.805 155.5915)
		(end 121.12 155.2765)
		(width 0.17)
		(layer "F.Cu")
		(net 166)
	)
	(segment
		(start 128.352237 126.928501)
		(end 129.666484 126.928501)
		(width 0.17)
		(layer "F.Cu")
		(net 166)
	)
	(segment
		(start 127.337962 150.038314)
		(end 127.337962 127.942776)
		(width 0.17)
		(layer "F.Cu")
		(net 166)
	)
	(segment
		(start 127.337962 127.942776)
		(end 128.352237 126.928501)
		(width 0.17)
		(layer "F.Cu")
		(net 166)
	)
	(via
		(at 129.831483 127.0935)
		(size 0.5)
		(drill 0.15)
		(layers "F.Cu" "B.Cu")
		(net 166)
	)
	(segment
		(start 129.101579 126.9285)
		(end 129.10158 126.928501)
		(width 0.17)
		(layer "B.Cu")
		(net 166)
	)
	(segment
		(start 129.10158 126.928501)
		(end 129.666484 126.928501)
		(width 0.17)
		(layer "B.Cu")
		(net 166)
	)
	(segment
		(start 129.666484 126.928501)
		(end 129.831483 127.0935)
		(width 0.17)
		(layer "B.Cu")
		(net 166)
	)
	(segment
		(start 128.167962 127.018)
		(end 128.792962 127.018)
		(width 0.17)
		(layer "B.Cu")
		(net 166)
	)
	(segment
		(start 128.882462 126.9285)
		(end 129.101579 126.9285)
		(width 0.17)
		(layer "B.Cu")
		(net 166)
	)
	(segment
		(start 128.792962 127.018)
		(end 128.882462 126.9285)
		(width 0.17)
		(layer "B.Cu")
		(net 166)
	)
	(segment
		(start 128.219687 126.608499)
		(end 129.666484 126.608499)
		(width 0.17)
		(layer "F.Cu")
		(net 167)
	)
	(segment
		(start 129.666484 126.608499)
		(end 129.831483 126.4435)
		(width 0.17)
		(layer "F.Cu")
		(net 167)
	)
	(segment
		(start 121.12 154.9565)
		(end 121.967224 154.9565)
		(width 0.17)
		(layer "F.Cu")
		(net 167)
	)
	(segment
		(start 120.805 154.6415)
		(end 121.12 154.9565)
		(width 0.17)
		(layer "F.Cu")
		(net 167)
	)
	(segment
		(start 127.017962 127.810224)
		(end 128.219687 126.608499)
		(width 0.17)
		(layer "F.Cu")
		(net 167)
	)
	(segment
		(start 121.967224 154.9565)
		(end 127.017962 149.905762)
		(width 0.17)
		(layer "F.Cu")
		(net 167)
	)
	(segment
		(start 127.017962 149.905762)
		(end 127.017962 127.810224)
		(width 0.17)
		(layer "F.Cu")
		(net 167)
	)
	(segment
		(start 120.78 154.6415)
		(end 120.805 154.6415)
		(width 0.17)
		(layer "F.Cu")
		(net 167)
	)
	(via
		(at 129.831483 126.4435)
		(size 0.5)
		(drill 0.15)
		(layers "F.Cu" "B.Cu")
		(net 167)
	)
	(segment
		(start 129.10158 126.608499)
		(end 129.666484 126.608499)
		(width 0.17)
		(layer "B.Cu")
		(net 167)
	)
	(segment
		(start 128.882462 126.6085)
		(end 129.101579 126.6085)
		(width 0.17)
		(layer "B.Cu")
		(net 167)
	)
	(segment
		(start 128.792962 126.519)
		(end 128.882462 126.6085)
		(width 0.17)
		(layer "B.Cu")
		(net 167)
	)
	(segment
		(start 129.101579 126.6085)
		(end 129.10158 126.608499)
		(width 0.17)
		(layer "B.Cu")
		(net 167)
	)
	(segment
		(start 129.666484 126.608499)
		(end 129.831483 126.4435)
		(width 0.17)
		(layer "B.Cu")
		(net 167)
	)
	(segment
		(start 128.167962 126.519)
		(end 128.792962 126.519)
		(width 0.17)
		(layer "B.Cu")
		(net 167)
	)
	(segment
		(start 126.095836 125.428001)
		(end 126.206541 125.428001)
		(width 0.17)
		(layer "F.Cu")
		(net 168)
	)
	(segment
		(start 125.737962 149.228314)
		(end 125.737962 125.785875)
		(width 0.17)
		(layer "F.Cu")
		(net 168)
	)
	(segment
		(start 118.36 154.3915)
		(end 118.385 154.3915)
		(width 0.17)
		(layer "F.Cu")
		(net 168)
	)
	(segment
		(start 126.206541 125.428001)
		(end 126.37154 125.593)
		(width 0.17)
		(layer "F.Cu")
		(net 168)
	)
	(segment
		(start 120.889776 154.0765)
		(end 125.737962 149.228314)
		(width 0.17)
		(layer "F.Cu")
		(net 168)
	)
	(segment
		(start 118.385 154.3915)
		(end 118.7 154.0765)
		(width 0.17)
		(layer "F.Cu")
		(net 168)
	)
	(segment
		(start 125.737962 125.785875)
		(end 126.095836 125.428001)
		(width 0.17)
		(layer "F.Cu")
		(net 168)
	)
	(segment
		(start 118.7 154.0765)
		(end 120.889776 154.0765)
		(width 0.17)
		(layer "F.Cu")
		(net 168)
	)
	(via
		(at 126.37154 125.593)
		(size 0.5)
		(drill 0.15)
		(layers "F.Cu" "B.Cu")
		(net 168)
	)
	(segment
		(start 126.574999 125.428001)
		(end 126.536539 125.428001)
		(width 0.17)
		(layer "B.Cu")
		(net 168)
	)
	(segment
		(start 126.915461 125.428)
		(end 126.575 125.428)
		(width 0.17)
		(layer "B.Cu")
		(net 168)
	)
	(segment
		(start 126.575 125.428)
		(end 126.574999 125.428001)
		(width 0.17)
		(layer "B.Cu")
		(net 168)
	)
	(segment
		(start 127.005461 125.518)
		(end 126.915461 125.428)
		(width 0.17)
		(layer "B.Cu")
		(net 168)
	)
	(segment
		(start 126.536539 125.428001)
		(end 126.37154 125.593)
		(width 0.17)
		(layer "B.Cu")
		(net 168)
	)
	(segment
		(start 128.167962 125.518)
		(end 127.005461 125.518)
		(width 0.17)
		(layer "B.Cu")
		(net 168)
	)
	(segment
		(start 118.385 153.4415)
		(end 118.7 153.7565)
		(width 0.17)
		(layer "F.Cu")
		(net 169)
	)
	(segment
		(start 125.417962 149.095762)
		(end 125.417962 125.653323)
		(width 0.17)
		(layer "F.Cu")
		(net 169)
	)
	(segment
		(start 118.36 153.4415)
		(end 118.385 153.4415)
		(width 0.17)
		(layer "F.Cu")
		(net 169)
	)
	(segment
		(start 118.7 153.7565)
		(end 120.757224 153.7565)
		(width 0.17)
		(layer "F.Cu")
		(net 169)
	)
	(segment
		(start 126.206541 125.107999)
		(end 126.37154 124.943)
		(width 0.17)
		(layer "F.Cu")
		(net 169)
	)
	(segment
		(start 125.963286 125.107999)
		(end 126.206541 125.107999)
		(width 0.17)
		(layer "F.Cu")
		(net 169)
	)
	(segment
		(start 120.757224 153.7565)
		(end 125.417962 149.095762)
		(width 0.17)
		(layer "F.Cu")
		(net 169)
	)
	(segment
		(start 125.417962 125.653323)
		(end 125.963286 125.107999)
		(width 0.17)
		(layer "F.Cu")
		(net 169)
	)
	(via
		(at 126.37154 124.943)
		(size 0.5)
		(drill 0.15)
		(layers "F.Cu" "B.Cu")
		(net 169)
	)
	(segment
		(start 126.574999 125.107999)
		(end 126.536539 125.107999)
		(width 0.17)
		(layer "B.Cu")
		(net 169)
	)
	(segment
		(start 126.536539 125.107999)
		(end 126.37154 124.943)
		(width 0.17)
		(layer "B.Cu")
		(net 169)
	)
	(segment
		(start 127.005461 125.018)
		(end 126.915461 125.108)
		(width 0.17)
		(layer "B.Cu")
		(net 169)
	)
	(segment
		(start 126.575 125.108)
		(end 126.574999 125.107999)
		(width 0.17)
		(layer "B.Cu")
		(net 169)
	)
	(segment
		(start 126.915461 125.108)
		(end 126.575 125.108)
		(width 0.17)
		(layer "B.Cu")
		(net 169)
	)
	(segment
		(start 128.167962 125.018)
		(end 127.005461 125.018)
		(width 0.17)
		(layer "B.Cu")
		(net 169)
	)
	(segment
		(start 121.897962 144.222776)
		(end 121.897962 124.528314)
		(width 0.17)
		(layer "F.Cu")
		(net 170)
	)
	(segment
		(start 121.897962 124.528314)
		(end 122.497775 123.928501)
		(width 0.17)
		(layer "F.Cu")
		(net 170)
	)
	(segment
		(start 118.043238 148.0775)
		(end 121.897962 144.222776)
		(width 0.17)
		(layer "F.Cu")
		(net 170)
	)
	(segment
		(start 116.079962 148.118)
		(end 116.120462 148.0775)
		(width 0.17)
		(layer "F.Cu")
		(net 170)
	)
	(segment
		(start 115.554961 148.118)
		(end 116.079962 148.118)
		(width 0.17)
		(layer "F.Cu")
		(net 170)
	)
	(segment
		(start 116.120462 148.0775)
		(end 118.043238 148.0775)
		(width 0.17)
		(layer "F.Cu")
		(net 170)
	)
	(segment
		(start 123.135001 123.928501)
		(end 123.3 124.0935)
		(width 0.17)
		(layer "F.Cu")
		(net 170)
	)
	(segment
		(start 122.497775 123.928501)
		(end 123.135001 123.928501)
		(width 0.17)
		(layer "F.Cu")
		(net 170)
	)
	(via
		(at 123.3 124.0935)
		(size 0.5)
		(drill 0.15)
		(layers "F.Cu" "B.Cu")
		(net 170)
	)
	(segment
		(start 126.91496 123.928501)
		(end 123.464999 123.928501)
		(width 0.17)
		(layer "B.Cu")
		(net 170)
	)
	(segment
		(start 128.167962 124.019)
		(end 127.005461 124.019)
		(width 0.17)
		(layer "B.Cu")
		(net 170)
	)
	(segment
		(start 123.464999 123.928501)
		(end 123.3 124.0935)
		(width 0.17)
		(layer "B.Cu")
		(net 170)
	)
	(segment
		(start 127.005461 124.019)
		(end 126.914961 123.9285)
		(width 0.17)
		(layer "B.Cu")
		(net 170)
	)
	(segment
		(start 126.914961 123.9285)
		(end 126.91496 123.928501)
		(width 0.17)
		(layer "B.Cu")
		(net 170)
	)
	(segment
		(start 121.577962 124.395762)
		(end 122.365225 123.608499)
		(width 0.17)
		(layer "F.Cu")
		(net 171)
	)
	(segment
		(start 115.554961 147.717)
		(end 116.079962 147.717)
		(width 0.17)
		(layer "F.Cu")
		(net 171)
	)
	(segment
		(start 122.365225 123.608499)
		(end 123.135001 123.608499)
		(width 0.17)
		(layer "F.Cu")
		(net 171)
	)
	(segment
		(start 116.120462 147.7575)
		(end 117.910686 147.7575)
		(width 0.17)
		(layer "F.Cu")
		(net 171)
	)
	(segment
		(start 116.079962 147.717)
		(end 116.120462 147.7575)
		(width 0.17)
		(layer "F.Cu")
		(net 171)
	)
	(segment
		(start 117.910686 147.7575)
		(end 121.577962 144.090224)
		(width 0.17)
		(layer "F.Cu")
		(net 171)
	)
	(segment
		(start 121.577962 144.090224)
		(end 121.577962 124.395762)
		(width 0.17)
		(layer "F.Cu")
		(net 171)
	)
	(segment
		(start 123.135001 123.608499)
		(end 123.3 123.4435)
		(width 0.17)
		(layer "F.Cu")
		(net 171)
	)
	(via
		(at 123.3 123.4435)
		(size 0.5)
		(drill 0.15)
		(layers "F.Cu" "B.Cu")
		(net 171)
	)
	(segment
		(start 126.91496 123.608499)
		(end 123.464999 123.608499)
		(width 0.17)
		(layer "B.Cu")
		(net 171)
	)
	(segment
		(start 128.167962 123.518)
		(end 127.005461 123.518)
		(width 0.17)
		(layer "B.Cu")
		(net 171)
	)
	(segment
		(start 127.005461 123.518)
		(end 126.914961 123.6085)
		(width 0.17)
		(layer "B.Cu")
		(net 171)
	)
	(segment
		(start 123.464999 123.608499)
		(end 123.3 123.4435)
		(width 0.17)
		(layer "B.Cu")
		(net 171)
	)
	(segment
		(start 126.914961 123.6085)
		(end 126.91496 123.608499)
		(width 0.17)
		(layer "B.Cu")
		(net 171)
	)
	(segment
		(start 125.005495 122.425243)
		(end 125.309874 122.425243)
		(width 0.17)
		(layer "F.Cu")
		(net 172)
	)
	(segment
		(start 116.079962 149.316)
		(end 116.119462 149.2765)
		(width 0.17)
		(layer "F.Cu")
		(net 172)
	)
	(segment
		(start 125.309874 122.425243)
		(end 125.474873 122.590242)
		(width 0.17)
		(layer "F.Cu")
		(net 172)
	)
	(segment
		(start 119.794238 149.2765)
		(end 124.297962 144.772776)
		(width 0.17)
		(layer "F.Cu")
		(net 172)
	)
	(segment
		(start 124.297962 123.132776)
		(end 125.005495 122.425243)
		(width 0.17)
		(layer "F.Cu")
		(net 172)
	)
	(segment
		(start 124.297962 144.772776)
		(end 124.297962 123.132776)
		(width 0.17)
		(layer "F.Cu")
		(net 172)
	)
	(segment
		(start 115.554961 149.316)
		(end 116.079962 149.316)
		(width 0.17)
		(layer "F.Cu")
		(net 172)
	)
	(segment
		(start 116.119462 149.2765)
		(end 119.794238 149.2765)
		(width 0.17)
		(layer "F.Cu")
		(net 172)
	)
	(via
		(at 125.474873 122.590242)
		(size 0.5)
		(drill 0.15)
		(layers "F.Cu" "B.Cu")
		(net 172)
	)
	(segment
		(start 128.167962 122.518)
		(end 127.005461 122.518)
		(width 0.17)
		(layer "B.Cu")
		(net 172)
	)
	(segment
		(start 126.265504 122.428)
		(end 126.262747 122.425243)
		(width 0.17)
		(layer "B.Cu")
		(net 172)
	)
	(segment
		(start 125.639872 122.425243)
		(end 125.474873 122.590242)
		(width 0.17)
		(layer "B.Cu")
		(net 172)
	)
	(segment
		(start 126.262747 122.425243)
		(end 125.639872 122.425243)
		(width 0.17)
		(layer "B.Cu")
		(net 172)
	)
	(segment
		(start 126.915461 122.428)
		(end 126.265504 122.428)
		(width 0.17)
		(layer "B.Cu")
		(net 172)
	)
	(segment
		(start 127.005461 122.518)
		(end 126.915461 122.428)
		(width 0.17)
		(layer "B.Cu")
		(net 172)
	)
	(segment
		(start 124.872945 122.105241)
		(end 125.309874 122.105241)
		(width 0.17)
		(layer "F.Cu")
		(net 173)
	)
	(segment
		(start 116.079962 148.917)
		(end 116.119462 148.9565)
		(width 0.17)
		(layer "F.Cu")
		(net 173)
	)
	(segment
		(start 115.554961 148.917)
		(end 116.079962 148.917)
		(width 0.17)
		(layer "F.Cu")
		(net 173)
	)
	(segment
		(start 123.977962 123.000224)
		(end 124.872945 122.105241)
		(width 0.17)
		(layer "F.Cu")
		(net 173)
	)
	(segment
		(start 116.119462 148.9565)
		(end 119.661686 148.9565)
		(width 0.17)
		(layer "F.Cu")
		(net 173)
	)
	(segment
		(start 123.977962 144.640224)
		(end 123.977962 123.000224)
		(width 0.17)
		(layer "F.Cu")
		(net 173)
	)
	(segment
		(start 119.661686 148.9565)
		(end 123.977962 144.640224)
		(width 0.17)
		(layer "F.Cu")
		(net 173)
	)
	(segment
		(start 125.309874 122.105241)
		(end 125.474873 121.940242)
		(width 0.17)
		(layer "F.Cu")
		(net 173)
	)
	(via
		(at 125.474873 121.940242)
		(size 0.5)
		(drill 0.15)
		(layers "F.Cu" "B.Cu")
		(net 173)
	)
	(segment
		(start 125.639872 122.105241)
		(end 125.474873 121.940242)
		(width 0.17)
		(layer "B.Cu")
		(net 173)
	)
	(segment
		(start 126.387962 122.108)
		(end 126.385203 122.105241)
		(width 0.17)
		(layer "B.Cu")
		(net 173)
	)
	(segment
		(start 127.005461 122.018)
		(end 126.915461 122.108)
		(width 0.17)
		(layer "B.Cu")
		(net 173)
	)
	(segment
		(start 126.915461 122.108)
		(end 126.387962 122.108)
		(width 0.17)
		(layer "B.Cu")
		(net 173)
	)
	(segment
		(start 128.167962 122.018)
		(end 127.005461 122.018)
		(width 0.17)
		(layer "B.Cu")
		(net 173)
	)
	(segment
		(start 126.385203 122.105241)
		(end 125.639872 122.105241)
		(width 0.17)
		(layer "B.Cu")
		(net 173)
	)
	(via
		(at 78.617962 138.1665)
		(size 0.45)
		(drill 0.1)
		(layers "F.Cu" "B.Cu")
		(net 175)
	)
	(segment
		(start 78.617962 146.0315)
		(end 78.617962 138.1665)
		(width 0.127)
		(layer "B.Cu")
		(net 175)
	)
	(segment
		(start 76.867962 136.4165)
		(end 78.617962 138.1665)
		(width 0.15)
		(layer "In2.Cu")
		(net 175)
	)
	(segment
		(start 74.597962 123.696449)
		(end 74.597962 123.705408)
		(width 0.15)
		(layer "In2.Cu")
		(net 175)
	)
	(segment
		(start 74.597962 123.705408)
		(end 75.842962 124.950408)
		(width 0.15)
		(layer "In2.Cu")
		(net 175)
	)
	(segment
		(start 75.842962 124.950408)
		(end 75.842962 128.794317)
		(width 0.15)
		(layer "In2.Cu")
		(net 175)
	)
	(segment
		(start 74.324054 123.4315)
		(end 74.333012 123.4315)
		(width 0.15)
		(layer "In2.Cu")
		(net 175)
	)
	(segment
		(start 59.397012 119.9415)
		(end 70.834054 119.9415)
		(width 0.15)
		(layer "In2.Cu")
		(net 175)
	)
	(segment
		(start 76.867962 129.819316)
		(end 76.867962 136.4165)
		(width 0.15)
		(layer "In2.Cu")
		(net 175)
	)
	(segment
		(start 58.128512 118.673)
		(end 59.397012 119.9415)
		(width 0.15)
		(layer "In2.Cu")
		(net 175)
	)
	(segment
		(start 70.834054 119.9415)
		(end 74.324054 123.4315)
		(width 0.15)
		(layer "In2.Cu")
		(net 175)
	)
	(segment
		(start 74.333012 123.4315)
		(end 74.597962 123.696449)
		(width 0.15)
		(layer "In2.Cu")
		(net 175)
	)
	(segment
		(start 75.842962 128.794317)
		(end 76.867962 129.819316)
		(width 0.15)
		(layer "In2.Cu")
		(net 175)
	)
	(via
		(at 79.642962 138.3915)
		(size 0.45)
		(drill 0.1)
		(layers "F.Cu" "B.Cu")
		(net 176)
	)
	(segment
		(start 79.667962 146.0065)
		(end 79.667962 138.4165)
		(width 0.15)
		(layer "B.Cu")
		(net 176)
	)
	(segment
		(start 79.667962 138.4165)
		(end 79.642962 138.3915)
		(width 0.15)
		(layer "B.Cu")
		(net 176)
	)
	(segment
		(start 76.117962 128.680409)
		(end 77.142962 129.705408)
		(width 0.15)
		(layer "In2.Cu")
		(net 176)
	)
	(segment
		(start 74.457962 123.1565)
		(end 74.457962 123.167541)
		(width 0.15)
		(layer "In2.Cu")
		(net 176)
	)
	(segment
		(start 68.869512 118.673)
		(end 69.863012 119.6665)
		(width 0.15)
		(layer "In2.Cu")
		(net 176)
	)
	(segment
		(start 70.967962 119.6665)
		(end 74.457962 123.1565)
		(width 0.15)
		(layer "In2.Cu")
		(net 176)
	)
	(segment
		(start 69.863012 119.6665)
		(end 70.967962 119.6665)
		(width 0.15)
		(layer "In2.Cu")
		(net 176)
	)
	(segment
		(start 79.642962 137.952592)
		(end 79.642962 138.3915)
		(width 0.15)
		(layer "In2.Cu")
		(net 176)
	)
	(segment
		(start 77.142962 135.452593)
		(end 79.642962 137.952592)
		(width 0.15)
		(layer "In2.Cu")
		(net 176)
	)
	(segment
		(start 76.117962 124.8165)
		(end 76.117962 128.680409)
		(width 0.15)
		(layer "In2.Cu")
		(net 176)
	)
	(segment
		(start 74.457962 123.167541)
		(end 75.061921 123.7715)
		(width 0.15)
		(layer "In2.Cu")
		(net 176)
	)
	(segment
		(start 77.142962 129.705408)
		(end 77.142962 135.452593)
		(width 0.15)
		(layer "In2.Cu")
		(net 176)
	)
	(segment
		(start 75.072962 123.7715)
		(end 76.117962 124.8165)
		(width 0.15)
		(layer "In2.Cu")
		(net 176)
	)
	(segment
		(start 120.5085 117.7915)
		(end 120 118.3)
		(width 0.2)
		(layer "F.Cu")
		(net 178)
	)
	(segment
		(start 120.617962 117.7915)
		(end 120.5085 117.7915)
		(width 0.2)
		(layer "F.Cu")
		(net 178)
	)
	(via
		(at 120.617962 117.7915)
		(size 0.45)
		(drill 0.1)
		(layers "F.Cu" "B.Cu")
		(net 178)
	)
	(segment
		(start 120.619962 117.269)
		(end 120.619962 117.7895)
		(width 0.2)
		(layer "B.Cu")
		(net 178)
	)
	(segment
		(start 120.619962 117.7895)
		(end 120.617962 117.7915)
		(width 0.2)
		(layer "B.Cu")
		(net 178)
	)
	(segment
		(start 119.542962 120.5415)
		(end 118.907962 120.5415)
		(width 0.2)
		(layer "B.Cu")
		(net 182)
	)
	(segment
		(start 120.619962 120.768)
		(end 119.769462 120.768)
		(width 0.2)
		(layer "B.Cu")
		(net 182)
	)
	(segment
		(start 119.769462 120.768)
		(end 119.542962 120.5415)
		(width 0.2)
		(layer "B.Cu")
		(net 182)
	)
	(via
		(at 118.142962 125.25)
		(size 0.45)
		(drill 0.1)
		(layers "F.Cu" "B.Cu")
		(net 185)
	)
	(segment
		(start 118.717962 124.675)
		(end 118.142962 125.25)
		(width 0.2)
		(layer "B.Cu")
		(net 185)
	)
	(segment
		(start 119.691462 123.268)
		(end 118.717962 124.2415)
		(width 0.2)
		(layer "B.Cu")
		(net 185)
	)
	(segment
		(start 120.619962 123.268)
		(end 119.691462 123.268)
		(width 0.2)
		(layer "B.Cu")
		(net 185)
	)
	(segment
		(start 118.717962 124.2415)
		(end 118.717962 124.675)
		(width 0.2)
		(layer "B.Cu")
		(net 185)
	)
	(segment
		(start 88.740237 150.146996)
		(end 88.740243 150.146996)
		(width 0.127)
		(layer "F.Cu")
		(net 186)
	)
	(segment
		(start 88.917608 150.147)
		(end 89.992962 151.222354)
		(width 0.127)
		(layer "F.Cu")
		(net 186)
	)
	(segment
		(start 87.14374 148.768868)
		(end 88.521868 150.146996)
		(width 0.127)
		(layer "F.Cu")
		(net 186)
	)
	(segment
		(start 88.531469 150.146992)
		(end 88.631046 150.146992)
		(width 0.127)
		(layer "F.Cu")
		(net 186)
	)
	(segment
		(start 88.531465 150.146996)
		(end 88.531469 150.146992)
		(width 0.127)
		(layer "F.Cu")
		(net 186)
	)
	(segment
		(start 88.631046 150.146992)
		(end 88.740223 150.146988)
		(width 0.127)
		(layer "F.Cu")
		(net 186)
	)
	(segment
		(start 89.992962 151.222354)
		(end 89.992962 151.6665)
		(width 0.127)
		(layer "F.Cu")
		(net 186)
	)
	(segment
		(start 88.740233 150.146992)
		(end 88.740237 150.146996)
		(width 0.127)
		(layer "F.Cu")
		(net 186)
	)
	(segment
		(start 88.740223 150.146988)
		(end 88.740227 150.146992)
		(width 0.127)
		(layer "F.Cu")
		(net 186)
	)
	(segment
		(start 85.117962 148.2165)
		(end 85.67033 148.768868)
		(width 0.127)
		(layer "F.Cu")
		(net 186)
	)
	(segment
		(start 85.117962 147.2665)
		(end 85.117962 148.2165)
		(width 0.127)
		(layer "F.Cu")
		(net 186)
	)
	(segment
		(start 88.740247 150.147)
		(end 88.917608 150.147)
		(width 0.127)
		(layer "F.Cu")
		(net 186)
	)
	(segment
		(start 88.740227 150.146992)
		(end 88.740233 150.146992)
		(width 0.127)
		(layer "F.Cu")
		(net 186)
	)
	(segment
		(start 88.521868 150.146996)
		(end 88.531465 150.146996)
		(width 0.127)
		(layer "F.Cu")
		(net 186)
	)
	(segment
		(start 88.740243 150.146996)
		(end 88.740247 150.147)
		(width 0.127)
		(layer "F.Cu")
		(net 186)
	)
	(segment
		(start 85.67033 148.768868)
		(end 87.14374 148.768868)
		(width 0.127)
		(layer "F.Cu")
		(net 186)
	)
	(segment
		(start 87.039358 149.020868)
		(end 88.41749 150.399)
		(width 0.127)
		(layer "F.Cu")
		(net 187)
	)
	(segment
		(start 88.41749 150.399)
		(end 88.427093 150.399)
		(width 0.127)
		(layer "F.Cu")
		(net 187)
	)
	(segment
		(start 88.531469 150.398996)
		(end 88.635851 150.398992)
		(width 0.127)
		(layer "F.Cu")
		(net 187)
	)
	(segment
		(start 89.592962 151.178736)
		(end 89.592962 151.6665)
		(width 0.127)
		(layer "F.Cu")
		(net 187)
	)
	(segment
		(start 85.565948 149.020868)
		(end 87.039358 149.020868)
		(width 0.127)
		(layer "F.Cu")
		(net 187)
	)
	(segment
		(start 88.635851 150.398992)
		(end 88.635855 150.398996)
		(width 0.127)
		(layer "F.Cu")
		(net 187)
	)
	(segment
		(start 84.717962 147.2665)
		(end 84.717962 148.172882)
		(width 0.127)
		(layer "F.Cu")
		(net 187)
	)
	(segment
		(start 88.635865 150.399)
		(end 88.813226 150.399)
		(width 0.127)
		(layer "F.Cu")
		(net 187)
	)
	(segment
		(start 88.427097 150.398996)
		(end 88.531469 150.398996)
		(width 0.127)
		(layer "F.Cu")
		(net 187)
	)
	(segment
		(start 88.635855 150.398996)
		(end 88.635861 150.398996)
		(width 0.127)
		(layer "F.Cu")
		(net 187)
	)
	(segment
		(start 88.813226 150.399)
		(end 89.592962 151.178736)
		(width 0.127)
		(layer "F.Cu")
		(net 187)
	)
	(segment
		(start 88.635861 150.398996)
		(end 88.635865 150.399)
		(width 0.127)
		(layer "F.Cu")
		(net 187)
	)
	(segment
		(start 84.717962 148.172882)
		(end 85.565948 149.020868)
		(width 0.127)
		(layer "F.Cu")
		(net 187)
	)
	(segment
		(start 88.427093 150.399)
		(end 88.427097 150.398996)
		(width 0.127)
		(layer "F.Cu")
		(net 187)
	)
	(segment
		(start 93.37303 143.587)
		(end 92.867962 143.081932)
		(width 0.127)
		(layer "F.Cu")
		(net 188)
	)
	(segment
		(start 86.497962 150.8665)
		(end 86.167962 151.1965)
		(width 0.127)
		(layer "F.Cu")
		(net 188)
	)
	(segment
		(start 93.381606 143.587)
		(end 93.37303 143.587)
		(width 0.127)
		(layer "F.Cu")
		(net 188)
	)
	(segment
		(start 92.867962 143.081932)
		(end 92.867962 142.657236)
		(width 0.127)
		(layer "F.Cu")
		(net 188)
	)
	(segment
		(start 86.167962 151.1965)
		(end 86.167962 151.5965)
		(width 0.127)
		(layer "F.Cu")
		(net 188)
	)
	(via
		(at 86.497962 150.8665)
		(size 0.45)
		(drill 0.1)
		(layers "F.Cu" "B.Cu")
		(net 188)
	)
	(via
		(at 93.381606 143.587)
		(size 0.45)
		(drill 0.1)
		(layers "F.Cu" "B.Cu")
		(net 188)
	)
	(segment
		(start 89.89349 146.5165)
		(end 88.167962 146.5165)
		(width 0.127)
		(layer "B.Cu")
		(net 188)
	)
	(segment
		(start 93.012962 144.0415)
		(end 92.36849 144.0415)
		(width 0.127)
		(layer "B.Cu")
		(net 188)
	)
	(segment
		(start 86.217962 150.137778)
		(end 86.497962 150.417778)
		(width 0.127)
		(layer "B.Cu")
		(net 188)
	)
	(segment
		(start 86.497962 150.417778)
		(end 86.497962 150.8665)
		(width 0.127)
		(layer "B.Cu")
		(net 188)
	)
	(segment
		(start 88.167962 146.5165)
		(end 86.217962 148.4665)
		(width 0.127)
		(layer "B.Cu")
		(net 188)
	)
	(segment
		(start 93.381606 143.587)
		(end 93.381606 143.672856)
		(width 0.127)
		(layer "B.Cu")
		(net 188)
	)
	(segment
		(start 92.36849 144.0415)
		(end 89.89349 146.5165)
		(width 0.127)
		(layer "B.Cu")
		(net 188)
	)
	(segment
		(start 93.381606 143.672856)
		(end 93.012962 144.0415)
		(width 0.127)
		(layer "B.Cu")
		(net 188)
	)
	(segment
		(start 86.217962 148.4665)
		(end 86.217962 150.137778)
		(width 0.127)
		(layer "B.Cu")
		(net 188)
	)
	(segment
		(start 85.944462 150.59)
		(end 85.767962 150.7665)
		(width 0.127)
		(layer "F.Cu")
		(net 189)
	)
	(segment
		(start 92.467962 143.26671)
		(end 92.467962 142.657236)
		(width 0.127)
		(layer "F.Cu")
		(net 189)
	)
	(segment
		(start 85.95 150.59)
		(end 85.944462 150.59)
		(width 0.127)
		(layer "F.Cu")
		(net 189)
	)
	(segment
		(start 92.806907 143.605655)
		(end 92.467962 143.26671)
		(width 0.127)
		(layer "F.Cu")
		(net 189)
	)
	(segment
		(start 85.767962 150.7665)
		(end 85.767962 151.5965)
		(width 0.127)
		(layer "F.Cu")
		(net 189)
	)
	(via
		(at 92.806907 143.605655)
		(size 0.45)
		(drill 0.1)
		(layers "F.Cu" "B.Cu")
		(net 189)
	)
	(via
		(at 85.95 150.59)
		(size 0.45)
		(drill 0.1)
		(layers "F.Cu" "B.Cu")
		(net 189)
	)
	(segment
		(start 85.965962 148.362118)
		(end 88.06358 146.2645)
		(width 0.127)
		(layer "B.Cu")
		(net 189)
	)
	(segment
		(start 92.447953 143.605655)
		(end 92.806907 143.605655)
		(width 0.127)
		(layer "B.Cu")
		(net 189)
	)
	(segment
		(start 88.06358 146.2645)
		(end 89.789108 146.2645)
		(width 0.127)
		(layer "B.Cu")
		(net 189)
	)
	(segment
		(start 85.95 150.59)
		(end 85.95 150.580462)
		(width 0.127)
		(layer "B.Cu")
		(net 189)
	)
	(segment
		(start 85.95 150.580462)
		(end 85.965962 150.5645)
		(width 0.127)
		(layer "B.Cu")
		(net 189)
	)
	(segment
		(start 89.789108 146.2645)
		(end 92.447953 143.605655)
		(width 0.127)
		(layer "B.Cu")
		(net 189)
	)
	(segment
		(start 85.965962 150.5645)
		(end 85.965962 148.362118)
		(width 0.127)
		(layer "B.Cu")
		(net 189)
	)
	(segment
		(start 95.292962 137.7165)
		(end 95.266962 137.6905)
		(width 0.127)
		(layer "F.Cu")
		(net 190)
	)
	(segment
		(start 94.467448 137.907236)
		(end 94.017962 137.907236)
		(width 0.127)
		(layer "F.Cu")
		(net 190)
	)
	(segment
		(start 85.367962 151.5965)
		(end 85.367962 150.5665)
		(width 0.127)
		(layer "F.Cu")
		(net 190)
	)
	(segment
		(start 95.266962 137.6905)
		(end 94.684184 137.6905)
		(width 0.127)
		(layer "F.Cu")
		(net 190)
	)
	(segment
		(start 94.684184 137.6905)
		(end 94.467448 137.907236)
		(width 0.127)
		(layer "F.Cu")
		(net 190)
	)
	(via
		(at 95.292962 137.7165)
		(size 0.45)
		(drill 0.1)
		(layers "F.Cu" "B.Cu")
		(net 190)
	)
	(via
		(at 85.367962 150.5665)
		(size 0.45)
		(drill 0.1)
		(layers "F.Cu" "B.Cu")
		(net 190)
	)
	(segment
		(start 95.067962 141.222882)
		(end 94.474344 141.222882)
		(width 0.127)
		(layer "B.Cu")
		(net 190)
	)
	(segment
		(start 96.067962 138.710118)
		(end 96.067962 140.222882)
		(width 0.127)
		(layer "B.Cu")
		(net 190)
	)
	(segment
		(start 87.959198 146.0125)
		(end 85.713962 148.257736)
		(width 0.127)
		(layer "B.Cu")
		(net 190)
	)
	(segment
		(start 95.292962 137.7165)
		(end 95.292962 137.935118)
		(width 0.127)
		(layer "B.Cu")
		(net 190)
	)
	(segment
		(start 85.713962 148.257736)
		(end 85.713962 149.632736)
		(width 0.127)
		(layer "B.Cu")
		(net 190)
	)
	(segment
		(start 89.684726 146.0125)
		(end 87.959198 146.0125)
		(width 0.127)
		(layer "B.Cu")
		(net 190)
	)
	(segment
		(start 96.067962 140.222882)
		(end 95.067962 141.222882)
		(width 0.127)
		(layer "B.Cu")
		(net 190)
	)
	(segment
		(start 94.474344 141.222882)
		(end 89.684726 146.0125)
		(width 0.127)
		(layer "B.Cu")
		(net 190)
	)
	(segment
		(start 95.292962 137.935118)
		(end 96.067962 138.710118)
		(width 0.127)
		(layer "B.Cu")
		(net 190)
	)
	(segment
		(start 85.367962 149.978736)
		(end 85.367962 150.5665)
		(width 0.127)
		(layer "B.Cu")
		(net 190)
	)
	(segment
		(start 85.713962 149.632736)
		(end 85.367962 149.978736)
		(width 0.127)
		(layer "B.Cu")
		(net 190)
	)
	(segment
		(start 84.793677 150.595214)
		(end 84.964962 150.766499)
		(width 0.127)
		(layer "F.Cu")
		(net 191)
	)
	(segment
		(start 84.964962 150.766499)
		(end 84.964962 151.5965)
		(width 0.127)
		(layer "F.Cu")
		(net 191)
	)
	(segment
		(start 94.855462 138.104)
		(end 94.652226 138.307236)
		(width 0.127)
		(layer "F.Cu")
		(net 191)
	)
	(segment
		(start 94.652226 138.307236)
		(end 94.017962 138.307236)
		(width 0.127)
		(layer "F.Cu")
		(net 191)
	)
	(via
		(at 84.793677 150.595214)
		(size 0.45)
		(drill 0.1)
		(layers "F.Cu" "B.Cu")
		(net 191)
	)
	(via
		(at 94.855462 138.104)
		(size 0.45)
		(drill 0.1)
		(layers "F.Cu" "B.Cu")
		(net 191)
	)
	(segment
		(start 95.815962 138.8145)
		(end 95.105462 138.104)
		(width 0.127)
		(layer "B.Cu")
		(net 191)
	)
	(segment
		(start 94.96358 140.970882)
		(end 95.815962 140.1185)
		(width 0.127)
		(layer "B.Cu")
		(net 191)
	)
	(segment
		(start 89.580344 145.7605)
		(end 94.369962 140.970882)
		(width 0.127)
		(layer "B.Cu")
		(net 191)
	)
	(segment
		(start 87.854816 145.7605)
		(end 89.580344 145.7605)
		(width 0.127)
		(layer "B.Cu")
		(net 191)
	)
	(segment
		(start 94.369962 140.970882)
		(end 94.96358 140.970882)
		(width 0.127)
		(layer "B.Cu")
		(net 191)
	)
	(segment
		(start 84.793677 150.196639)
		(end 85.461962 149.528354)
		(width 0.127)
		(layer "B.Cu")
		(net 191)
	)
	(segment
		(start 95.815962 140.1185)
		(end 95.815962 138.8145)
		(width 0.127)
		(layer "B.Cu")
		(net 191)
	)
	(segment
		(start 95.105462 138.104)
		(end 94.855462 138.104)
		(width 0.127)
		(layer "B.Cu")
		(net 191)
	)
	(segment
		(start 85.461962 148.153354)
		(end 87.854816 145.7605)
		(width 0.127)
		(layer "B.Cu")
		(net 191)
	)
	(segment
		(start 84.793677 150.595214)
		(end 84.793677 150.196639)
		(width 0.127)
		(layer "B.Cu")
		(net 191)
	)
	(segment
		(start 85.461962 149.528354)
		(end 85.461962 148.153354)
		(width 0.127)
		(layer "B.Cu")
		(net 191)
	)
	(via
		(at 118.142962 126.2415)
		(size 0.45)
		(drill 0.1)
		(layers "F.Cu" "B.Cu")
		(net 192)
	)
	(segment
		(start 120.619962 123.769)
		(end 119.690462 123.769)
		(width 0.2)
		(layer "B.Cu")
		(net 192)
	)
	(segment
		(start 119.690462 123.769)
		(end 119.042962 124.4165)
		(width 0.2)
		(layer "B.Cu")
		(net 192)
	)
	(segment
		(start 119.042962 124.4165)
		(end 119.042962 125.3415)
		(width 0.2)
		(layer "B.Cu")
		(net 192)
	)
	(segment
		(start 119.042962 125.3415)
		(end 118.142962 126.2415)
		(width 0.2)
		(layer "B.Cu")
		(net 192)
	)
	(via
		(at 118.15 127.25)
		(size 0.45)
		(drill 0.1)
		(layers "F.Cu" "B.Cu")
		(net 193)
	)
	(segment
		(start 120.619962 124.269)
		(end 119.665462 124.269)
		(width 0.2)
		(layer "B.Cu")
		(net 193)
	)
	(segment
		(start 119.665462 124.269)
		(end 119.367962 124.5665)
		(width 0.2)
		(layer "B.Cu")
		(net 193)
	)
	(segment
		(start 119.367962 124.5665)
		(end 119.367962 126.032038)
		(width 0.2)
		(layer "B.Cu")
		(net 193)
	)
	(segment
		(start 119.367962 126.032038)
		(end 118.15 127.25)
		(width 0.2)
		(layer "B.Cu")
		(net 193)
	)
	(segment
		(start 101.067962 122.1865)
		(end 101.067962 121.804)
		(width 0.15)
		(layer "F.Cu")
		(net 203)
	)
	(segment
		(start 91.767962 120.921929)
		(end 91.767962 121.696929)
		(width 0.15)
		(layer "F.Cu")
		(net 203)
	)
	(segment
		(start 91.767962 121.696929)
		(end 91.767962 122.4765)
		(width 0.127)
		(layer "F.Cu")
		(net 203)
	)
	(segment
		(start 91.542135 120.315673)
		(end 91.316451 120.315673)
		(width 0.15)
		(layer "F.Cu")
		(net 203)
	)
	(segment
		(start 94.267962 118.2065)
		(end 94.267962 119.1165)
		(width 0.15)
		(layer "F.Cu")
		(net 203)
	)
	(segment
		(start 91.767962 120.921929)
		(end 91.767962 120.5415)
		(width 0.15)
		(layer "F.Cu")
		(net 203)
	)
	(segment
		(start 100.914962 121.651)
		(end 100.292962 121.651)
		(width 0.15)
		(layer "F.Cu")
		(net 203)
	)
	(segment
		(start 100.687962 122.5665)
		(end 101.067962 122.1865)
		(width 0.15)
		(layer "F.Cu")
		(net 203)
	)
	(segment
		(start 93.867962 117.8065)
		(end 94.267962 118.2065)
		(width 0.15)
		(layer "F.Cu")
		(net 203)
	)
	(segment
		(start 101.067962 121.804)
		(end 100.914962 121.651)
		(width 0.15)
		(layer "F.Cu")
		(net 203)
	)
	(segment
		(start 91.767962 120.5415)
		(end 91.542135 120.315673)
		(width 0.15)
		(layer "F.Cu")
		(net 203)
	)
	(via
		(at 91.767962 122.4765)
		(size 0.45)
		(drill 0.1)
		(layers "F.Cu" "B.Cu")
		(net 203)
	)
	(via
		(at 100.687962 122.5665)
		(size 0.45)
		(drill 0.1)
		(layers "F.Cu" "B.Cu")
		(net 203)
	)
	(via
		(at 93.867962 117.8065)
		(size 0.45)
		(drill 0.1)
		(layers "F.Cu" "B.Cu")
		(net 203)
	)
	(via
		(at 91.316451 120.315673)
		(size 0.45)
		(drill 0.1)
		(layers "F.Cu" "B.Cu")
		(net 203)
	)
	(segment
		(start 91.316451 119.718011)
		(end 91.316451 120.315673)
		(width 0.15)
		(layer "B.Cu")
		(net 203)
	)
	(segment
		(start 93.227962 117.8065)
		(end 91.316451 119.718011)
		(width 0.15)
		(layer "B.Cu")
		(net 203)
	)
	(segment
		(start 98.592962 122.5665)
		(end 97.367962 123.7915)
		(width 0.15)
		(layer "B.Cu")
		(net 203)
	)
	(segment
		(start 100.687962 122.5665)
		(end 98.592962 122.5665)
		(width 0.15)
		(layer "B.Cu")
		(net 203)
	)
	(segment
		(start 93.867962 117.8065)
		(end 93.227962 117.8065)
		(width 0.15)
		(layer "B.Cu")
		(net 203)
	)
	(segment
		(start 91.767962 122.8915)
		(end 91.767962 122.4765)
		(width 0.15)
		(layer "B.Cu")
		(net 203)
	)
	(segment
		(start 92.667962 123.7915)
		(end 91.767962 122.8915)
		(width 0.15)
		(layer "B.Cu")
		(net 203)
	)
	(segment
		(start 97.367962 123.7915)
		(end 92.667962 123.7915)
		(width 0.15)
		(layer "B.Cu")
		(net 203)
	)
	(segment
		(start 101.067962 120.5165)
		(end 101.067962 121.129)
		(width 0.15)
		(layer "F.Cu")
		(net 204)
	)
	(segment
		(start 91.762962 119.8915)
		(end 91.342962 119.8915)
		(width 0.15)
		(layer "F.Cu")
		(net 204)
	)
	(segment
		(start 91.268962 119.8175)
		(end 91.268962 119.1165)
		(width 0.15)
		(layer "F.Cu")
		(net 204)
	)
	(segment
		(start 101.067962 121.129)
		(end 100.947962 121.249)
		(width 0.15)
		(layer "F.Cu")
		(net 204)
	)
	(segment
		(start 91.342962 119.8915)
		(end 91.268962 119.8175)
		(width 0.15)
		(layer "F.Cu")
		(net 204)
	)
	(segment
		(start 100.947962 121.249)
		(end 100.292962 121.249)
		(width 0.15)
		(layer "F.Cu")
		(net 204)
	)
	(segment
		(start 92.266962 120.3955)
		(end 91.762962 119.8915)
		(width 0.15)
		(layer "F.Cu")
		(net 204)
	)
	(segment
		(start 92.266962 120.921929)
		(end 92.266962 120.3955)
		(width 0.15)
		(layer "F.Cu")
		(net 204)
	)
	(segment
		(start 92.266962 120.921929)
		(end 92.266962 121.695929)
		(width 0.15)
		(layer "F.Cu")
		(net 204)
	)
	(segment
		(start 100.827962 120.2765)
		(end 101.067962 120.5165)
		(width 0.15)
		(layer "F.Cu")
		(net 204)
	)
	(segment
		(start 92.267962 122.7665)
		(end 92.267962 121.696929)
		(width 0.127)
		(layer "F.Cu")
		(net 204)
	)
	(via
		(at 92.267962 122.7665)
		(size 0.45)
		(drill 0.1)
		(layers "F.Cu" "B.Cu")
		(net 204)
	)
	(via
		(at 100.827962 120.2765)
		(size 0.45)
		(drill 0.1)
		(layers "F.Cu" "B.Cu")
		(net 204)
	)
	(segment
		(start 100.494054 120.2765)
		(end 97.254054 123.5165)
		(width 0.15)
		(layer "B.Cu")
		(net 204)
	)
	(segment
		(start 93.017962 123.5165)
		(end 92.267962 122.7665)
		(width 0.15)
		(layer "B.Cu")
		(net 204)
	)
	(segment
		(start 97.254054 123.5165)
		(end 93.017962 123.5165)
		(width 0.15)
		(layer "B.Cu")
		(net 204)
	)
	(segment
		(start 100.827962 120.2765)
		(end 100.494054 120.2765)
		(width 0.15)
		(layer "B.Cu")
		(net 204)
	)
	(segment
		(start 93.311712 120.02275)
		(end 93.267962 119.979001)
		(width 0.182)
		(layer "F.Cu")
		(net 205)
	)
	(segment
		(start 92.642962 120.2415)
		(end 92.892962 120.2415)
		(width 0.182)
		(layer "F.Cu")
		(net 205)
	)
	(segment
		(start 92.269962 119.8685)
		(end 92.642962 120.2415)
		(width 0.182)
		(layer "F.Cu")
		(net 205)
	)
	(segment
		(start 93.118962 122.628998)
		(end 93.328962 122.418998)
		(width 0.182)
		(layer "F.Cu")
		(net 205)
	)
	(segment
		(start 92.892962 120.2415)
		(end 93.111712 120.02275)
		(width 0.182)
		(layer "F.Cu")
		(net 205)
	)
	(segment
		(start 93.267962 122.05318)
		(end 93.267962 121.696929)
		(width 0.182)
		(layer "F.Cu")
		(net 205)
	)
	(segment
		(start 92.269962 119.1165)
		(end 92.269962 119.8685)
		(width 0.182)
		(layer "F.Cu")
		(net 205)
	)
	(segment
		(start 93.267962 120.921929)
		(end 93.267962 120.565678)
		(width 0.182)
		(layer "F.Cu")
		(net 205)
	)
	(segment
		(start 93.111712 120.02275)
		(end 93.311712 120.02275)
		(width 0.182)
		(layer "F.Cu")
		(net 205)
	)
	(segment
		(start 93.328962 120.504678)
		(end 93.328962 120.040001)
		(width 0.182)
		(layer "F.Cu")
		(net 205)
	)
	(segment
		(start 93.328962 122.418998)
		(end 93.328962 122.11418)
		(width 0.182)
		(layer "F.Cu")
		(net 205)
	)
	(segment
		(start 93.328962 120.040001)
		(end 93.311712 120.02275)
		(width 0.182)
		(layer "F.Cu")
		(net 205)
	)
	(segment
		(start 93.118962 123.303999)
		(end 93.118962 122.628998)
		(width 0.182)
		(layer "F.Cu")
		(net 205)
	)
	(segment
		(start 93.267962 120.565678)
		(end 93.328962 120.504678)
		(width 0.182)
		(layer "F.Cu")
		(net 205)
	)
	(segment
		(start 93.328962 122.11418)
		(end 93.267962 122.05318)
		(width 0.182)
		(layer "F.Cu")
		(net 205)
	)
	(segment
		(start 93.267962 119.1165)
		(end 93.267962 119.979001)
		(width 0.182)
		(layer "F.Cu")
		(net 205)
	)
	(segment
		(start 93.267962 121.696929)
		(end 93.267962 120.921929)
		(width 0.182)
		(layer "F.Cu")
		(net 205)
	)
	(segment
		(start 93.040938 118.2545)
		(end 92.830962 118.464476)
		(width 0.182)
		(layer "F.Cu")
		(net 206)
	)
	(segment
		(start 93.706962 120.040001)
		(end 93.767962 119.979001)
		(width 0.182)
		(layer "F.Cu")
		(net 206)
	)
	(segment
		(start 93.918962 122.628998)
		(end 93.706962 122.416998)
		(width 0.182)
		(layer "F.Cu")
		(net 206)
	)
	(segment
		(start 93.767962 120.565678)
		(end 93.706962 120.504678)
		(width 0.182)
		(layer "F.Cu")
		(net 206)
	)
	(segment
		(start 93.767962 119.1165)
		(end 93.704962 119.0535)
		(width 0.182)
		(layer "F.Cu")
		(net 206)
	)
	(segment
		(start 93.706962 122.416998)
		(end 93.706962 122.11418)
		(width 0.182)
		(layer "F.Cu")
		(net 206)
	)
	(segment
		(start 93.704962 118.464476)
		(end 93.494986 118.2545)
		(width 0.182)
		(layer "F.Cu")
		(net 206)
	)
	(segment
		(start 93.706962 120.504678)
		(end 93.706962 120.040001)
		(width 0.182)
		(layer "F.Cu")
		(net 206)
	)
	(segment
		(start 93.767962 119.979001)
		(end 93.767962 119.1165)
		(width 0.182)
		(layer "F.Cu")
		(net 206)
	)
	(segment
		(start 93.767962 120.921929)
		(end 93.767962 120.565678)
		(width 0.182)
		(layer "F.Cu")
		(net 206)
	)
	(segment
		(start 92.830962 118.464476)
		(end 92.830962 119.0555)
		(width 0.182)
		(layer "F.Cu")
		(net 206)
	)
	(segment
		(start 92.830962 119.0555)
		(end 92.769962 119.1165)
		(width 0.182)
		(layer "F.Cu")
		(net 206)
	)
	(segment
		(start 93.918962 123.303999)
		(end 93.918962 122.628998)
		(width 0.182)
		(layer "F.Cu")
		(net 206)
	)
	(segment
		(start 93.767962 122.05318)
		(end 93.767962 121.696929)
		(width 0.182)
		(layer "F.Cu")
		(net 206)
	)
	(segment
		(start 93.704962 119.0535)
		(end 93.704962 118.464476)
		(width 0.182)
		(layer "F.Cu")
		(net 206)
	)
	(segment
		(start 93.767962 121.696929)
		(end 93.767962 120.921929)
		(width 0.182)
		(layer "F.Cu")
		(net 206)
	)
	(segment
		(start 93.706962 122.11418)
		(end 93.767962 122.05318)
		(width 0.182)
		(layer "F.Cu")
		(net 206)
	)
	(segment
		(start 93.494986 118.2545)
		(end 93.040938 118.2545)
		(width 0.182)
		(layer "F.Cu")
		(net 206)
	)
	(segment
		(start 88.656462 127.43)
		(end 85.104462 123.878)
		(width 0.127)
		(layer "F.Cu")
		(net 207)
	)
	(segment
		(start 78.530962 120.979)
		(end 78.530962 120.392)
		(width 0.127)
		(layer "F.Cu")
		(net 207)
	)
	(segment
		(start 79.84808 123.878)
		(end 78.530962 122.560882)
		(width 0.127)
		(layer "F.Cu")
		(net 207)
	)
	(segment
		(start 78.530962 122.560882)
		(end 78.530962 121.854)
		(width 0.127)
		(layer "F.Cu")
		(net 207)
	)
	(segment
		(start 88.321462 130.223)
		(end 88.656462 129.888)
		(width 0.127)
		(layer "F.Cu")
		(net 207)
	)
	(segment
		(start 88.321462 131.161462)
		(end 88.321462 130.223)
		(width 0.127)
		(layer "F.Cu")
		(net 207)
	)
	(segment
		(start 81.030962 118.232318)
		(end 81.030962 119.102)
		(width 0.127)
		(layer "F.Cu")
		(net 207)
	)
	(segment
		(start 88.681462 131.521462)
		(end 88.321462 131.161462)
		(width 0.127)
		(layer "F.Cu")
		(net 207)
	)
	(segment
		(start 88.681462 133.266736)
		(end 88.681462 131.521462)
		(width 0.127)
		(layer "F.Cu")
		(net 207)
	)
	(segment
		(start 78.530962 121.754)
		(end 78.530962 120.979)
		(width 0.127)
		(layer "F.Cu")
		(net 207)
	)
	(segment
		(start 78.530962 120.392)
		(end 78.517962 120.379)
		(width 0.127)
		(layer "F.Cu")
		(net 207)
	)
	(segment
		(start 88.467962 133.957236)
		(end 88.467962 133.480236)
		(width 0.127)
		(layer "F.Cu")
		(net 207)
	)
	(segment
		(start 85.104462 123.878)
		(end 79.84808 123.878)
		(width 0.127)
		(layer "F.Cu")
		(net 207)
	)
	(segment
		(start 88.656462 129.888)
		(end 88.656462 127.43)
		(width 0.127)
		(layer "F.Cu")
		(net 207)
	)
	(segment
		(start 80.691553 117.892909)
		(end 81.030962 118.232318)
		(width 0.127)
		(layer "F.Cu")
		(net 207)
	)
	(segment
		(start 88.467962 133.480236)
		(end 88.681462 133.266736)
		(width 0.127)
		(layer "F.Cu")
		(net 207)
	)
	(via
		(at 78.517962 120.3665)
		(size 0.45)
		(drill 0.1)
		(layers "F.Cu" "B.Cu")
		(net 207)
	)
	(via
		(at 80.691553 117.892909)
		(size 0.45)
		(drill 0.1)
		(layers "F.Cu" "B.Cu")
		(net 207)
	)
	(segment
		(start 80.691553 117.892909)
		(end 80.491553 117.892909)
		(width 0.127)
		(layer "B.Cu")
		(net 207)
	)
	(segment
		(start 80.491553 117.892909)
		(end 78.517962 119.8665)
		(width 0.127)
		(layer "B.Cu")
		(net 207)
	)
	(segment
		(start 78.517962 119.8665)
		(end 78.517962 120.3665)
		(width 0.127)
		(layer "B.Cu")
		(net 207)
	)
	(segment
		(start 78.031962 119.7805)
		(end 78.116962 119.8655)
		(width 0.127)
		(layer "F.Cu")
		(net 208)
	)
	(segment
		(start 89.667962 133.957236)
		(end 89.667962 133.0765)
		(width 0.127)
		(layer "F.Cu")
		(net 208)
	)
	(segment
		(start 79.029962 120.2785)
		(end 79.029962 120.979)
		(width 0.127)
		(layer "F.Cu")
		(net 208)
	)
	(segment
		(start 88.936448 130.123609)
		(end 88.936448 127.353604)
		(width 0.127)
		(layer "F.Cu")
		(net 208)
	)
	(segment
		(start 78.616962 119.8655)
		(end 79.029962 120.2785)
		(width 0.127)
		(layer "F.Cu")
		(net 208)
	)
	(segment
		(start 78.031962 119.102)
		(end 78.031962 119.7805)
		(width 0.127)
		(layer "F.Cu")
		(net 208)
	)
	(segment
		(start 85.208844 123.626)
		(end 79.952462 123.626)
		(width 0.127)
		(layer "F.Cu")
		(net 208)
	)
	(segment
		(start 79.952462 123.626)
		(end 79.030962 122.7045)
		(width 0.127)
		(layer "F.Cu")
		(net 208)
	)
	(segment
		(start 89.667962 133.0765)
		(end 89.657962 133.0665)
		(width 0.127)
		(layer "F.Cu")
		(net 208)
	)
	(segment
		(start 88.936448 127.353604)
		(end 85.208844 123.626)
		(width 0.127)
		(layer "F.Cu")
		(net 208)
	)
	(segment
		(start 79.030962 122.7045)
		(end 79.030962 121.854)
		(width 0.127)
		(layer "F.Cu")
		(net 208)
	)
	(segment
		(start 89.523376 130.710537)
		(end 88.936448 130.123609)
		(width 0.127)
		(layer "F.Cu")
		(net 208)
	)
	(segment
		(start 78.116962 119.8655)
		(end 78.616962 119.8655)
		(width 0.127)
		(layer "F.Cu")
		(net 208)
	)
	(segment
		(start 79.030962 121.754)
		(end 79.030962 120.9425)
		(width 0.127)
		(layer "F.Cu")
		(net 208)
	)
	(via
		(at 89.523376 130.710537)
		(size 0.45)
		(drill 0.1)
		(layers "F.Cu" "B.Cu")
		(net 208)
	)
	(via
		(at 89.657962 133.0665)
		(size 0.45)
		(drill 0.1)
		(layers "F.Cu" "B.Cu")
		(net 208)
	)
	(segment
		(start 89.657962 133.0665)
		(end 89.657962 131.6265)
		(width 0.127)
		(layer "B.Cu")
		(net 208)
	)
	(segment
		(start 89.657962 131.6265)
		(end 89.523376 131.491914)
		(width 0.127)
		(layer "B.Cu")
		(net 208)
	)
	(segment
		(start 89.523376 130.710537)
		(end 89.523376 131.491914)
		(width 0.127)
		(layer "B.Cu")
		(net 208)
	)
	(segment
		(start 80.030962 119.102)
		(end 80.030962 119.964501)
		(width 0.182)
		(layer "F.Cu")
		(net 209)
	)
	(segment
		(start 80.030962 120.585249)
		(end 80.030962 120.979)
		(width 0.182)
		(layer "F.Cu")
		(net 209)
	)
	(segment
		(start 83.142962 123.0665)
		(end 82.603962 123.0665)
		(width 0.182)
		(layer "F.Cu")
		(net 209)
	)
	(segment
		(start 80.030962 119.964501)
		(end 80.091962 120.025501)
		(width 0.182)
		(layer "F.Cu")
		(net 209)
	)
	(segment
		(start 80.030962 122.110251)
		(end 80.030962 121.754)
		(width 0.182)
		(layer "F.Cu")
		(net 209)
	)
	(segment
		(start 82.603962 123.0665)
		(end 82.392962 122.8555)
		(width 0.182)
		(layer "F.Cu")
		(net 209)
	)
	(segment
		(start 80.091962 122.4665)
		(end 80.091962 122.171251)
		(width 0.182)
		(layer "F.Cu")
		(net 209)
	)
	(segment
		(start 80.030962 119.964501)
		(end 79.215963 119.964501)
		(width 0.182)
		(layer "F.Cu")
		(net 209)
	)
	(segment
		(start 80.480962 122.8555)
		(end 80.091962 122.4665)
		(width 0.182)
		(layer "F.Cu")
		(net 209)
	)
	(segment
		(start 80.091962 120.524249)
		(end 80.030962 120.585249)
		(width 0.182)
		(layer "F.Cu")
		(net 209)
	)
	(segment
		(start 79.215963 119.964501)
		(end 79.032962 119.7815)
		(width 0.182)
		(layer "F.Cu")
		(net 209)
	)
	(segment
		(start 79.032962 119.7815)
		(end 79.032962 119.102)
		(width 0.182)
		(layer "F.Cu")
		(net 209)
	)
	(segment
		(start 80.091962 120.025501)
		(end 80.091962 120.524249)
		(width 0.182)
		(layer "F.Cu")
		(net 209)
	)
	(segment
		(start 80.030962 120.979)
		(end 80.030962 121.754)
		(width 0.182)
		(layer "F.Cu")
		(net 209)
	)
	(segment
		(start 82.392962 122.8555)
		(end 80.480962 122.8555)
		(width 0.182)
		(layer "F.Cu")
		(net 209)
	)
	(segment
		(start 80.091962 122.171251)
		(end 80.030962 122.110251)
		(width 0.182)
		(layer "F.Cu")
		(net 209)
	)
	(segment
		(start 79.593962 119.041)
		(end 79.532962 119.102)
		(width 0.182)
		(layer "F.Cu")
		(net 210)
	)
	(segment
		(start 80.469962 120.025501)
		(end 80.469962 120.524249)
		(width 0.182)
		(layer "F.Cu")
		(net 210)
	)
	(segment
		(start 80.530962 122.111)
		(end 80.530962 121.754)
		(width 0.182)
		(layer "F.Cu")
		(net 210)
	)
	(segment
		(start 81.619402 121.928939)
		(end 81.567962 121.928939)
		(width 0.182)
		(layer "F.Cu")
		(net 210)
	)
	(segment
		(start 80.469962 122.172)
		(end 80.530962 122.111)
		(width 0.182)
		(layer "F.Cu")
		(net 210)
	)
	(segment
		(start 79.803938 118.24)
		(end 79.593962 118.449976)
		(width 0.182)
		(layer "F.Cu")
		(net 210)
	)
	(segment
		(start 81.293682 122.203219)
		(end 81.293682 122.20322)
		(width 0.182)
		(layer "F.Cu")
		(net 210)
	)
	(segment
		(start 80.467962 119.039)
		(end 80.467962 118.449976)
		(width 0.182)
		(layer "F.Cu")
		(net 210)
	)
	(segment
		(start 80.469962 120.524249)
		(end 80.530962 120.585249)
		(width 0.182)
		(layer "F.Cu")
		(net 210)
	)
	(segment
		(start 80.530962 119.102)
		(end 80.467962 119.039)
		(width 0.182)
		(layer "F.Cu")
		(net 210)
	)
	(segment
		(start 80.530962 120.585249)
		(end 80.530962 120.979)
		(width 0.182)
		(layer "F.Cu")
		(net 210)
	)
	(segment
		(start 82.592962 122.2665)
		(end 82.381962 122.4775)
		(width 0.182)
		(layer "F.Cu")
		(net 210)
	)
	(segment
		(start 81.019402 122.4775)
		(end 80.967962 122.4775)
		(width 0.182)
		(layer "F.Cu")
		(net 210)
	)
	(segment
		(start 80.530962 120.979)
		(end 80.530962 121.754)
		(width 0.182)
		(layer "F.Cu")
		(net 210)
	)
	(segment
		(start 79.593962 118.449976)
		(end 79.593962 119.041)
		(width 0.182)
		(layer "F.Cu")
		(net 210)
	)
	(segment
		(start 80.467962 118.449976)
		(end 80.257986 118.24)
		(width 0.182)
		(layer "F.Cu")
		(net 210)
	)
	(segment
		(start 80.967962 122.4775)
		(end 80.637534 122.4775)
		(width 0.182)
		(layer "F.Cu")
		(net 210)
	)
	(segment
		(start 82.381962 122.4775)
		(end 82.167962 122.4775)
		(width 0.182)
		(layer "F.Cu")
		(net 210)
	)
	(segment
		(start 80.257986 118.24)
		(end 79.803938 118.24)
		(width 0.182)
		(layer "F.Cu")
		(net 210)
	)
	(segment
		(start 83.142962 122.2665)
		(end 82.592962 122.2665)
		(width 0.182)
		(layer "F.Cu")
		(net 210)
	)
	(segment
		(start 80.530962 119.102)
		(end 80.530962 119.964501)
		(width 0.182)
		(layer "F.Cu")
		(net 210)
	)
	(segment
		(start 80.637534 122.4775)
		(end 80.469962 122.309928)
		(width 0.182)
		(layer "F.Cu")
		(net 210)
	)
	(segment
		(start 80.469962 122.309928)
		(end 80.469962 122.172)
		(width 0.182)
		(layer "F.Cu")
		(net 210)
	)
	(segment
		(start 80.530962 119.964501)
		(end 80.469962 120.025501)
		(width 0.182)
		(layer "F.Cu")
		(net 210)
	)
	(segment
		(start 81.893682 122.20322)
		(end 81.893682 122.203219)
		(width 0.182)
		(layer "F.Cu")
		(net 210)
	)
	(arc
		(start 81.893682 122.203219)
		(mid 81.813347 122.009274)
		(end 81.619402 121.928939)
		(width 0.182)
		(layer "F.Cu")
		(net 210)
	)
	(arc
		(start 81.293682 122.20322)
		(mid 81.213347 122.397165)
		(end 81.019402 122.4775)
		(width 0.182)
		(layer "F.Cu")
		(net 210)
	)
	(arc
		(start 81.567962 121.928939)
		(mid 81.374017 122.009274)
		(end 81.293682 122.203219)
		(width 0.182)
		(layer "F.Cu")
		(net 210)
	)
	(arc
		(start 82.167962 122.4775)
		(mid 81.974017 122.397165)
		(end 81.893682 122.20322)
		(width 0.182)
		(layer "F.Cu")
		(net 210)
	)
	(segment
		(start 89.95183 134.550368)
		(end 89.885698 134.6165)
		(width 0.254)
		(layer "F.Cu")
		(net 211)
	)
	(segment
		(start 89.885698 134.6165)
		(end 89.317962 134.6165)
		(width 0.254)
		(layer "F.Cu")
		(net 211)
	)
	(segment
		(start 88.867962 133.957236)
		(end 88.867962 134.384236)
		(width 0.127)
		(layer "F.Cu")
		(net 211)
	)
	(segment
		(start 89.100226 134.6165)
		(end 88.984094 134.500368)
		(width 0.254)
		(layer "F.Cu")
		(net 211)
	)
	(segment
		(start 90.067962 133.2915)
		(end 90.067962 133.957236)
		(width 0.2)
		(layer "F.Cu")
		(net 211)
	)
	(segment
		(start 89.95183 134.550368)
		(end 90.067962 134.434236)
		(width 0.127)
		(layer "F.Cu")
		(net 211)
	)
	(segment
		(start 90.192962 130.5315)
		(end 90.192962 132.397236)
		(width 0.2)
		(layer "F.Cu")
		(net 211)
	)
	(segment
		(start 90.147962 133.2115)
		(end 90.067962 133.2915)
		(width 0.2)
		(layer "F.Cu")
		(net 211)
	)
	(segment
		(start 90.147962 132.442236)
		(end 90.147962 133.2115)
		(width 0.2)
		(layer "F.Cu")
		(net 211)
	)
	(segment
		(start 90.192962 132.397236)
		(end 90.147962 132.442236)
		(width 0.2)
		(layer "F.Cu")
		(net 211)
	)
	(segment
		(start 89.317962 134.6165)
		(end 89.100226 134.6165)
		(width 0.254)
		(layer "F.Cu")
		(net 211)
	)
	(segment
		(start 88.867962 134.384236)
		(end 88.984094 134.500368)
		(width 0.127)
		(layer "F.Cu")
		(net 211)
	)
	(segment
		(start 90.067962 134.434236)
		(end 90.067962 133.957236)
		(width 0.127)
		(layer "F.Cu")
		(net 211)
	)
	(segment
		(start 79.103614 147.717)
		(end 78.473961 147.717)
		(width 0.15)
		(layer "F.Cu")
		(net 212)
	)
	(segment
		(start 79.245504 147.57511)
		(end 79.103614 147.717)
		(width 0.15)
		(layer "F.Cu")
		(net 212)
	)
	(via
		(at 79.245504 147.57511)
		(size 0.45)
		(drill 0.1)
		(layers "F.Cu" "B.Cu")
		(net 212)
	)
	(segment
		(start 79.245504 147.57511)
		(end 78.617962 146.947568)
		(width 0.2)
		(layer "B.Cu")
		(net 212)
	)
	(segment
		(start 80.65 147.262039)
		(end 81.104961 147.717)
		(width 0.15)
		(layer "F.Cu")
		(net 213)
	)
	(segment
		(start 80.65 146.9)
		(end 80.65 147.262039)
		(width 0.15)
		(layer "F.Cu")
		(net 213)
	)
	(segment
		(start 81.104961 147.717)
		(end 81.554961 147.717)
		(width 0.15)
		(layer "F.Cu")
		(net 213)
	)
	(via
		(at 80.542962 146.9165)
		(size 0.45)
		(drill 0.1)
		(layers "F.Cu" "B.Cu")
		(net 213)
	)
	(segment
		(start 79.421885 148.130269)
		(end 78.48623 148.130269)
		(width 0.15)
		(layer "F.Cu")
		(net 214)
	)
	(segment
		(start 79.820256 147.731898)
		(end 79.421885 148.130269)
		(width 0.15)
		(layer "F.Cu")
		(net 214)
	)
	(segment
		(start 79.820256 147.592111)
		(end 79.820256 147.731898)
		(width 0.15)
		(layer "F.Cu")
		(net 214)
	)
	(via
		(at 79.820256 147.592111)
		(size 0.45)
		(drill 0.1)
		(layers "F.Cu" "B.Cu")
		(net 214)
	)
	(segment
		(start 79.670844 147.442699)
		(end 79.670844 147.029382)
		(width 0.15)
		(layer "B.Cu")
		(net 214)
	)
	(segment
		(start 79.820256 147.592111)
		(end 79.670844 147.442699)
		(width 0.15)
		(layer "B.Cu")
		(net 214)
	)
	(segment
		(start 80.768 148.118)
		(end 81.554961 148.118)
		(width 0.15)
		(layer "F.Cu")
		(net 215)
	)
	(segment
		(start 80.55 147.9)
		(end 80.768 148.118)
		(width 0.15)
		(layer "F.Cu")
		(net 215)
	)
	(via
		(at 80.542962 147.7915)
		(size 0.45)
		(drill 0.1)
		(layers "F.Cu" "B.Cu")
		(net 215)
	)
	(segment
		(start 81.554961 148.517)
		(end 82.583462 148.517)
		(width 0.15)
		(layer "F.Cu")
		(net 216)
	)
	(segment
		(start 141.905462 140.4165)
		(end 142.680462 140.4165)
		(width 0.127)
		(layer "F.Cu")
		(net 217)
	)
	(segment
		(start 143.067962 140.4165)
		(end 143.217962 140.2665)
		(width 0.127)
		(layer "F.Cu")
		(net 217)
	)
	(segment
		(start 82.85274 149.7665)
		(end 82.40224 149.316)
		(width 0.127)
		(layer "F.Cu")
		(net 217)
	)
	(segment
		(start 139.917962 139.9665)
		(end 139.392962 140.4915)
		(width 0.127)
		(layer "F.Cu")
		(net 217)
	)
	(segment
		(start 82.40224 149.316)
		(end 81.554961 149.316)
		(width 0.127)
		(layer "F.Cu")
		(net 217)
	)
	(segment
		(start 139.516962 141.4665)
		(end 140.393962 141.4665)
		(width 0.127)
		(layer "F.Cu")
		(net 217)
	)
	(segment
		(start 139.392962 141.3425)
		(end 139.516962 141.4665)
		(width 0.127)
		(layer "F.Cu")
		(net 217)
	)
	(segment
		(start 142.680462 140.4165)
		(end 143.067962 140.4165)
		(width 0.127)
		(layer "F.Cu")
		(net 217)
	)
	(segment
		(start 139.392962 140.4915)
		(end 139.392962 141.3425)
		(width 0.127)
		(layer "F.Cu")
		(net 217)
	)
	(segment
		(start 82.942962 149.7665)
		(end 82.85274 149.7665)
		(width 0.127)
		(layer "F.Cu")
		(net 217)
	)
	(segment
		(start 141.905462 140.4165)
		(end 141.467962 140.4165)
		(width 0.127)
		(layer "F.Cu")
		(net 217)
	)
	(segment
		(start 141.017962 139.9665)
		(end 139.917962 139.9665)
		(width 0.127)
		(layer "F.Cu")
		(net 217)
	)
	(segment
		(start 141.467962 140.4165)
		(end 141.017962 139.9665)
		(width 0.127)
		(layer "F.Cu")
		(net 217)
	)
	(via
		(at 123.367019 160.1165)
		(size 0.45)
		(drill 0.1)
		(layers "F.Cu" "B.Cu")
		(free yes)
		(net 217)
	)
	(via
		(at 82.942962 149.7665)
		(size 0.45)
		(drill 0.1)
		(layers "F.Cu" "B.Cu")
		(net 217)
	)
	(via
		(at 143.217962 140.2665)
		(size 0.45)
		(drill 0.1)
		(layers "F.Cu" "B.Cu")
		(net 217)
	)
	(segment
		(start 118.675108 165.7035)
		(end 123.367019 161.011589)
		(width 0.127)
		(layer "In2.Cu")
		(net 217)
	)
	(segment
		(start 108.388984 165.7035)
		(end 118.675108 165.7035)
		(width 0.127)
		(layer "In2.Cu")
		(net 217)
	)
	(segment
		(start 87.538108 156.9925)
		(end 99.677984 156.9925)
		(width 0.127)
		(layer "In2.Cu")
		(net 217)
	)
	(segment
		(start 123.367019 161.011589)
		(end 123.367019 159.9355)
		(width 0.127)
		(layer "In2.Cu")
		(net 217)
	)
	(segment
		(start 84.525962 151.3495)
		(end 84.525962 153.980354)
		(width 0.127)
		(layer "In2.Cu")
		(net 217)
	)
	(segment
		(start 84.525962 153.980354)
		(end 87.538108 156.9925)
		(width 0.127)
		(layer "In2.Cu")
		(net 217)
	)
	(segment
		(start 82.942962 149.7665)
		(end 84.525962 151.3495)
		(width 0.127)
		(layer "In2.Cu")
		(net 217)
	)
	(segment
		(start 99.677984 156.9925)
		(end 108.388984 165.7035)
		(width 0.127)
		(layer "In2.Cu")
		(net 217)
	)
	(segment
		(start 142.115962 142.4285)
		(end 136.588962 147.9555)
		(width 0.127)
		(layer "In3.Cu")
		(net 217)
	)
	(segment
		(start 126.567962 155.9765)
		(end 123.367019 159.177443)
		(width 0.127)
		(layer "In3.Cu")
		(net 217)
	)
	(segment
		(start 133.937962 155.9765)
		(end 126.567962 155.9765)
		(width 0.127)
		(layer "In3.Cu")
		(net 217)
	)
	(segment
		(start 142.115962 141.358722)
		(end 142.115962 142.4285)
		(width 0.127)
		(layer "In3.Cu")
		(net 217)
	)
	(segment
		(start 136.588962 147.9555)
		(end 136.588962 153.3255)
		(width 0.127)
		(layer "In3.Cu")
		(net 217)
	)
	(segment
		(start 143.208184 140.2665)
		(end 142.115962 141.358722)
		(width 0.127)
		(layer "In3.Cu")
		(net 217)
	)
	(segment
		(start 136.588962 153.3255)
		(end 133.937962 155.9765)
		(width 0.127)
		(layer "In3.Cu")
		(net 217)
	)
	(segment
		(start 143.217962 140.2665)
		(end 143.208184 140.2665)
		(width 0.127)
		(layer "In3.Cu")
		(net 217)
	)
	(segment
		(start 123.367019 159.177443)
		(end 123.367019 160.1165)
		(width 0.127)
		(layer "In3.Cu")
		(net 217)
	)
	(segment
		(start 139.092962 136.407344)
		(end 137.942962 137.557344)
		(width 0.127)
		(layer "F.Cu")
		(net 218)
	)
	(segment
		(start 137.942962 140.0665)
		(end 137.042962 140.9665)
		(width 0.127)
		(layer "F.Cu")
		(net 218)
	)
	(segment
		(start 139.092962 134.741498)
		(end 138.942963 134.591499)
		(width 0.15)
		(layer "F.Cu")
		(net 218)
	)
	(segment
		(start 77.866152 149.781282)
		(end 77.930434 149.717)
		(width 0.127)
		(layer "F.Cu")
		(net 218)
	)
	(segment
		(start 77.930434 149.717)
		(end 78.473961 149.717)
		(width 0.127)
		(layer "F.Cu")
		(net 218)
	)
	(segment
		(start 137.942962 137.557344)
		(end 137.942962 140.0665)
		(width 0.127)
		(layer "F.Cu")
		(net 218)
	)
	(segment
		(start 139.092962 135.1915)
		(end 139.092962 134.741498)
		(width 0.15)
		(layer "F.Cu")
		(net 218)
	)
	(segment
		(start 139.092962 135.9665)
		(end 139.092962 136.407344)
		(width 0.127)
		(layer "F.Cu")
		(net 218)
	)
	(segment
		(start 139.092962 135.979)
		(end 139.092962 135.204)
		(width 0.127)
		(layer "F.Cu")
		(net 218)
	)
	(segment
		(start 139.092963 134.741499)
		(end 138.942963 134.591499)
		(width 0.127)
		(layer "F.Cu")
		(net 218)
	)
	(via
		(at 77.866152 149.781282)
		(size 0.45)
		(drill 0.1)
		(layers "F.Cu" "B.Cu")
		(net 218)
	)
	(via
		(at 138.942963 134.591499)
		(size 0.45)
		(drill 0.1)
		(layers "F.Cu" "B.Cu")
		(net 218)
	)
	(segment
		(start 138.942963 136.985117)
		(end 138.942963 134.591499)
		(width 0.127)
		(layer "In2.Cu")
		(net 218)
	)
	(segment
		(start 134.471962 141.456118)
		(end 138.942963 136.985117)
		(width 0.127)
		(layer "In2.Cu")
		(net 218)
	)
	(segment
		(start 77.866152 149.782354)
		(end 78.669962 150.586164)
		(width 0.127)
		(layer "In2.Cu")
		(net 218)
	)
	(segment
		(start 132.123962 144.7855)
		(end 132.442962 144.4665)
		(width 0.127)
		(layer "In2.Cu")
		(net 218)
	)
	(segment
		(start 130.430962 167.576298)
		(end 130.430962 154.146299)
		(width 0.127)
		(layer "In2.Cu")
		(net 218)
	)
	(segment
		(start 131.312962 153.260681)
		(end 132.123962 152.44968)
		(width 0.127)
		(layer "In2.Cu")
		(net 218)
	)
	(segment
		(start 132.123962 152.44968)
		(end 132.123962 144.7855)
		(width 0.127)
		(layer "In2.Cu")
		(net 218)
	)
	(segment
		(start 78.669962 150.586164)
		(end 78.669962 157.843236)
		(width 0.127)
		(layer "In2.Cu")
		(net 218)
	)
	(segment
		(start 133.705726 144.4665)
		(end 134.471962 143.700264)
		(width 0.127)
		(layer "In2.Cu")
		(net 218)
	)
	(segment
		(start 130.430962 154.146299)
		(end 131.312962 153.264299)
		(width 0.127)
		(layer "In2.Cu")
		(net 218)
	)
	(segment
		(start 131.312962 153.264299)
		(end 131.312962 153.260681)
		(width 0.127)
		(layer "In2.Cu")
		(net 218)
	)
	(segment
		(start 77.866152 149.781282)
		(end 77.866152 149.782354)
		(width 0.127)
		(layer "In2.Cu")
		(net 218)
	)
	(segment
		(start 132.442962 144.4665)
		(end 133.705726 144.4665)
		(width 0.127)
		(layer "In2.Cu")
		(net 218)
	)
	(segment
		(start 106.510108 170.2395)
		(end 127.76776 170.2395)
		(width 0.127)
		(layer "In2.Cu")
		(net 218)
	)
	(segment
		(start 97.799108 161.5285)
		(end 106.510108 170.2395)
		(width 0.127)
		(layer "In2.Cu")
		(net 218)
	)
	(segment
		(start 82.355226 161.5285)
		(end 97.799108 161.5285)
		(width 0.127)
		(layer "In2.Cu")
		(net 218)
	)
	(segment
		(start 134.471962 143.700264)
		(end 134.471962 141.456118)
		(width 0.127)
		(layer "In2.Cu")
		(net 218)
	)
	(segment
		(start 78.669962 157.843236)
		(end 82.355226 161.5285)
		(width 0.127)
		(layer "In2.Cu")
		(net 218)
	)
	(segment
		(start 127.76776 170.2395)
		(end 130.430962 167.576298)
		(width 0.127)
		(layer "In2.Cu")
		(net 218)
	)
	(segment
		(start 141.367962 141.0665)
		(end 141.517962 140.9165)
		(width 0.127)
		(layer "F.Cu")
		(net 219)
	)
	(segment
		(start 142.680462 140.9165)
		(end 143.142962 140.9165)
		(width 0.127)
		(layer "F.Cu")
		(net 219)
	)
	(segment
		(start 143.142962 140.9165)
		(end 143.217962 140.8415)
		(width 0.127)
		(layer "F.Cu")
		(net 219)
	)
	(segment
		(start 141.905462 140.9165)
		(end 142.680462 140.9165)
		(width 0.127)
		(layer "F.Cu")
		(net 219)
	)
	(segment
		(start 82.218462 149.717)
		(end 81.554961 149.717)
		(width 0.127)
		(layer "F.Cu")
		(net 219)
	)
	(segment
		(start 82.267962 149.7665)
		(end 82.218462 149.717)
		(width 0.127)
		(layer "F.Cu")
		(net 219)
	)
	(segment
		(start 141.367962 141.6665)
		(end 141.367962 141.0665)
		(width 0.127)
		(layer "F.Cu")
		(net 219)
	)
	(segment
		(start 141.517962 140.9165)
		(end 141.905462 140.9165)
		(width 0.127)
		(layer "F.Cu")
		(net 219)
	)
	(segment
		(start 141.067962 141.9665)
		(end 141.367962 141.6665)
		(width 0.127)
		(layer "F.Cu")
		(net 219)
	)
	(via
		(at 82.267962 149.7665)
		(size 0.45)
		(drill 0.1)
		(layers "F.Cu" "B.Cu")
		(net 219)
	)
	(via
		(at 123.780519 159.397849)
		(size 0.45)
		(drill 0.1)
		(layers "F.Cu" "B.Cu")
		(free yes)
		(net 219)
	)
	(via
		(at 143.217962 140.8415)
		(size 0.45)
		(drill 0.1)
		(layers "F.Cu" "B.Cu")
		(net 219)
	)
	(segment
		(start 84.273962 154.084736)
		(end 87.433726 157.2445)
		(width 0.127)
		(layer "In2.Cu")
		(net 219)
	)
	(segment
		(start 82.267962 149.7665)
		(end 82.34349 149.7665)
		(width 0.127)
		(layer "In2.Cu")
		(net 219)
	)
	(segment
		(start 118.77949 165.9555)
		(end 123.780519 160.954471)
		(width 0.127)
		(layer "In2.Cu")
		(net 219)
	)
	(segment
		(start 82.34349 149.7665)
		(end 84.273962 151.696972)
		(width 0.127)
		(layer "In2.Cu")
		(net 219)
	)
	(segment
		(start 87.433726 157.2445)
		(end 99.573602 157.2445)
		(width 0.127)
		(layer "In2.Cu")
		(net 219)
	)
	(segment
		(start 123.780519 160.954471)
		(end 123.780519 159.397849)
		(width 0.127)
		(layer "In2.Cu")
		(net 219)
	)
	(segment
		(start 84.273962 151.696972)
		(end 84.273962 154.084736)
		(width 0.127)
		(layer "In2.Cu")
		(net 219)
	)
	(segment
		(start 108.284602 165.9555)
		(end 118.77949 165.9555)
		(width 0.127)
		(layer "In2.Cu")
		(net 219)
	)
	(segment
		(start 99.573602 157.2445)
		(end 108.284602 165.9555)
		(width 0.127)
		(layer "In2.Cu")
		(net 219)
	)
	(segment
		(start 143.217962 140.8415)
		(end 142.367962 141.6915)
		(width 0.127)
		(layer "In3.Cu")
		(net 219)
	)
	(segment
		(start 126.813802 156.2285)
		(end 123.780519 159.261783)
		(width 0.127)
		(layer "In3.Cu")
		(net 219)
	)
	(segment
		(start 142.367962 141.6915)
		(end 142.367962 142.535116)
		(width 0.127)
		(layer "In3.Cu")
		(net 219)
	)
	(segment
		(start 142.367962 142.535116)
		(end 136.840962 148.062116)
		(width 0.127)
		(layer "In3.Cu")
		(net 219)
	)
	(segment
		(start 136.840962 153.429882)
		(end 134.042344 156.2285)
		(width 0.127)
		(layer "In3.Cu")
		(net 219)
	)
	(segment
		(start 134.042344 156.2285)
		(end 126.813802 156.2285)
		(width 0.127)
		(layer "In3.Cu")
		(net 219)
	)
	(segment
		(start 123.780519 159.261783)
		(end 123.780519 159.397849)
		(width 0.127)
		(layer "In3.Cu")
		(net 219)
	)
	(segment
		(start 136.840962 148.062116)
		(end 136.840962 153.429882)
		(width 0.127)
		(layer "In3.Cu")
		(net 219)
	)
	(segment
		(start 133.806462 142.4665)
		(end 134.646995 141.625967)
		(width 0.127)
		(layer "F.Cu")
		(net 220)
	)
	(segment
		(start 139.592962 135.1915)
		(end 139.592962 134.666498)
		(width 0.15)
		(layer "F.Cu")
		(net 220)
	)
	(segment
		(start 139.592962 134.666498)
		(end 139.517963 134.591499)
		(width 0.15)
		(layer "F.Cu")
		(net 220)
	)
	(segment
		(start 139.592962 135.979)
		(end 139.592962 135.204)
		(width 0.127)
		(layer "F.Cu")
		(net 220)
	)
	(segment
		(start 138.194962 140.5915)
		(end 137.319962 141.4665)
		(width 0.127)
		(layer "F.Cu")
		(net 220)
	)
	(segment
		(start 139.592963 134.666499)
		(end 139.517963 134.591499)
		(width 0.127)
		(layer "F.Cu")
		(net 220)
	)
	(segment
		(start 79.192962 149.9165)
		(end 78.991462 150.118)
		(width 0.127)
		(layer "F.Cu")
		(net 220)
	)
	(segment
		(start 139.037462 137.049)
		(end 138.194962 137.8915)
		(width 0.127)
		(layer "F.Cu")
		(net 220)
	)
	(segment
		(start 78.991462 150.118)
		(end 78.473961 150.118)
		(width 0.127)
		(layer "F.Cu")
		(net 220)
	)
	(segment
		(start 137.319962 141.4665)
		(end 136.442962 141.4665)
		(width 0.127)
		(layer "F.Cu")
		(net 220)
	)
	(segment
		(start 139.592962 135.9665)
		(end 139.592962 136.8165)
		(width 0.127)
		(layer "F.Cu")
		(net 220)
	)
	(segment
		(start 139.360462 137.049)
		(end 139.037462 137.049)
		(width 0.127)
		(layer "F.Cu")
		(net 220)
	)
	(segment
		(start 138.194962 137.8915)
		(end 138.194962 140.5915)
		(width 0.127)
		(layer "F.Cu")
		(net 220)
	)
	(segment
		(start 139.592962 136.8165)
		(end 139.360462 137.049)
		(width 0.127)
		(layer "F.Cu")
		(net 220)
	)
	(segment
		(start 134.646995 141.625967)
		(end 134.927429 141.625967)
		(width 0.127)
		(layer "F.Cu")
		(net 220)
	)
	(via
		(at 134.927429 141.625967)
		(size 0.45)
		(drill 0.1)
		(layers "F.Cu" "B.Cu")
		(net 220)
	)
	(via
		(at 133.806462 142.4665)
		(size 0.45)
		(drill 0.1)
		(layers "F.Cu" "B.Cu")
		(net 220)
	)
	(via
		(at 139.517963 134.591499)
		(size 0.45)
		(drill 0.1)
		(layers "F.Cu" "B.Cu")
		(net 220)
	)
	(via
		(at 79.192962 149.9165)
		(size 0.45)
		(drill 0.1)
		(layers "F.Cu" "B.Cu")
		(net 220)
	)
	(segment
		(start 82.56399 161.0245)
		(end 98.007872 161.0245)
		(width 0.127)
		(layer "In2.Cu")
		(net 220)
	)
	(segment
		(start 98.007872 161.0245)
		(end 106.718872 169.7355)
		(width 0.127)
		(layer "In2.Cu")
		(net 220)
	)
	(segment
		(start 133.806462 143.412779)
		(end 133.806462 142.4665)
		(width 0.127)
		(layer "In2.Cu")
		(net 220)
	)
	(segment
		(start 134.927429 141.357033)
		(end 139.548962 136.7355)
		(width 0.127)
		(layer "In2.Cu")
		(net 220)
	)
	(segment
		(start 79.192962 149.9165)
		(end 79.59187 150.315408)
		(width 0.127)
		(layer "In2.Cu")
		(net 220)
	)
	(segment
		(start 81.038962 159.499472)
		(end 82.56399 161.0245)
		(width 0.127)
		(layer "In2.Cu")
		(net 220)
	)
	(segment
		(start 81.038962 157.4125)
		(end 81.038962 159.499472)
		(width 0.127)
		(layer "In2.Cu")
		(net 220)
	)
	(segment
		(start 131.619962 152.240916)
		(end 131.619962 144.576736)
		(width 0.127)
		(layer "In2.Cu")
		(net 220)
	)
	(segment
		(start 79.59187 151.182814)
		(end 79.190962 151.583722)
		(width 0.127)
		(layer "In2.Cu")
		(net 220)
	)
	(segment
		(start 129.926962 153.933916)
		(end 131.619962 152.240916)
		(width 0.127)
		(layer "In2.Cu")
		(net 220)
	)
	(segment
		(start 80.142962 156.5165)
		(end 81.038962 157.4125)
		(width 0.127)
		(layer "In2.Cu")
		(net 220)
	)
	(segment
		(start 134.927429 141.625967)
		(end 134.927429 141.357033)
		(width 0.127)
		(layer "In2.Cu")
		(net 220)
	)
	(segment
		(start 106.718872 169.7355)
		(end 127.558996 169.7355)
		(width 0.127)
		(layer "In2.Cu")
		(net 220)
	)
	(segment
		(start 127.558996 169.7355)
		(end 129.926962 167.367534)
		(width 0.127)
		(layer "In2.Cu")
		(net 220)
	)
	(segment
		(start 129.926962 167.367534)
		(end 129.926962 153.933916)
		(width 0.127)
		(layer "In2.Cu")
		(net 220)
	)
	(segment
		(start 79.190962 151.583722)
		(end 79.190962 155.370882)
		(width 0.127)
		(layer "In2.Cu")
		(net 220)
	)
	(segment
		(start 80.142962 156.322882)
		(end 80.142962 156.5165)
		(width 0.127)
		(layer "In2.Cu")
		(net 220)
	)
	(segment
		(start 79.190962 155.370882)
		(end 80.142962 156.322882)
		(width 0.127)
		(layer "In2.Cu")
		(net 220)
	)
	(segment
		(start 131.619962 144.576736)
		(end 132.234198 143.9625)
		(width 0.127)
		(layer "In2.Cu")
		(net 220)
	)
	(segment
		(start 133.256741 143.9625)
		(end 133.806462 143.412779)
		(width 0.127)
		(layer "In2.Cu")
		(net 220)
	)
	(segment
		(start 132.234198 143.9625)
		(end 133.256741 143.9625)
		(width 0.127)
		(layer "In2.Cu")
		(net 220)
	)
	(segment
		(start 139.548962 136.7355)
		(end 139.548962 134.622498)
		(width 0.127)
		(layer "In2.Cu")
		(net 220)
	)
	(segment
		(start 139.548962 134.622498)
		(end 139.517963 134.591499)
		(width 0.127)
		(layer "In2.Cu")
		(net 220)
	)
	(segment
		(start 79.59187 150.315408)
		(end 79.59187 151.182814)
		(width 0.127)
		(layer "In2.Cu")
		(net 220)
	)
	(segment
		(start 81.13544 150.118)
		(end 81.554961 150.118)
		(width 0.127)
		(layer "F.Cu")
		(net 221)
	)
	(segment
		(start 80.801472 149.784032)
		(end 81.13544 150.118)
		(width 0.127)
		(layer "F.Cu")
		(net 221)
	)
	(segment
		(start 141.616962 141.9175)
		(end 141.067962 142.4665)
		(width 0.127)
		(layer "F.Cu")
		(net 221)
	)
	(segment
		(start 142.680462 141.9165)
		(end 143.167962 141.9165)
		(width 0.127)
		(layer "F.Cu")
		(net 221)
	)
	(segment
		(start 89.786571 154.572891)
		(end 89.992962 154.3665)
		(width 0.127)
		(layer "F.Cu")
		(net 221)
	)
	(segment
		(start 141.905462 141.9175)
		(end 142.679462 141.9175)
		(width 0.127)
		(layer "F.Cu")
		(net 221)
	)
	(segment
		(start 143.092962 141.9165)
		(end 143.217961 142.041499)
		(width 0.127)
		(layer "F.Cu")
		(net 221)
	)
	(segment
		(start 141.905462 141.9175)
		(end 141.616962 141.9175)
		(width 0.127)
		(layer "F.Cu")
		(net 221)
	)
	(segment
		(start 89.786571 155.0365)
		(end 89.786571 154.572891)
		(width 0.127)
		(layer "F.Cu")
		(net 221)
	)
	(segment
		(start 89.992962 154.3665)
		(end 89.992962 152.9695)
		(width 0.127)
		(layer "F.Cu")
		(net 221)
	)
	(via
		(at 124.194019 160.1165)
		(size 0.45)
		(drill 0.1)
		(layers "F.Cu" "B.Cu")
		(free yes)
		(net 221)
	)
	(via
		(at 143.217961 142.041499)
		(size 0.45)
		(drill 0.1)
		(layers "F.Cu" "B.Cu")
		(net 221)
	)
	(via
		(at 89.786571 155.0365)
		(size 0.45)
		(drill 0.1)
		(layers "F.Cu" "B.Cu")
		(net 221)
	)
	(via
		(at 80.801472 149.784032)
		(size 0.45)
		(drill 0.1)
		(layers "F.Cu" "B.Cu")
		(net 221)
	)
	(segment
		(start 108.18022 166.2075)
		(end 118.883872 166.2075)
		(width 0.127)
		(layer "In2.Cu")
		(net 221)
	)
	(segment
		(start 82.400608 150.18)
		(end 84.021962 151.801354)
		(width 0.127)
		(layer "In2.Cu")
		(net 221)
	)
	(segment
		(start 99.46922 157.4965)
		(end 108.18022 166.2075)
		(width 0.127)
		(layer "In2.Cu")
		(net 221)
	)
	(segment
		(start 80.801472 149.784032)
		(end 81.19744 150.18)
		(width 0.127)
		(layer "In2.Cu")
		(net 221)
	)
	(segment
		(start 84.021962 154.189118)
		(end 87.329344 157.4965)
		(width 0.127)
		(layer "In2.Cu")
		(net 221)
	)
	(segment
		(start 84.021962 151.801354)
		(end 84.021962 154.189118)
		(width 0.127)
		(layer "In2.Cu")
		(net 221)
	)
	(segment
		(start 87.329344 157.4965)
		(end 99.46922 157.4965)
		(width 0.127)
		(layer "In2.Cu")
		(net 221)
	)
	(segment
		(start 124.032519 161.058853)
		(end 124.032519 160.131009)
		(width 0.127)
		(layer "In2.Cu")
		(net 221)
	)
	(segment
		(start 81.19744 150.18)
		(end 82.400608 150.18)
		(width 0.127)
		(layer "In2.Cu")
		(net 221)
	)
	(segment
		(start 118.883872 166.2075)
		(end 124.032519 161.058853)
		(width 0.127)
		(layer "In2.Cu")
		(net 221)
	)
	(segment
		(start 124.032519 160.131009)
		(end 124.194019 159.969509)
		(width 0.127)
		(layer "In2.Cu")
		(net 221)
	)
	(segment
		(start 81.535931 150.518491)
		(end 83.182717 150.518491)
		(width 0.127)
		(layer "In3.Cu")
		(net 221)
	)
	(segment
		(start 137.092962 153.534264)
		(end 134.146726 156.4805)
		(width 0.127)
		(layer "In3.Cu")
		(net 221)
	)
	(segment
		(start 88.127462 151.501)
		(end 89.792929 153.166467)
		(width 0.127)
		(layer "In3.Cu")
		(net 221)
	)
	(segment
		(start 80.801472 149.784032)
		(end 81.535931 150.518491)
		(width 0.127)
		(layer "In3.Cu")
		(net 221)
	)
	(segment
		(start 89.792929 155.030142)
		(end 89.786571 155.0365)
		(width 0.127)
		(layer "In3.Cu")
		(net 221)
	)
	(segment
		(start 89.792929 153.166467)
		(end 89.792929 155.030142)
		(width 0.127)
		(layer "In3.Cu")
		(net 221)
	)
	(segment
		(start 134.146726 156.4805)
		(end 126.918184 156.4805)
		(width 0.127)
		(layer "In3.Cu")
		(net 221)
	)
	(segment
		(start 83.182717 150.518491)
		(end 84.165226 151.501)
		(width 0.127)
		(layer "In3.Cu")
		(net 221)
	)
	(segment
		(start 143.217961 142.041499)
		(end 137.092962 148.166498)
		(width 0.127)
		(layer "In3.Cu")
		(net 221)
	)
	(segment
		(start 84.165226 151.501)
		(end 88.127462 151.501)
		(width 0.127)
		(layer "In3.Cu")
		(net 221)
	)
	(segment
		(start 124.194019 159.204665)
		(end 124.194019 160.1165)
		(width 0.127)
		(layer "In3.Cu")
		(net 221)
	)
	(segment
		(start 137.092962 148.166498)
		(end 137.092962 153.534264)
		(width 0.127)
		(layer "In3.Cu")
		(net 221)
	)
	(segment
		(start 126.918184 156.4805)
		(end 124.194019 159.204665)
		(width 0.127)
		(layer "In3.Cu")
		(net 221)
	)
	(segment
		(start 140.593962 135.9665)
		(end 140.593962 136.7655)
		(width 0.127)
		(layer "F.Cu")
		(net 222)
	)
	(segment
		(start 79.17837 150.5165)
		(end 79.17787 150.517)
		(width 0.127)
		(layer "F.Cu")
		(net 222)
	)
	(segment
		(start 137.319962 141.9665)
		(end 136.442962 141.9665)
		(width 0.127)
		(layer "F.Cu")
		(net 222)
	)
	(segment
		(start 138.446962 138.0165)
		(end 138.446962 140.8395)
		(width 0.127)
		(layer "F.Cu")
		(net 222)
	)
	(segment
		(start 140.592962 135.204)
		(end 140.592962 134.7165)
		(width 0.127)
		(layer "F.Cu")
		(net 222)
	)
	(segment
		(start 139.162462 137.301)
		(end 138.446962 138.0165)
		(width 0.127)
		(layer "F.Cu")
		(net 222)
	)
	(segment
		(start 140.593962 135.979)
		(end 140.593962 135.205)
		(width 0.127)
		(layer "F.Cu")
		(net 222)
	)
	(segment
		(start 140.592963 134.716499)
		(end 140.717962 134.5915)
		(width 0.127)
		(layer "F.Cu")
		(net 222)
	)
	(segment
		(start 79.17787 150.517)
		(end 78.473961 150.517)
		(width 0.127)
		(layer "F.Cu")
		(net 222)
	)
	(segment
		(start 140.058462 137.301)
		(end 139.162462 137.301)
		(width 0.127)
		(layer "F.Cu")
		(net 222)
	)
	(segment
		(start 140.593962 136.7655)
		(end 140.058462 137.301)
		(width 0.127)
		(layer "F.Cu")
		(net 222)
	)
	(segment
		(start 138.446962 140.8395)
		(end 137.319962 141.9665)
		(width 0.127)
		(layer "F.Cu")
		(net 222)
	)
	(via
		(at 79.17837 150.5165)
		(size 0.45)
		(drill 0.1)
		(layers "F.Cu" "B.Cu")
		(net 222)
	)
	(via
		(at 140.717962 134.5915)
		(size 0.45)
		(drill 0.1)
		(layers "F.Cu" "B.Cu")
		(net 222)
	)
	(segment
		(start 79.17837 150.5165)
		(end 78.938962 150.755908)
		(width 0.127)
		(layer "In2.Cu")
		(net 222)
	)
	(segment
		(start 130.178962 167.471916)
		(end 130.178962 154.038298)
		(width 0.127)
		(layer "In2.Cu")
		(net 222)
	)
	(segment
		(start 130.178962 154.038298)
		(end 131.871962 152.345298)
		(width 0.127)
		(layer "In2.Cu")
		(net 222)
	)
	(segment
		(start 131.871962 152.345298)
		(end 131.871962 144.681118)
		(width 0.127)
		(layer "In2.Cu")
		(net 222)
	)
	(segment
		(start 138.492962 134.4165)
		(end 138.756462 134.153)
		(width 0.127)
		(layer "In2.Cu")
		(net 222)
	)
	(segment
		(start 131.871962 144.681118)
		(end 132.33858 144.2145)
		(width 0.127)
		(layer "In2.Cu")
		(net 222)
	)
	(segment
		(start 134.219962 141.351736)
		(end 138.492962 137.078736)
		(width 0.127)
		(layer "In2.Cu")
		(net 222)
	)
	(segment
		(start 78.938962 157.755854)
		(end 82.459608 161.2765)
		(width 0.127)
		(layer "In2.Cu")
		(net 222)
	)
	(segment
		(start 106.61449 169.9875)
		(end 127.663378 169.9875)
		(width 0.127)
		(layer "In2.Cu")
		(net 222)
	)
	(segment
		(start 138.492962 137.078736)
		(end 138.492962 134.4165)
		(width 0.127)
		(layer "In2.Cu")
		(net 222)
	)
	(segment
		(start 133.369962 144.2145)
		(end 134.219962 143.3645)
		(width 0.127)
		(layer "In2.Cu")
		(net 222)
	)
	(segment
		(start 78.938962 150.755908)
		(end 78.938962 157.755854)
		(width 0.127)
		(layer "In2.Cu")
		(net 222)
	)
	(segment
		(start 132.33858 144.2145)
		(end 133.369962 144.2145)
		(width 0.127)
		(layer "In2.Cu")
		(net 222)
	)
	(segment
		(start 134.219962 143.3645)
		(end 134.219962 141.351736)
		(width 0.127)
		(layer "In2.Cu")
		(net 222)
	)
	(segment
		(start 82.459608 161.2765)
		(end 97.90349 161.2765)
		(width 0.127)
		(layer "In2.Cu")
		(net 222)
	)
	(segment
		(start 127.663378 169.9875)
		(end 130.178962 167.471916)
		(width 0.127)
		(layer "In2.Cu")
		(net 222)
	)
	(segment
		(start 140.279462 134.153)
		(end 140.717962 134.5915)
		(width 0.127)
		(layer "In2.Cu")
		(net 222)
	)
	(segment
		(start 97.90349 161.2765)
		(end 106.61449 169.9875)
		(width 0.127)
		(layer "In2.Cu")
		(net 222)
	)
	(segment
		(start 138.756462 134.153)
		(end 140.279462 134.153)
		(width 0.127)
		(layer "In2.Cu")
		(net 222)
	)
	(segment
		(start 141.905462 142.4165)
		(end 142.680462 142.4165)
		(width 0.127)
		(layer "F.Cu")
		(net 223)
	)
	(segment
		(start 80.840031 150.517)
		(end 81.554961 150.517)
		(width 0.127)
		(layer "F.Cu")
		(net 223)
	)
	(segment
		(start 80.680022 150.356991)
		(end 80.840031 150.517)
		(width 0.127)
		(layer "F.Cu")
		(net 223)
	)
	(segment
		(start 141.617962 142.4165)
		(end 141.067962 142.9665)
		(width 0.127)
		(layer "F.Cu")
		(net 223)
	)
	(segment
		(start 141.905462 142.4165)
		(end 141.617962 142.4165)
		(width 0.127)
		(layer "F.Cu")
		(net 223)
	)
	(segment
		(start 142.992962 142.4165)
		(end 143.217962 142.6415)
		(width 0.127)
		(layer "F.Cu")
		(net 223)
	)
	(segment
		(start 142.680462 142.4165)
		(end 142.992962 142.4165)
		(width 0.127)
		(layer "F.Cu")
		(net 223)
	)
	(via
		(at 124.614462 159.369)
		(size 0.45)
		(drill 0.1)
		(layers "F.Cu" "B.Cu")
		(free yes)
		(net 223)
	)
	(via
		(at 80.680022 150.356991)
		(size 0.45)
		(drill 0.1)
		(layers "F.Cu" "B.Cu")
		(net 223)
	)
	(via
		(at 143.217962 142.6415)
		(size 0.45)
		(drill 0.1)
		(layers "F.Cu" "B.Cu")
		(net 223)
	)
	(segment
		(start 99.364838 157.7485)
		(end 108.075838 166.4595)
		(width 0.127)
		(layer "In2.Cu")
		(net 223)
	)
	(segment
		(start 108.075838 166.4595)
		(end 118.988254 166.4595)
		(width 0.127)
		(layer "In2.Cu")
		(net 223)
	)
	(segment
		(start 124.614462 160.833292)
		(end 124.614462 159.369)
		(width 0.127)
		(layer "In2.Cu")
		(net 223)
	)
	(segment
		(start 87.224962 157.7485)
		(end 99.364838 157.7485)
		(width 0.127)
		(layer "In2.Cu")
		(net 223)
	)
	(segment
		(start 83.769962 154.2935)
		(end 87.224962 157.7485)
		(width 0.127)
		(layer "In2.Cu")
		(net 223)
	)
	(segment
		(start 82.296226 150.432)
		(end 83.769962 151.905736)
		(width 0.127)
		(layer "In2.Cu")
		(net 223)
	)
	(segment
		(start 80.755031 150.432)
		(end 82.296226 150.432)
		(width 0.127)
		(layer "In2.Cu")
		(net 223)
	)
	(segment
		(start 80.680022 150.356991)
		(end 80.755031 150.432)
		(width 0.127)
		(layer "In2.Cu")
		(net 223)
	)
	(segment
		(start 118.988254 166.4595)
		(end 124.614462 160.833292)
		(width 0.127)
		(layer "In2.Cu")
		(net 223)
	)
	(segment
		(start 83.769962 151.905736)
		(end 83.769962 154.2935)
		(width 0.127)
		(layer "In2.Cu")
		(net 223)
	)
	(segment
		(start 124.614462 159.26234)
		(end 124.614462 159.369)
		(width 0.127)
		(layer "In3.Cu")
		(net 223)
	)
	(segment
		(start 143.039038 142.6415)
		(end 137.981462 147.699076)
		(width 0.127)
		(layer "In3.Cu")
		(net 223)
	)
	(segment
		(start 137.981462 147.699076)
		(end 137.981462 154.680034)
		(width 0.127)
		(layer "In3.Cu")
		(net 223)
	)
	(segment
		(start 137.981462 154.680034)
		(end 135.928996 156.7325)
		(width 0.127)
		(layer "In3.Cu")
		(net 223)
	)
	(segment
		(start 135.928996 156.7325)
		(end 127.144302 156.7325)
		(width 0.127)
		(layer "In3.Cu")
		(net 223)
	)
	(segment
		(start 143.217962 142.6415)
		(end 143.039038 142.6415)
		(width 0.127)
		(layer "In3.Cu")
		(net 223)
	)
	(segment
		(start 127.144302 156.7325)
		(end 124.614462 159.26234)
		(width 0.127)
		(layer "In3.Cu")
		(net 223)
	)
	(segment
		(start 141.092962 136.622882)
		(end 140.162844 137.553)
		(width 0.127)
		(layer "F.Cu")
		(net 224)
	)
	(segment
		(start 141.092963 134.816499)
		(end 141.317963 134.591499)
		(width 0.127)
		(layer "F.Cu")
		(net 224)
	)
	(segment
		(start 141.092962 134.8165)
		(end 141.317963 134.591499)
		(width 0.15)
		(layer "F.Cu")
		(net 224)
	)
	(segment
		(start 79.644843 150.93)
		(end 78.484961 150.93)
		(width 0.127)
		(layer "F.Cu")
		(net 224)
	)
	(segment
		(start 80.114402 150.460441)
		(end 79.644843 150.93)
		(width 0.127)
		(layer "F.Cu")
		(net 224)
	)
	(segment
		(start 138.698962 141.7105)
		(end 137.442962 142.9665)
		(width 0.127)
		(layer "F.Cu")
		(net 224)
	)
	(segment
		(start 89.592962 154.356834)
		(end 89.592962 152.9695)
		(width 0.127)
		(layer "F.Cu")
		(net 224)
	)
	(segment
		(start 139.317962 137.553)
		(end 138.698962 138.172)
		(width 0.127)
		(layer "F.Cu")
		(net 224)
	)
	(segment
		(start 137.442962 142.9665)
		(end 136.442962 142.9665)
		(width 0.127)
		(layer "F.Cu")
		(net 224)
	)
	(segment
		(start 138.698962 138.172)
		(end 138.698962 141.7105)
		(width 0.127)
		(layer "F.Cu")
		(net 224)
	)
	(segment
		(start 141.092962 135.979)
		(end 141.092962 135.204)
		(width 0.127)
		(layer "F.Cu")
		(net 224)
	)
	(segment
		(start 141.092962 135.9665)
		(end 141.092962 136.622882)
		(width 0.127)
		(layer "F.Cu")
		(net 224)
	)
	(segment
		(start 141.092962 135.1915)
		(end 141.092962 134.8165)
		(width 0.15)
		(layer "F.Cu")
		(net 224)
	)
	(segment
		(start 89.275307 154.674489)
		(end 89.592962 154.356834)
		(width 0.127)
		(layer "F.Cu")
		(net 224)
	)
	(segment
		(start 140.162844 137.553)
		(end 139.317962 137.553)
		(width 0.127)
		(layer "F.Cu")
		(net 224)
	)
	(via
		(at 89.275307 154.674489)
		(size 0.45)
		(drill 0.1)
		(layers "F.Cu" "B.Cu")
		(net 224)
	)
	(via
		(at 80.114402 150.460441)
		(size 0.45)
		(drill 0.1)
		(layers "F.Cu" "B.Cu")
		(net 224)
	)
	(via
		(at 141.317963 134.591499)
		(size 0.45)
		(drill 0.1)
		(layers "F.Cu" "B.Cu")
		(net 224)
	)
	(segment
		(start 89.275307 155.136081)
		(end 90.375726 156.2365)
		(width 0.127)
		(layer "In2.Cu")
		(net 224)
	)
	(segment
		(start 89.275307 154.674489)
		(end 89.275307 155.136081)
		(width 0.127)
		(layer "In2.Cu")
		(net 224)
	)
	(segment
		(start 138.65208 133.901)
		(end 140.627464 133.901)
		(width 0.127)
		(layer "In2.Cu")
		(net 224)
	)
	(segment
		(start 122.407962 160.9015)
		(end 122.407962 159.2665)
		(width 0.127)
		(layer "In2.Cu")
		(net 224)
	)
	(segment
		(start 130.137962 145.077354)
		(end 138.240962 136.974354)
		(width 0.127)
		(layer "In2.Cu")
		(net 224)
	)
	(segment
		(start 130.137962 151.5365)
		(end 130.137962 145.077354)
		(width 0.127)
		(layer "In2.Cu")
		(net 224)
	)
	(segment
		(start 118.361962 164.9475)
		(end 122.407962 160.9015)
		(width 0.127)
		(layer "In2.Cu")
		(net 224)
	)
	(segment
		(start 100.012434 156.2365)
		(end 108.723434 164.9475)
		(width 0.127)
		(layer "In2.Cu")
		(net 224)
	)
	(segment
		(start 90.375726 156.2365)
		(end 100.012434 156.2365)
		(width 0.127)
		(layer "In2.Cu")
		(net 224)
	)
	(segment
		(start 138.240962 136.974354)
		(end 138.240962 134.312118)
		(width 0.127)
		(layer "In2.Cu")
		(net 224)
	)
	(segment
		(start 138.240962 134.312118)
		(end 138.65208 133.901)
		(width 0.127)
		(layer "In2.Cu")
		(net 224)
	)
	(segment
		(start 108.723434 164.9475)
		(end 118.361962 164.9475)
		(width 0.127)
		(layer "In2.Cu")
		(net 224)
	)
	(segment
		(start 140.627464 133.901)
		(end 141.317963 134.591499)
		(width 0.127)
		(layer "In2.Cu")
		(net 224)
	)
	(segment
		(start 122.407962 159.2665)
		(end 130.137962 151.5365)
		(width 0.127)
		(layer "In2.Cu")
		(net 224)
	)
	(segment
		(start 83.078335 150.770491)
		(end 84.060844 151.753)
		(width 0.127)
		(layer "In3.Cu")
		(net 224)
	)
	(segment
		(start 80.398127 150.770491)
		(end 83.078335 150.770491)
		(width 0.127)
		(layer "In3.Cu")
		(net 224)
	)
	(segment
		(start 89.540929 153.439467)
		(end 89.540929 154.468533)
		(width 0.127)
		(layer "In3.Cu")
		(net 224)
	)
	(segment
		(start 89.540929 154.468533)
		(end 89.334973 154.674489)
		(width 0.127)
		(layer "In3.Cu")
		(net 224)
	)
	(segment
		(start 80.114402 150.486766)
		(end 80.398127 150.770491)
		(width 0.127)
		(layer "In3.Cu")
		(net 224)
	)
	(segment
		(start 84.060844 151.753)
		(end 87.854462 151.753)
		(width 0.127)
		(layer "In3.Cu")
		(net 224)
	)
	(segment
		(start 89.334973 154.674489)
		(end 89.275307 154.674489)
		(width 0.127)
		(layer "In3.Cu")
		(net 224)
	)
	(segment
		(start 87.854462 151.753)
		(end 89.540929 153.439467)
		(width 0.127)
		(layer "In3.Cu")
		(net 224)
	)
	(segment
		(start 80.114402 150.460441)
		(end 80.114402 150.486766)
		(width 0.127)
		(layer "In3.Cu")
		(net 224)
	)
	(segment
		(start 82.034461 151.2665)
		(end 81.982961 151.318)
		(width 0.127)
		(layer "F.Cu")
		(net 225)
	)
	(segment
		(start 141.905462 143.3915)
		(end 142.680462 143.3915)
		(width 0.127)
		(layer "F.Cu")
		(net 225)
	)
	(segment
		(start 140.393962 143.4665)
		(end 141.367962 143.4665)
		(width 0.127)
		(layer "F.Cu")
		(net 225)
	)
	(segment
		(start 84.964962 153.5385)
		(end 84.964962 152.8995)
		(width 0.127)
		(layer "F.Cu")
		(net 225)
	)
	(segment
		(start 141.367962 143.4665)
		(end 141.442962 143.3915)
		(width 0.127)
		(layer "F.Cu")
		(net 225)
	)
	(segment
		(start 81.982961 151.318)
		(end 81.554961 151.318)
		(width 0.127)
		(layer "F.Cu")
		(net 225)
	)
	(segment
		(start 143.067962 143.3915)
		(end 143.217962 143.2415)
		(width 0.127)
		(layer "F.Cu")
		(net 225)
	)
	(segment
		(start 84.954462 153.549)
		(end 84.964962 153.5385)
		(width 0.127)
		(layer "F.Cu")
		(net 225)
	)
	(segment
		(start 141.905462 143.3915)
		(end 141.442962 143.3915)
		(width 0.127)
		(layer "F.Cu")
		(net 225)
	)
	(segment
		(start 82.267962 151.2665)
		(end 82.034461 151.2665)
		(width 0.127)
		(layer "F.Cu")
		(net 225)
	)
	(segment
		(start 142.680462 143.3915)
		(end 143.067962 143.3915)
		(width 0.127)
		(layer "F.Cu")
		(net 225)
	)
	(via
		(at 84.954462 153.549)
		(size 0.45)
		(drill 0.1)
		(layers "F.Cu" "B.Cu")
		(net 225)
	)
	(via
		(at 82.267962 151.2665)
		(size 0.45)
		(drill 0.1)
		(layers "F.Cu" "B.Cu")
		(net 225)
	)
	(via
		(at 125.027962 160.134502)
		(size 0.45)
		(drill 0.1)
		(layers "F.Cu" "B.Cu")
		(free yes)
		(net 225)
	)
	(via
		(at 143.217962 143.2415)
		(size 0.45)
		(drill 0.1)
		(layers "F.Cu" "B.Cu")
		(net 225)
	)
	(segment
		(start 82.767962 151.2665)
		(end 83.517962 152.0165)
		(width 0.127)
		(layer "In2.Cu")
		(net 225)
	)
	(segment
		(start 119.092636 166.7115)
		(end 125.027962 160.776174)
		(width 0.127)
		(layer "In2.Cu")
		(net 225)
	)
	(segment
		(start 87.12058 158.0005)
		(end 99.260456 158.0005)
		(width 0.127)
		(layer "In2.Cu")
		(net 225)
	)
	(segment
		(start 107.971456 166.7115)
		(end 119.092636 166.7115)
		(width 0.127)
		(layer "In2.Cu")
		(net 225)
	)
	(segment
		(start 82.267962 151.2665)
		(end 82.767962 151.2665)
		(width 0.127)
		(layer "In2.Cu")
		(net 225)
	)
	(segment
		(start 83.517962 154.403736)
		(end 86.556726 157.4425)
		(width 0.127)
		(layer "In2.Cu")
		(net 225)
	)
	(segment
		(start 125.027962 160.776174)
		(end 125.027962 159.994502)
		(width 0.127)
		(layer "In2.Cu")
		(net 225)
	)
	(segment
		(start 83.517962 152.0165)
		(end 83.517962 154.403736)
		(width 0.127)
		(layer "In2.Cu")
		(net 225)
	)
	(segment
		(start 99.260456 158.0005)
		(end 107.971456 166.7115)
		(width 0.127)
		(layer "In2.Cu")
		(net 225)
	)
	(segment
		(start 86.56258 157.4425)
		(end 87.12058 158.0005)
		(width 0.127)
		(layer "In2.Cu")
		(net 225)
	)
	(segment
		(start 86.556726 157.4425)
		(end 86.56258 157.4425)
		(width 0.127)
		(layer "In2.Cu")
		(net 225)
	)
	(segment
		(start 125.027962 159.205222)
		(end 125.027962 160.134502)
		(width 0.127)
		(layer "In3.Cu")
		(net 225)
	)
	(segment
		(start 127.248684 156.9845)
		(end 125.027962 159.205222)
		(width 0.127)
		(layer "In3.Cu")
		(net 225)
	)
	(segment
		(start 138.233462 147.803458)
		(end 138.233462 154.784416)
		(width 0.127)
		(layer "In3.Cu")
		(net 225)
	)
	(segment
		(start 136.033378 156.9845)
		(end 127.248684 156.9845)
		(width 0.127)
		(layer "In3.Cu")
		(net 225)
	)
	(segment
		(start 138.233462 154.784416)
		(end 136.033378 156.9845)
		(width 0.127)
		(layer "In3.Cu")
		(net 225)
	)
	(segment
		(start 84.954462 153.549)
		(end 84.954462 153.003)
		(width 0.127)
		(layer "In3.Cu")
		(net 225)
	)
	(segment
		(start 142.79542 143.2415)
		(end 138.233462 147.803458)
		(width 0.127)
		(layer "In3.Cu")
		(net 225)
	)
	(segment
		(start 84.954462 153.003)
		(end 83.217962 151.2665)
		(width 0.127)
		(layer "In3.Cu")
		(net 225)
	)
	(segment
		(start 143.217962 143.2415)
		(end 142.79542 143.2415)
		(width 0.127)
		(layer "In3.Cu")
		(net 225)
	)
	(segment
		(start 83.217962 151.2665)
		(end 82.267962 151.2665)
		(width 0.127)
		(layer "In3.Cu")
		(net 225)
	)
	(segment
		(start 135.221806 144.6785)
		(end 135.433806 144.4665)
		(width 0.127)
		(layer "F.Cu")
		(net 226)
	)
	(segment
		(start 77.264551 152.116)
		(end 78.473961 152.116)
		(width 0.127)
		(layer "F.Cu")
		(net 226)
	)
	(segment
		(start 132.694672 144.89979)
		(end 132.914962 144.6795)
		(width 0.127)
		(layer "F.Cu")
		(net 226)
	)
	(segment
		(start 134.467462 144.6785)
		(end 135.221806 144.6785)
		(width 0.127)
		(layer "F.Cu")
		(net 226)
	)
	(segment
		(start 133.692962 144.6915)
		(end 134.467962 144.6915)
		(width 0.127)
		(layer "F.Cu")
		(net 226)
	)
	(segment
		(start 132.694672 144.904141)
		(end 132.694672 144.89979)
		(width 0.127)
		(layer "F.Cu")
		(net 226)
	)
	(segment
		(start 132.914962 144.6795)
		(end 133.692462 144.6795)
		(width 0.127)
		(layer "F.Cu")
		(net 226)
	)
	(segment
		(start 135.433806 144.4665)
		(end 136.442962 144.4665)
		(width 0.127)
		(layer "F.Cu")
		(net 226)
	)
	(segment
		(start 77.254297 152.126254)
		(end 77.264551 152.116)
		(width 0.127)
		(layer "F.Cu")
		(net 226)
	)
	(via
		(at 77.254297 152.126254)
		(size 0.45)
		(drill 0.1)
		(layers "F.Cu" "B.Cu")
		(net 226)
	)
	(via
		(at 132.694672 144.904141)
		(size 0.45)
		(drill 0.1)
		(layers "F.Cu" "B.Cu")
		(net 226)
	)
	(segment
		(start 106.405726 170.4915)
		(end 97.694726 161.7805)
		(width 0.127)
		(layer "In2.Cu")
		(net 226)
	)
	(segment
		(start 130.682962 154.250681)
		(end 130.682962 167.68068)
		(width 0.127)
		(layer "In2.Cu")
		(net 226)
	)
	(segment
		(start 82.250844 161.7805)
		(end 78.417962 157.947618)
		(width 0.127)
		(layer "In2.Cu")
		(net 226)
	)
	(segment
		(start 132.375962 152.554062)
		(end 131.564962 153.365063)
		(width 0.127)
		(layer "In2.Cu")
		(net 226)
	)
	(segment
		(start 131.564962 153.365063)
		(end 131.564962 153.368681)
		(width 0.127)
		(layer "In2.Cu")
		(net 226)
	)
	(segment
		(start 78.417962 152.78732)
		(end 77.756897 152.126254)
		(width 0.127)
		(layer "In2.Cu")
		(net 226)
	)
	(segment
		(start 130.682962 167.68068)
		(end 127.872142 170.4915)
		(width 0.127)
		(layer "In2.Cu")
		(net 226)
	)
	(segment
		(start 78.417962 157.947618)
		(end 78.417962 152.78732)
		(width 0.127)
		(layer "In2.Cu")
		(net 226)
	)
	(segment
		(start 127.872142 170.4915)
		(end 106.405726 170.4915)
		(width 0.127)
		(layer "In2.Cu")
		(net 226)
	)
	(segment
		(start 131.564962 153.368681)
		(end 130.682962 154.250681)
		(width 0.127)
		(layer "In2.Cu")
		(net 226)
	)
	(segment
		(start 77.756897 152.126254)
		(end 77.254297 152.126254)
		(width 0.127)
		(layer "In2.Cu")
		(net 226)
	)
	(segment
		(start 132.694672 144.904141)
		(end 132.375962 145.222851)
		(width 0.127)
		(layer "In2.Cu")
		(net 226)
	)
	(segment
		(start 132.375962 145.222851)
		(end 132.375962 152.554062)
		(width 0.127)
		(layer "In2.Cu")
		(net 226)
	)
	(segment
		(start 97.694726 161.7805)
		(end 82.250844 161.7805)
		(width 0.127)
		(layer "In2.Cu")
		(net 226)
	)
	(segment
		(start 140.393962 144.9665)
		(end 141.367962 144.9665)
		(width 0.127)
		(layer "F.Cu")
		(net 227)
	)
	(segment
		(start 141.906462 144.8915)
		(end 142.680462 144.8915)
		(width 0.127)
		(layer "F.Cu")
		(net 227)
	)
	(segment
		(start 82.218609 152.116)
		(end 82.246637 152.144028)
		(width 0.127)
		(layer "F.Cu")
		(net 227)
	)
	(segment
		(start 142.680462 144.8915)
		(end 143.092962 144.8915)
		(width 0.127)
		(layer "F.Cu")
		(net 227)
	)
	(segment
		(start 141.441962 144.8925)
		(end 141.905462 144.8925)
		(width 0.127)
		(layer "F.Cu")
		(net 227)
	)
	(segment
		(start 141.367962 144.9665)
		(end 141.441962 144.8925)
		(width 0.127)
		(layer "F.Cu")
		(net 227)
	)
	(segment
		(start 143.092962 144.8915)
		(end 143.217961 145.016499)
		(width 0.127)
		(layer "F.Cu")
		(net 227)
	)
	(segment
		(start 81.554961 152.116)
		(end 82.218609 152.116)
		(width 0.127)
		(layer "F.Cu")
		(net 227)
	)
	(via
		(at 143.217961 145.016499)
		(size 0.45)
		(drill 0.1)
		(layers "F.Cu" "B.Cu")
		(net 227)
	)
	(via
		(at 125.854962 160.187283)
		(size 0.45)
		(drill 0.1)
		(layers "F.Cu" "B.Cu")
		(free yes)
		(net 227)
	)
	(via
		(at 82.246637 152.144028)
		(size 0.45)
		(drill 0.1)
		(layers "F.Cu" "B.Cu")
		(net 227)
	)
	(segment
		(start 86.347962 157.9465)
		(end 86.353816 157.9465)
		(width 0.127)
		(layer "In2.Cu")
		(net 227)
	)
	(segment
		(start 119.3014 167.2155)
		(end 125.854962 160.661938)
		(width 0.127)
		(layer "In2.Cu")
		(net 227)
	)
	(segment
		(start 86.911816 158.5045)
		(end 99.051692 158.5045)
		(width 0.127)
		(layer "In2.Cu")
		(net 227)
	)
	(segment
		(start 82.246637 153.845175)
		(end 86.347962 157.9465)
		(width 0.127)
		(layer "In2.Cu")
		(net 227)
	)
	(segment
		(start 82.246637 152.144028)
		(end 82.246637 153.845175)
		(width 0.127)
		(layer "In2.Cu")
		(net 227)
	)
	(segment
		(start 86.353816 157.9465)
		(end 86.911816 158.5045)
		(width 0.127)
		(layer "In2.Cu")
		(net 227)
	)
	(segment
		(start 125.854962 160.661938)
		(end 125.854962 160.047283)
		(width 0.127)
		(layer "In2.Cu")
		(net 227)
	)
	(segment
		(start 107.762692 167.2155)
		(end 119.3014 167.2155)
		(width 0.127)
		(layer "In2.Cu")
		(net 227)
	)
	(segment
		(start 99.051692 158.5045)
		(end 107.762692 167.2155)
		(width 0.127)
		(layer "In2.Cu")
		(net 227)
	)
	(segment
		(start 141.733185 145.016499)
		(end 138.779962 147.969722)
		(width 0.127)
		(layer "In3.Cu")
		(net 227)
	)
	(segment
		(start 138.737462 154.947099)
		(end 138.737462 154.99318)
		(width 0.127)
		(layer "In3.Cu")
		(net 227)
	)
	(segment
		(start 138.779962 147.969722)
		(end 138.779962 154.904599)
		(width 0.127)
		(layer "In3.Cu")
		(net 227)
	)
	(segment
		(start 143.217961 145.016499)
		(end 141.733185 145.016499)
		(width 0.127)
		(layer "In3.Cu")
		(net 227)
	)
	(segment
		(start 138.737462 154.99318)
		(end 136.242142 157.4885)
		(width 0.127)
		(layer "In3.Cu")
		(net 227)
	)
	(segment
		(start 127.573684 157.4885)
		(end 125.854962 159.207222)
		(width 0.127)
		(layer "In3.Cu")
		(net 227)
	)
	(segment
		(start 136.242142 157.4885)
		(end 127.573684 157.4885)
		(width 0.127)
		(layer "In3.Cu")
		(net 227)
	)
	(segment
		(start 138.779962 154.904599)
		(end 138.737462 154.947099)
		(width 0.127)
		(layer "In3.Cu")
		(net 227)
	)
	(segment
		(start 125.854962 159.207222)
		(end 125.854962 160.187283)
		(width 0.127)
		(layer "In3.Cu")
		(net 227)
	)
	(segment
		(start 135.155962 145.1785)
		(end 135.367962 144.9665)
		(width 0.127)
		(layer "F.Cu")
		(net 228)
	)
	(segment
		(start 134.467462 145.1785)
		(end 135.155962 145.1785)
		(width 0.127)
		(layer "F.Cu")
		(net 228)
	)
	(segment
		(start 86.167962 153.431017)
		(end 86.35632 153.619375)
		(width 0.127)
		(layer "F.Cu")
		(net 228)
	)
	(segment
		(start 133.223829 145.1785)
		(end 133.692462 145.1785)
		(width 0.127)
		(layer "F.Cu")
		(net 228)
	)
	(segment
		(start 79.897962 152.265754)
		(end 79.647716 152.516)
		(width 0.127)
		(layer "F.Cu")
		(net 228)
	)
	(segment
		(start 133.033947 145.368382)
		(end 133.223829 145.1785)
		(width 0.127)
		(layer "F.Cu")
		(net 228)
	)
	(segment
		(start 79.647716 152.516)
		(end 78.473961 152.516)
		(width 0.127)
		(layer "F.Cu")
		(net 228)
	)
	(segment
		(start 86.167962 152.8995)
		(end 86.167962 153.431017)
		(width 0.127)
		(layer "F.Cu")
		(net 228)
	)
	(segment
		(start 133.692962 145.1915)
		(end 134.467962 145.1915)
		(width 0.127)
		(layer "F.Cu")
		(net 228)
	)
	(segment
		(start 135.367962 144.9665)
		(end 136.442962 144.9665)
		(width 0.127)
		(layer "F.Cu")
		(net 228)
	)
	(via
		(at 79.897962 152.265754)
		(size 0.45)
		(drill 0.1)
		(layers "F.Cu" "B.Cu")
		(net 228)
	)
	(via
		(at 127.86 152.94)
		(size 0.45)
		(drill 0.1)
		(layers "F.Cu" "B.Cu")
		(net 228)
	)
	(via
		(at 133.033947 145.368382)
		(size 0.45)
		(drill 0.1)
		(layers "F.Cu" "B.Cu")
		(net 228)
	)
	(via
		(at 86.35632 153.619375)
		(size 0.45)
		(drill 0.1)
		(layers "F.Cu" "B.Cu")
		(net 228)
	)
	(segment
		(start 132.409962 145.9245)
		(end 132.96608 145.368382)
		(width 0.127)
		(layer "B.Cu")
		(net 228)
	)
	(segment
		(start 132.409962 146.857264)
		(end 132.409962 145.9245)
		(width 0.127)
		(layer "B.Cu")
		(net 228)
	)
	(segment
		(start 132.96608 145.368382)
		(end 133.033947 145.368382)
		(width 0.127)
		(layer "B.Cu")
		(net 228)
	)
	(segment
		(start 128.1 151.167226)
		(end 132.409962 146.857264)
		(width 0.127)
		(layer "B.Cu")
		(net 228)
	)
	(segment
		(start 128.1 152.7)
		(end 128.1 151.167226)
		(width 0.127)
		(layer "B.Cu")
		(net 228)
	)
	(segment
		(start 127.86 152.94)
		(end 128.1 152.7)
		(width 0.127)
		(layer "B.Cu")
		(net 228)
	)
	(segment
		(start 127.86 153.424462)
		(end 122.122962 159.1615)
		(width 0.127)
		(layer "In2.Cu")
		(net 228)
	)
	(segment
		(start 108.245316 164.113)
		(end 100.108816 155.9765)
		(width 0.127)
		(layer "In2.Cu")
		(net 228)
	)
	(segment
		(start 122.122962 160.8115)
		(end 118.821462 164.113)
		(width 0.127)
		(layer "In2.Cu")
		(net 228)
	)
	(segment
		(start 100.108816 155.9765)
		(end 92.177962 155.9765)
		(width 0.127)
		(layer "In2.Cu")
		(net 228)
	)
	(segment
		(start 92.177962 155.9765)
		(end 89.454462 153.253)
		(width 0.127)
		(layer "In2.Cu")
		(net 228)
	)
	(segment
		(start 122.122962 159.1615)
		(end 122.122962 160.8115)
		(width 0.127)
		(layer "In2.Cu")
		(net 228)
	)
	(segment
		(start 89.454462 153.253)
		(end 86.722695 153.253)
		(width 0.127)
		(layer "In2.Cu")
		(net 228)
	)
	(segment
		(start 127.86 152.94)
		(end 127.86 153.424462)
		(width 0.127)
		(layer "In2.Cu")
		(net 228)
	)
	(segment
		(start 118.821462 164.113)
		(end 108.245316 164.113)
		(width 0.127)
		(layer "In2.Cu")
		(net 228)
	)
	(segment
		(start 86.722695 153.253)
		(end 86.35632 153.619375)
		(width 0.127)
		(layer "In2.Cu")
		(net 228)
	)
	(segment
		(start 79.897962 152.520656)
		(end 79.429462 152.989156)
		(width 0.127)
		(layer "In3.Cu")
		(net 228)
	)
	(segment
		(start 79.429462 153.853)
		(end 79.790962 154.2145)
		(width 0.127)
		(layer "In3.Cu")
		(net 228)
	)
	(segment
		(start 86.35632 154.048142)
		(end 86.35632 153.619375)
		(width 0.127)
		(layer "In3.Cu")
		(net 228)
	)
	(segment
		(start 79.897962 152.265754)
		(end 79.897962 152.520656)
		(width 0.127)
		(layer "In3.Cu")
		(net 228)
	)
	(segment
		(start 79.790962 154.2145)
		(end 86.189962 154.2145)
		(width 0.127)
		(layer "In3.Cu")
		(net 228)
	)
	(segment
		(start 79.429462 152.989156)
		(end 79.429462 153.853)
		(width 0.127)
		(layer "In3.Cu")
		(net 228)
	)
	(segment
		(start 86.189962 154.2145)
		(end 86.35632 154.048142)
		(width 0.127)
		(layer "In3.Cu")
		(net 228)
	)
	(segment
		(start 142.680462 145.3915)
		(end 142.992962 145.3915)
		(width 0.127)
		(layer "F.Cu")
		(net 229)
	)
	(segment
		(start 141.367962 145.4665)
		(end 141.442962 145.3915)
		(width 0.127)
		(layer "F.Cu")
		(net 229)
	)
	(segment
		(start 142.992962 145.3915)
		(end 143.217962 145.6165)
		(width 0.127)
		(layer "F.Cu")
		(net 229)
	)
	(segment
		(start 141.905462 145.3915)
		(end 142.680462 145.3915)
		(width 0.127)
		(layer "F.Cu")
		(net 229)
	)
	(segment
		(start 80.717962 152.08)
		(end 80.717962 152.1915)
		(width 0.127)
		(layer "F.Cu")
		(net 229)
	)
	(segment
		(start 141.905462 145.3915)
		(end 141.442962 145.3915)
		(width 0.127)
		(layer "F.Cu")
		(net 229)
	)
	(segment
		(start 85.781462 153.6065)
		(end 85.767962 153.593)
		(width 0.127)
		(layer "F.Cu")
		(net 229)
	)
	(segment
		(start 85.767962 153.593)
		(end 85.767962 152.8995)
		(width 0.127)
		(layer "F.Cu")
		(net 229)
	)
	(segment
		(start 80.717962 152.1915)
		(end 81.042462 152.516)
		(width 0.127)
		(layer "F.Cu")
		(net 229)
	)
	(segment
		(start 140.393962 145.4665)
		(end 141.367962 145.4665)
		(width 0.127)
		(layer "F.Cu")
		(net 229)
	)
	(segment
		(start 81.042462 152.516)
		(end 81.554961 152.516)
		(width 0.127)
		(layer "F.Cu")
		(net 229)
	)
	(via
		(at 80.717962 152.08)
		(size 0.45)
		(drill 0.1)
		(layers "F.Cu" "B.Cu")
		(net 229)
	)
	(via
		(at 126.267962 159.379)
		(size 0.45)
		(drill 0.1)
		(layers "F.Cu" "B.Cu")
		(free yes)
		(net 229)
	)
	(via
		(at 85.781462 153.6065)
		(size 0.45)
		(drill 0.1)
		(layers "F.Cu" "B.Cu")
		(net 229)
	)
	(via
		(at 143.217962 145.6165)
		(size 0.45)
		(drill 0.1)
		(layers "F.Cu" "B.Cu")
		(net 229)
	)
	(segment
		(start 85.852108 158.7565)
		(end 98.94731 158.7565)
		(width 0.127)
		(layer "In2.Cu")
		(net 229)
	)
	(segment
		(start 119.405782 167.4675)
		(end 126.267962 160.60532)
		(width 0.127)
		(layer "In2.Cu")
		(net 229)
	)
	(segment
		(start 126.267962 160.60532)
		(end 126.267962 159.379)
		(width 0.127)
		(layer "In2.Cu")
		(net 229)
	)
	(segment
		(start 98.94731 158.7565)
		(end 107.65831 167.4675)
		(width 0.127)
		(layer "In2.Cu")
		(net 229)
	)
	(segment
		(start 81.967962 153.33)
		(end 81.967962 153.922882)
		(width 0.127)
		(layer "In2.Cu")
		(net 229)
	)
	(segment
		(start 80.717962 152.08)
		(end 81.967962 153.33)
		(width 0.127)
		(layer "In2.Cu")
		(net 229)
	)
	(segment
		(start 83.354962 155.309882)
		(end 83.354962 156.259354)
		(width 0.127)
		(layer "In2.Cu")
		(net 229)
	)
	(segment
		(start 83.354962 156.259354)
		(end 85.852108 158.7565)
		(width 0.127)
		(layer "In2.Cu")
		(net 229)
	)
	(segment
		(start 107.65831 167.4675)
		(end 119.405782 167.4675)
		(width 0.127)
		(layer "In2.Cu")
		(net 229)
	)
	(segment
		(start 81.967962 153.922882)
		(end 83.354962 155.309882)
		(width 0.127)
		(layer "In2.Cu")
		(net 229)
	)
	(segment
		(start 141.040462 147.794)
		(end 143.217962 145.6165)
		(width 0.127)
		(layer "In3.Cu")
		(net 229)
	)
	(segment
		(start 136.346524 157.7405)
		(end 141.040462 153.046562)
		(width 0.127)
		(layer "In3.Cu")
		(net 229)
	)
	(segment
		(start 84.413962 153.9625)
		(end 85.425462 153.9625)
		(width 0.127)
		(layer "In3.Cu")
		(net 229)
	)
	(segment
		(start 83.117962 152.6665)
		(end 84.413962 153.9625)
		(width 0.127)
		(layer "In3.Cu")
		(net 229)
	)
	(segment
		(start 80.717962 152.08)
		(end 81.304462 152.6665)
		(width 0.127)
		(layer "In3.Cu")
		(net 229)
	)
	(segment
		(start 141.040462 153.046562)
		(end 141.040462 147.794)
		(width 0.127)
		(layer "In3.Cu")
		(net 229)
	)
	(segment
		(start 127.796466 157.7405)
		(end 136.346524 157.7405)
		(width 0.127)
		(layer "In3.Cu")
		(net 229)
	)
	(segment
		(start 126.267962 159.269004)
		(end 127.796466 157.7405)
		(width 0.127)
		(layer "In3.Cu")
		(net 229)
	)
	(segment
		(start 81.304462 152.6665)
		(end 83.117962 152.6665)
		(width 0.127)
		(layer "In3.Cu")
		(net 229)
	)
	(segment
		(start 85.425462 153.9625)
		(end 85.781462 153.6065)
		(width 0.127)
		(layer "In3.Cu")
		(net 229)
	)
	(segment
		(start 126.267962 159.379)
		(end 126.267962 159.269004)
		(width 0.127)
		(layer "In3.Cu")
		(net 229)
	)
	(segment
		(start 134.817962 146.1665)
		(end 134.892962 146.0915)
		(width 0.127)
		(layer "F.Cu")
		(net 230)
	)
	(segment
		(start 134.455462 146.1665)
		(end 134.817962 146.1665)
		(width 0.127)
		(layer "F.Cu")
		(net 230)
	)
	(segment
		(start 135.142962 145.4665)
		(end 136.442962 145.4665)
		(width 0.127)
		(layer "F.Cu")
		(net 230)
	)
	(segment
		(start 134.892962 146.0915)
		(end 134.892962 145.7165)
		(width 0.127)
		(layer "F.Cu")
		(net 230)
	)
	(segment
		(start 133.692962 146.1665)
		(end 134.467962 146.1665)
		(width 0.127)
		(layer "F.Cu")
		(net 230)
	)
	(segment
		(start 134.892962 145.7165)
		(end 135.142962 145.4665)
		(width 0.127)
		(layer "F.Cu")
		(net 230)
	)
	(segment
		(start 133.680462 146.1665)
		(end 133.214992 146.1665)
		(width 0.127)
		(layer "F.Cu")
		(net 230)
	)
	(segment
		(start 77.617715 152.57185)
		(end 77.961865 152.916)
		(width 0.127)
		(layer "F.Cu")
		(net 230)
	)
	(segment
		(start 77.961865 152.916)
		(end 78.473961 152.916)
		(width 0.127)
		(layer "F.Cu")
		(net 230)
	)
	(segment
		(start 133.214992 146.1665)
		(end 133.017233 145.968741)
		(width 0.127)
		(layer "F.Cu")
		(net 230)
	)
	(via
		(at 133.017233 145.968741)
		(size 0.45)
		(drill 0.1)
		(layers "F.Cu" "B.Cu")
		(net 230)
	)
	(via
		(at 77.617715 152.57185)
		(size 0.45)
		(drill 0.1)
		(layers "F.Cu" "B.Cu")
		(net 230)
	)
	(segment
		(start 131.816962 153.473063)
		(end 130.934962 154.355063)
		(width 0.127)
		(layer "In2.Cu")
		(net 230)
	)
	(segment
		(start 133.017233 145.968741)
		(end 132.627962 146.358012)
		(width 0.127)
		(layer "In2.Cu")
		(net 230)
	)
	(segment
		(start 132.627962 152.658444)
		(end 131.816962 153.469445)
		(width 0.127)
		(layer "In2.Cu")
		(net 230)
	)
	(segment
		(start 130.934962 167.785062)
		(end 127.976524 170.7435)
		(width 0.127)
		(layer "In2.Cu")
		(net 230)
	)
	(segment
		(start 106.301344 170.7435)
		(end 97.590344 162.0325)
		(width 0.127)
		(layer "In2.Cu")
		(net 230)
	)
	(segment
		(start 78.165962 153.120097)
		(end 77.617715 152.57185)
		(width 0.127)
		(layer "In2.Cu")
		(net 230)
	)
	(segment
		(start 131.816962 153.469445)
		(end 131.816962 153.473063)
		(width 0.127)
		(layer "In2.Cu")
		(net 230)
	)
	(segment
		(start 130.934962 154.355063)
		(end 130.934962 167.785062)
		(width 0.127)
		(layer "In2.Cu")
		(net 230)
	)
	(segment
		(start 127.976524 170.7435)
		(end 106.301344 170.7435)
		(width 0.127)
		(layer "In2.Cu")
		(net 230)
	)
	(segment
		(start 78.165962 158.052)
		(end 78.165962 153.120097)
		(width 0.127)
		(layer "In2.Cu")
		(net 230)
	)
	(segment
		(start 132.627962 146.358012)
		(end 132.627962 152.658444)
		(width 0.127)
		(layer "In2.Cu")
		(net 230)
	)
	(segment
		(start 97.590344 162.0325)
		(end 82.146462 162.0325)
		(width 0.127)
		(layer "In2.Cu")
		(net 230)
	)
	(segment
		(start 82.146462 162.0325)
		(end 78.165962 158.052)
		(width 0.127)
		(layer "In2.Cu")
		(net 230)
	)
	(segment
		(start 85.042962 157.2665)
		(end 86.217962 157.2665)
		(width 0.2)
		(layer "F.Cu")
		(net 231)
	)
	(segment
		(start 77.644462 153.318)
		(end 78.473961 153.318)
		(width 0.127)
		(layer "F.Cu")
		(net 231)
	)
	(segment
		(start 77.041976 152.660621)
		(end 77.041976 152.715514)
		(width 0.127)
		(layer "F.Cu")
		(net 231)
	)
	(segment
		(start 100.267962 149.1315)
		(end 98.652962 149.1315)
		(width 0.127)
		(layer "F.Cu")
		(net 231)
	)
	(segment
		(start 77.041976 152.715514)
		(end 77.644462 153.318)
		(width 0.127)
		(layer "F.Cu")
		(net 231)
	)
	(segment
		(start 101.267962 149.1165)
		(end 100.282962 149.1165)
		(width 0.127)
		(layer "F.Cu")
		(net 231)
	)
	(segment
		(start 98.652962 149.1315)
		(end 98.477962 149.3065)
		(width 0.127)
		(layer "F.Cu")
		(net 231)
	)
	(via
		(at 98.477962 149.3065)
		(size 0.45)
		(drill 0.1)
		(layers "F.Cu" "B.Cu")
		(net 231)
	)
	(via
		(at 85.042962 157.2665)
		(size 0.45)
		(drill 0.1)
		(layers "F.Cu" "B.Cu")
		(net 231)
	)
	(via
		(at 77.041976 152.660621)
		(size 0.45)
		(drill 0.1)
		(layers "F.Cu" "B.Cu")
		(net 231)
	)
	(segment
		(start 85.017962 156.805)
		(end 94.979462 156.805)
		(width 0.127)
		(layer "B.Cu")
		(net 231)
	)
	(segment
		(start 77.041976 152.660621)
		(end 77.366705 152.98535)
		(width 0.127)
		(layer "B.Cu")
		(net 231)
	)
	(segment
		(start 77.366705 152.98535)
		(end 77.827962 152.98535)
		(width 0.127)
		(layer "B.Cu")
		(net 231)
	)
	(segment
		(start 83.456462 156.805)
		(end 85.017962 156.805)
		(width 0.127)
		(layer "B.Cu")
		(net 231)
	)
	(segment
		(start 98.217962 153.5665)
		(end 94.979462 156.805)
		(width 0.127)
		(layer "B.Cu")
		(net 231)
	)
	(segment
		(start 79.506648 153.985186)
		(end 79.506648 154.07666)
		(width 0.127)
		(layer "B.Cu")
		(net 231)
	)
	(segment
		(start 77.999112 153.1565)
		(end 77.827962 152.98535)
		(width 0.127)
		(layer "B.Cu")
		(net 231)
	)
	(segment
		(start 81.939462 155.2965)
		(end 81.947962 155.2965)
		(width 0.127)
		(layer "B.Cu")
		(net 231)
	)
	(segment
		(start 98.477962 149.3065)
		(end 98.217962 149.5665)
		(width 0.127)
		(layer "B.Cu")
		(net 231)
	)
	(segment
		(start 79.506648 154.07666)
		(end 79.896488 154.4665)
		(width 0.127)
		(layer "B.Cu")
		(net 231)
	)
	(segment
		(start 85.042962 157.2665)
		(end 85.042962 156.83)
		(width 0.127)
		(layer "B.Cu")
		(net 231)
	)
	(segment
		(start 78.677962 153.1565)
		(end 79.506648 153.985186)
		(width 0.127)
		(layer "B.Cu")
		(net 231)
	)
	(segment
		(start 85.042962 156.83)
		(end 85.017962 156.805)
		(width 0.127)
		(layer "B.Cu")
		(net 231)
	)
	(segment
		(start 98.217962 149.5665)
		(end 98.217962 153.5665)
		(width 0.127)
		(layer "B.Cu")
		(net 231)
	)
	(segment
		(start 79.896488 154.4665)
		(end 81.109462 154.4665)
		(width 0.127)
		(layer "B.Cu")
		(net 231)
	)
	(segment
		(start 78.587962 153.1565)
		(end 78.677962 153.1565)
		(width 0.127)
		(layer "B.Cu")
		(net 231)
	)
	(segment
		(start 81.947962 155.2965)
		(end 83.456462 156.805)
		(width 0.127)
		(layer "B.Cu")
		(net 231)
	)
	(segment
		(start 78.492962 153.1565)
		(end 77.999112 153.1565)
		(width 0.127)
		(layer "B.Cu")
		(net 231)
	)
	(segment
		(start 81.109462 154.4665)
		(end 81.939462 155.2965)
		(width 0.127)
		(layer "B.Cu")
		(net 231)
	)
	(segment
		(start 80.431461 153.268444)
		(end 80.478663 153.315646)
		(width 0.127)
		(layer "F.Cu")
		(net 232)
	)
	(segment
		(start 80.478663 153.315646)
		(end 81.552607 153.315646)
		(width 0.127)
		(layer "F.Cu")
		(net 232)
	)
	(segment
		(start 142.680462 146.3665)
		(end 143.067962 146.3665)
		(width 0.127)
		(layer "F.Cu")
		(net 232)
	)
	(segment
		(start 141.905462 146.3665)
		(end 142.680462 146.3665)
		(width 0.127)
		(layer "F.Cu")
		(net 232)
	)
	(segment
		(start 141.905462 146.3665)
		(end 141.492962 146.3665)
		(width 0.127)
		(layer "F.Cu")
		(net 232)
	)
	(segment
		(start 141.090962 145.9645)
		(end 140.393962 145.9645)
		(width 0.127)
		(layer "F.Cu")
		(net 232)
	)
	(segment
		(start 141.492962 146.3665)
		(end 141.090962 145.9645)
		(width 0.127)
		(layer "F.Cu")
		(net 232)
	)
	(segment
		(start 143.067962 146.3665)
		(end 143.217962 146.2165)
		(width 0.127)
		(layer "F.Cu")
		(net 232)
	)
	(via
		(at 80.431461 153.268444)
		(size 0.45)
		(drill 0.1)
		(layers "F.Cu" "B.Cu")
		(net 232)
	)
	(via
		(at 143.217962 146.2165)
		(size 0.45)
		(drill 0.1)
		(layers "F.Cu" "B.Cu")
		(net 232)
	)
	(via
		(at 126.681462 160.189)
		(size 0.45)
		(drill 0.1)
		(layers "F.Cu" "B.Cu")
		(free yes)
		(net 232)
	)
	(segment
		(start 80.958975 153.294749)
		(end 83.102962 155.438736)
		(width 0.127)
		(layer "In2.Cu")
		(net 232)
	)
	(segment
		(start 80.457766 153.294749)
		(end 80.958975 153.294749)
		(width 0.127)
		(layer "In2.Cu")
		(net 232)
	)
	(segment
		(start 80.431461 153.268444)
		(end 80.457766 153.294749)
		(width 0.127)
		(layer "In2.Cu")
		(net 232)
	)
	(segment
		(start 85.747726 159.0085)
		(end 98.842928 159.0085)
		(width 0.127)
		(layer "In2.Cu")
		(net 232)
	)
	(segment
		(start 98.842928 159.0085)
		(end 107.553928 167.7195)
		(width 0.127)
		(layer "In2.Cu")
		(net 232)
	)
	(segment
		(start 83.102962 156.363736)
		(end 85.747726 159.0085)
		(width 0.127)
		(layer "In2.Cu")
		(net 232)
	)
	(segment
		(start 107.553928 167.7195)
		(end 119.510164 167.7195)
		(width 0.127)
		(layer "In2.Cu")
		(net 232)
	)
	(segment
		(start 119.510164 167.7195)
		(end 126.681462 160.548202)
		(width 0.127)
		(layer "In2.Cu")
		(net 232)
	)
	(segment
		(start 126.681462 160.548202)
		(end 126.681462 160.049)
		(width 0.127)
		(layer "In2.Cu")
		(net 232)
	)
	(segment
		(start 83.102962 155.438736)
		(end 83.102962 156.363736)
		(width 0.127)
		(layer "In2.Cu")
		(net 232)
	)
	(segment
		(start 126.681462 159.5665)
		(end 126.681462 160.189)
		(width 0.127)
		(layer "In3.Cu")
		(net 232)
	)
	(segment
		(start 136.450906 157.9925)
		(end 141.292462 153.150944)
		(width 0.127)
		(layer "In3.Cu")
		(net 232)
	)
	(segment
		(start 142.974344 146.2165)
		(end 143.217962 146.2165)
		(width 0.127)
		(layer "In3.Cu")
		(net 232)
	)
	(segment
		(start 127.946684 157.9925)
		(end 136.450906 157.9925)
		(width 0.127)
		(layer "In3.Cu")
		(net 232)
	)
	(segment
		(start 126.681462 159.257722)
		(end 126.681462 159.5665)
		(width 0.127)
		(layer "In3.Cu")
		(net 232)
	)
	(segment
		(start 141.292462 153.150944)
		(end 141.292462 147.898382)
		(width 0.127)
		(layer "In3.Cu")
		(net 232)
	)
	(segment
		(start 126.681462 159.3265)
		(end 126.681462 159.257722)
		(width 0.127)
		(layer "In3.Cu")
		(net 232)
	)
	(segment
		(start 141.292462 147.898382)
		(end 142.974344 146.2165)
		(width 0.127)
		(layer "In3.Cu")
		(net 232)
	)
	(segment
		(start 126.681462 159.257722)
		(end 127.946684 157.9925)
		(width 0.127)
		(layer "In3.Cu")
		(net 232)
	)
	(segment
		(start 126.681462 159.5665)
		(end 126.681462 159.3265)
		(width 0.127)
		(layer "In3.Cu")
		(net 232)
	)
	(segment
		(start 135.242962 146.4645)
		(end 136.442962 146.4645)
		(width 0.127)
		(layer "F.Cu")
		(net 233)
	)
	(segment
		(start 133.041462 146.5915)
		(end 133.116462 146.6665)
		(width 0.127)
		(layer "F.Cu")
		(net 233)
	)
	(segment
		(start 134.455462 146.6665)
		(end 135.040962 146.6665)
		(width 0.127)
		(layer "F.Cu")
		(net 233)
	)
	(segment
		(start 77.996961 153.717)
		(end 78.473961 153.717)
		(width 0.127)
		(layer "F.Cu")
		(net 233)
	)
	(segment
		(start 133.692962 146.6665)
		(end 134.466962 146.6665)
		(width 0.127)
		(layer "F.Cu")
		(net 233)
	)
	(segment
		(start 77.968961 153.689)
		(end 77.996961 153.717)
		(width 0.127)
		(layer "F.Cu")
		(net 233)
	)
	(segment
		(start 77.297961 153.689)
		(end 77.968961 153.689)
		(width 0.127)
		(layer "F.Cu")
		(net 233)
	)
	(segment
		(start 135.040962 146.6665)
		(end 135.242962 146.4645)
		(width 0.127)
		(layer "F.Cu")
		(net 233)
	)
	(segment
		(start 133.116462 146.6665)
		(end 133.680462 146.6665)
		(width 0.127)
		(layer "F.Cu")
		(net 233)
	)
	(via
		(at 77.297961 153.689)
		(size 0.45)
		(drill 0.1)
		(layers "F.Cu" "B.Cu")
		(net 233)
	)
	(via
		(at 133.041462 146.5915)
		(size 0.45)
		(drill 0.1)
		(layers "F.Cu" "B.Cu")
		(net 233)
	)
	(segment
		(start 132.217962 154.8865)
		(end 134.419962 152.6845)
		(width 0.127)
		(layer "In2.Cu")
		(net 233)
	)
	(segment
		(start 76.431462 157.140236)
		(end 76.125462 157.446236)
		(width 0.127)
		(layer "In2.Cu")
		(net 233)
	)
	(segment
		(start 134.419962 147.958723)
		(end 133.052739 146.5915)
		(width 0.127)
		(layer "In2.Cu")
		(net 233)
	)
	(segment
		(start 76.125462 157.446236)
		(end 76.125462 162.096542)
		(width 0.127)
		(layer "In2.Cu")
		(net 233)
	)
	(segment
		(start 77.208962 153.689)
		(end 76.431462 154.4665)
		(width 0.127)
		(layer "In2.Cu")
		(net 233)
	)
	(segment
		(start 102.506962 168.7755)
		(end 105.757962 172.0265)
		(width 0.127)
		(layer "In2.Cu")
		(net 233)
	)
	(segment
		(start 77.83742 163.8085)
		(end 81.389962 163.8085)
		(width 0.127)
		(layer "In2.Cu")
		(net 233)
	)
	(segment
		(start 76.431462 154.4665)
		(end 76.431462 157.140236)
		(width 0.127)
		(layer "In2.Cu")
		(net 233)
	)
	(segment
		(start 128.507962 172.0265)
		(end 132.217962 168.3165)
		(width 0.127)
		(layer "In2.Cu")
		(net 233)
	)
	(segment
		(start 105.757962 172.0265)
		(end 128.507962 172.0265)
		(width 0.127)
		(layer "In2.Cu")
		(net 233)
	)
	(segment
		(start 81.389962 163.8085)
		(end 86.356962 168.7755)
		(width 0.127)
		(layer "In2.Cu")
		(net 233)
	)
	(segment
		(start 76.125462 162.096542)
		(end 77.83742 163.8085)
		(width 0.127)
		(layer "In2.Cu")
		(net 233)
	)
	(segment
		(start 77.297961 153.689)
		(end 77.208962 153.689)
		(width 0.127)
		(layer "In2.Cu")
		(net 233)
	)
	(segment
		(start 132.217962 168.3165)
		(end 132.217962 154.8865)
		(width 0.127)
		(layer "In2.Cu")
		(net 233)
	)
	(segment
		(start 133.052739 146.5915)
		(end 133.041462 146.5915)
		(width 0.127)
		(layer "In2.Cu")
		(net 233)
	)
	(segment
		(start 134.419962 152.6845)
		(end 134.419962 147.958723)
		(width 0.127)
		(layer "In2.Cu")
		(net 233)
	)
	(segment
		(start 86.356962 168.7755)
		(end 102.506962 168.7755)
		(width 0.127)
		(layer "In2.Cu")
		(net 233)
	)
	(segment
		(start 141.905462 146.8665)
		(end 142.680462 146.8665)
		(width 0.127)
		(layer "F.Cu")
		(net 234)
	)
	(segment
		(start 143.142962 146.8665)
		(end 143.217962 146.7915)
		(width 0.127)
		(layer "F.Cu")
		(net 234)
	)
	(segment
		(start 80.74594 153.763703)
		(end 80.792643 153.717)
		(width 0.127)
		(layer "F.Cu")
		(net 234)
	)
	(segment
		(start 141.318962 146.9655)
		(end 141.417962 146.8665)
		(width 0.127)
		(layer "F.Cu")
		(net 234)
	)
	(segment
		(start 80.792643 153.717)
		(end 81.554961 153.717)
		(width 0.127)
		(layer "F.Cu")
		(net 234)
	)
	(segment
		(start 140.393962 146.9655)
		(end 141.318962 146.9655)
		(width 0.127)
		(layer "F.Cu")
		(net 234)
	)
	(segment
		(start 142.680462 146.8665)
		(end 143.142962 146.8665)
		(width 0.127)
		(layer "F.Cu")
		(net 234)
	)
	(segment
		(start 141.905462 146.8665)
		(end 141.417962 146.8665)
		(width 0.127)
		(layer "F.Cu")
		(net 234)
	)
	(via
		(at 127.094962 159.429)
		(size 0.45)
		(drill 0.1)
		(layers "F.Cu" "B.Cu")
		(free yes)
		(net 234)
	)
	(via
		(at 143.217962 146.7915)
		(size 0.45)
		(drill 0.1)
		(layers "F.Cu" "B.Cu")
		(net 234)
	)
	(via
		(at 80.74594 153.763703)
		(size 0.45)
		(drill 0.1)
		(layers "F.Cu" "B.Cu")
		(net 234)
	)
	(segment
		(start 82.850962 156.468118)
		(end 85.643344 159.2605)
		(width 0.127)
		(layer "In2.Cu")
		(net 234)
	)
	(segment
		(start 82.850962 155.543118)
		(end 82.850962 156.468118)
		(width 0.127)
		(layer "In2.Cu")
		(net 234)
	)
	(segment
		(start 98.738546 159.2605)
		(end 107.449546 167.9715)
		(width 0.127)
		(layer "In2.Cu")
		(net 234)
	)
	(segment
		(start 119.614546 167.9715)
		(end 127.094962 160.491084)
		(width 0.127)
		(layer "In2.Cu")
		(net 234)
	)
	(segment
		(start 80.74594 153.763703)
		(end 81.071547 153.763703)
		(width 0.127)
		(layer "In2.Cu")
		(net 234)
	)
	(segment
		(start 127.094962 160.491084)
		(end 127.094962 159.429)
		(width 0.127)
		(layer "In2.Cu")
		(net 234)
	)
	(segment
		(start 107.449546 167.9715)
		(end 119.614546 167.9715)
		(width 0.127)
		(layer "In2.Cu")
		(net 234)
	)
	(segment
		(start 81.071547 153.763703)
		(end 82.850962 155.543118)
		(width 0.127)
		(layer "In2.Cu")
		(net 234)
	)
	(segment
		(start 85.643344 159.2605)
		(end 98.738546 159.2605)
		(width 0.127)
		(layer "In2.Cu")
		(net 234)
	)
	(segment
		(start 141.544462 148.465)
		(end 141.544462 153.255326)
		(width 0.127)
		(layer "In3.Cu")
		(net 234)
	)
	(segment
		(start 127.094962 159.31484)
		(end 127.094962 159.429)
		(width 0.127)
		(layer "In3.Cu")
		(net 234)
	)
	(segment
		(start 128.165302 158.2445)
		(end 127.094962 159.31484)
		(width 0.127)
		(layer "In3.Cu")
		(net 234)
	)
	(segment
		(start 136.555288 158.2445)
		(end 128.165302 158.2445)
		(width 0.127)
		(layer "In3.Cu")
		(net 234)
	)
	(segment
		(start 141.544462 153.255326)
		(end 136.555288 158.2445)
		(width 0.127)
		(layer "In3.Cu")
		(net 234)
	)
	(segment
		(start 143.217962 146.7915)
		(end 141.544462 148.465)
		(width 0.127)
		(layer "In3.Cu")
		(net 234)
	)
	(segment
		(start 133.692962 147.6665)
		(end 134.467962 147.6665)
		(width 0.127)
		(layer "F.Cu")
		(net 235)
	)
	(segment
		(start 90.040962 157.2145)
		(end 89.782962 156.9565)
		(width 0.127)
		(layer "F.Cu")
		(net 235)
	)
	(segment
		(start 89.042962 155.7665)
		(end 89.042962 156.9565)
		(width 0.127)
		(layer "F.Cu")
		(net 235)
	)
	(segment
		(start 89.782962 156.9565)
		(end 89.042962 156.9565)
		(width 0.127)
		(layer "F.Cu")
		(net 235)
	)
	(segment
		(start 87.742962 154.4665)
		(end 89.042962 155.7665)
		(width 0.127)
		(layer "F.Cu")
		(net 235)
	)
	(segment
		(start 135.543962 146.9655)
		(end 136.442962 146.9655)
		(width 0.127)
		(layer "F.Cu")
		(net 235)
	)
	(segment
		(start 134.455462 147.6665)
		(end 134.842962 147.6665)
		(width 0.127)
		(layer "F.Cu")
		(net 235)
	)
	(segment
		(start 134.842962 147.6665)
		(end 135.543962 146.9655)
		(width 0.127)
		(layer "F.Cu")
		(net 235)
	)
	(segment
		(start 133.680462 147.6675)
		(end 133.141961 147.6675)
		(width 0.127)
		(layer "F.Cu")
		(net 235)
	)
	(segment
		(start 77.721962 154.117)
		(end 78.473961 154.117)
		(width 0.127)
		(layer "F.Cu")
		(net 235)
	)
	(segment
		(start 86.992962 154.4665)
		(end 87.742962 154.4665)
		(width 0.127)
		(layer "F.Cu")
		(net 235)
	)
	(segment
		(start 77.707462 154.1025)
		(end 77.721962 154.117)
		(width 0.127)
		(layer "F.Cu")
		(net 235)
	)
	(segment
		(start 133.067961 147.7415)
		(end 133.141961 147.6675)
		(width 0.127)
		(layer "F.Cu")
		(net 235)
	)
	(segment
		(start 90.040962 157.6915)
		(end 90.040962 157.2145)
		(width 0.127)
		(layer "F.Cu")
		(net 235)
	)
	(via
		(at 86.992962 154.4665)
		(size 0.45)
		(drill 0.1)
		(layers "F.Cu" "B.Cu")
		(net 235)
	)
	(via
		(at 133.067961 147.7415)
		(size 0.45)
		(drill 0.1)
		(layers "F.Cu" "B.Cu")
		(net 235)
	)
	(via
		(at 77.707462 154.1025)
		(size 0.45)
		(drill 0.1)
		(layers "F.Cu" "B.Cu")
		(net 235)
	)
	(segment
		(start 102.611344 168.5235)
		(end 86.461344 168.5235)
		(width 0.127)
		(layer "In2.Cu")
		(net 235)
	)
	(segment
		(start 133.067961 147.7415)
		(end 133.592962 147.7415)
		(width 0.127)
		(layer "In2.Cu")
		(net 235)
	)
	(segment
		(start 81.494344 163.5565)
		(end 77.941802 163.5565)
		(width 0.127)
		(layer "In2.Cu")
		(net 235)
	)
	(segment
		(start 134.167962 152.5765)
		(end 132.847962 153.8965)
		(width 0.127)
		(layer "In2.Cu")
		(net 235)
	)
	(segment
		(start 86.461344 168.5235)
		(end 81.494344 163.5565)
		(width 0.127)
		(layer "In2.Cu")
		(net 235)
	)
	(segment
		(start 134.167962 148.3165)
		(end 134.167962 152.5765)
		(width 0.127)
		(layer "In2.Cu")
		(net 235)
	)
	(segment
		(start 77.171811 154.1025)
		(end 77.707462 154.1025)
		(width 0.127)
		(layer "In2.Cu")
		(net 235)
	)
	(segment
		(start 132.847962 153.900118)
		(end 131.965962 154.782118)
		(width 0.127)
		(layer "In2.Cu")
		(net 235)
	)
	(segment
		(start 132.847962 153.8965)
		(end 132.847962 153.900118)
		(width 0.127)
		(layer "In2.Cu")
		(net 235)
	)
	(segment
		(start 77.941802 163.5565)
		(end 76.377462 161.99216)
		(width 0.127)
		(layer "In2.Cu")
		(net 235)
	)
	(segment
		(start 76.377462 157.550618)
		(end 76.692962 157.235118)
		(width 0.127)
		(layer "In2.Cu")
		(net 235)
	)
	(segment
		(start 105.862344 171.7745)
		(end 102.611344 168.5235)
		(width 0.127)
		(layer "In2.Cu")
		(net 235)
	)
	(segment
		(start 76.377462 161.99216)
		(end 76.377462 157.550618)
		(width 0.127)
		(layer "In2.Cu")
		(net 235)
	)
	(segment
		(start 128.40358 171.7745)
		(end 105.862344 171.7745)
		(width 0.127)
		(layer "In2.Cu")
		(net 235)
	)
	(segment
		(start 133.592962 147.7415)
		(end 134.167962 148.3165)
		(width 0.127)
		(layer "In2.Cu")
		(net 235)
	)
	(segment
		(start 131.965962 168.212118)
		(end 128.40358 171.7745)
		(width 0.127)
		(layer "In2.Cu")
		(net 235)
	)
	(segment
		(start 131.965962 154.782118)
		(end 131.965962 168.212118)
		(width 0.127)
		(layer "In2.Cu")
		(net 235)
	)
	(segment
		(start 76.692962 157.235118)
		(end 76.692962 154.581349)
		(width 0.127)
		(layer "In2.Cu")
		(net 235)
	)
	(segment
		(start 76.692962 154.581349)
		(end 77.171811 154.1025)
		(width 0.127)
		(layer "In2.Cu")
		(net 235)
	)
	(segment
		(start 86.992962 154.4665)
		(end 78.071462 154.4665)
		(width 0.127)
		(layer "In3.Cu")
		(net 235)
	)
	(segment
		(start 78.071462 154.4665)
		(end 77.707462 154.1025)
		(width 0.127)
		(layer "In3.Cu")
		(net 235)
	)
	(segment
		(start 143.092962 147.8665)
		(end 143.217961 147.991499)
		(width 0.127)
		(layer "F.Cu")
		(net 236)
	)
	(segment
		(start 141.906462 147.8665)
		(end 142.680462 147.8665)
		(width 0.127)
		(layer "F.Cu")
		(net 236)
	)
	(segment
		(start 81.554961 154.117)
		(end 80.982823 154.117)
		(width 0.127)
		(layer "F.Cu")
		(net 236)
	)
	(segment
		(start 141.468962 147.8675)
		(end 141.905462 147.8675)
		(width 0.127)
		(layer "F.Cu")
		(net 236)
	)
	(segment
		(start 80.172148 153.801)
		(end 80.578009 154.206861)
		(width 0.127)
		(layer "F.Cu")
		(net 236)
	)
	(segment
		(start 80.578009 154.206861)
		(end 80.892962 154.206861)
		(width 0.127)
		(layer "F.Cu")
		(net 236)
	)
	(segment
		(start 141.066962 147.4655)
		(end 141.468962 147.8675)
		(width 0.127)
		(layer "F.Cu")
		(net 236)
	)
	(segment
		(start 80.982823 154.117)
		(end 80.892962 154.206861)
		(width 0.127)
		(layer "F.Cu")
		(net 236)
	)
	(segment
		(start 142.680462 147.8665)
		(end 143.092962 147.8665)
		(width 0.127)
		(layer "F.Cu")
		(net 236)
	)
	(via
		(at 127.567962 160.12)
		(size 0.45)
		(drill 0.1)
		(layers "F.Cu" "B.Cu")
		(free yes)
		(net 236)
	)
	(via
		(at 80.172148 153.801)
		(size 0.45)
		(drill 0.1)
		(layers "F.Cu" "B.Cu")
		(net 236)
	)
	(via
		(at 143.217961 147.991499)
		(size 0.45)
		(drill 0.1)
		(layers "F.Cu" "B.Cu")
		(net 236)
	)
	(segment
		(start 98.634164 159.5125)
		(end 85.538962 159.5125)
		(width 0.127)
		(layer "In2.Cu")
		(net 236)
	)
	(segment
		(start 107.345164 168.2235)
		(end 98.634164 159.5125)
		(width 0.127)
		(layer "In2.Cu")
		(net 236)
	)
	(segment
		(start 126.895434 168.2235)
		(end 107.345164 168.2235)
		(width 0.127)
		(layer "In2.Cu")
		(net 236)
	)
	(segment
		(start 82.598962 156.5725)
		(end 82.598962 155.6475)
		(width 0.127)
		(layer "In2.Cu")
		(net 236)
	)
	(segment
		(start 82.598962 155.6475)
		(end 81.165962 154.2145)
		(width 0.127)
		(layer "In2.Cu")
		(net 236)
	)
	(segment
		(start 127.567962 160.12)
		(end 127.567962 162.4265)
		(width 0.127)
		(layer "In2.Cu")
		(net 236)
	)
	(segment
		(start 127.567962 162.4265)
		(end 128.153462 163.012)
		(width 0.127)
		(layer "In2.Cu")
		(net 236)
	)
	(segment
		(start 128.153462 163.012)
		(end 128.153462 166.965472)
		(width 0.127)
		(layer "In2.Cu")
		(net 236)
	)
	(segment
		(start 85.538962 159.5125)
		(end 82.598962 156.5725)
		(width 0.127)
		(layer "In2.Cu")
		(net 236)
	)
	(segment
		(start 128.153462 166.965472)
		(end 126.895434 168.2235)
		(width 0.127)
		(layer "In2.Cu")
		(net 236)
	)
	(segment
		(start 80.585648 154.2145)
		(end 80.172148 153.801)
		(width 0.127)
		(layer "In2.Cu")
		(net 236)
	)
	(segment
		(start 81.165962 154.2145)
		(end 80.585648 154.2145)
		(width 0.127)
		(layer "In2.Cu")
		(net 236)
	)
	(segment
		(start 136.65967 158.4965)
		(end 141.796462 153.359708)
		(width 0.127)
		(layer "In3.Cu")
		(net 236)
	)
	(segment
		(start 127.567962 159.198222)
		(end 128.269684 158.4965)
		(width 0.127)
		(layer "In3.Cu")
		(net 236)
	)
	(segment
		(start 127.567962 160.12)
		(end 127.567962 159.198222)
		(width 0.127)
		(layer "In3.Cu")
		(net 236)
	)
	(segment
		(start 141.796462 149.412998)
		(end 143.217961 147.991499)
		(width 0.127)
		(layer "In3.Cu")
		(net 236)
	)
	(segment
		(start 141.796462 153.359708)
		(end 141.796462 149.412998)
		(width 0.127)
		(layer "In3.Cu")
		(net 236)
	)
	(segment
		(start 128.269684 158.4965)
		(end 136.65967 158.4965)
		(width 0.127)
		(layer "In3.Cu")
		(net 236)
	)
	(segment
		(start 135.565962 147.9655)
		(end 136.442962 147.9655)
		(width 0.127)
		(layer "F.Cu")
		(net 237)
	)
	(segment
		(start 134.417462 149.1415)
		(end 133.305462 149.1415)
		(width 0.127)
		(layer "F.Cu")
		(net 237)
	)
	(segment
		(start 77.343089 154.516)
		(end 77.32618 154.532909)
		(width 0.127)
		(layer "F.Cu")
		(net 237)
	)
	(segment
		(start 77.001553 154.532909)
		(end 76.692962 154.8415)
		(width 0.127)
		(layer "F.Cu")
		(net 237)
	)
	(segment
		(start 76.692962 154.8415)
		(end 76.692962 155.166127)
		(width 0.127)
		(layer "F.Cu")
		(net 237)
	)
	(segment
		(start 134.917962 148.6135)
		(end 135.565962 147.9655)
		(width 0.127)
		(layer "F.Cu")
		(net 237)
	)
	(segment
		(start 77.32618 154.532909)
		(end 77.001553 154.532909)
		(width 0.127)
		(layer "F.Cu")
		(net 237)
	)
	(segment
		(start 134.830962 149.1285)
		(end 134.917962 149.0415)
		(width 0.127)
		(layer "F.Cu")
		(net 237)
	)
	(segment
		(start 134.917962 149.0415)
		(end 134.917962 148.6135)
		(width 0.127)
		(layer "F.Cu")
		(net 237)
	)
	(segment
		(start 78.473961 154.516)
		(end 77.343089 154.516)
		(width 0.127)
		(layer "F.Cu")
		(net 237)
	)
	(segment
		(start 134.455462 149.1285)
		(end 134.830962 149.1285)
		(width 0.127)
		(layer "F.Cu")
		(net 237)
	)
	(segment
		(start 133.292961 149.1415)
		(end 133.067961 148.9165)
		(width 0.127)
		(layer "F.Cu")
		(net 237)
	)
	(via
		(at 133.067961 148.9165)
		(size 0.45)
		(drill 0.1)
		(layers "F.Cu" "B.Cu")
		(net 237)
	)
	(via
		(at 77.32618 154.532909)
		(size 0.45)
		(drill 0.1)
		(layers "F.Cu" "B.Cu")
		(net 237)
	)
	(segment
		(start 106.196962 170.9955)
		(end 97.485962 162.2845)
		(width 0.127)
		(layer "In2.Cu")
		(net 237)
	)
	(segment
		(start 97.485962 162.2845)
		(end 77.026184 162.2845)
		(width 0.127)
		(layer "In2.Cu")
		(net 237)
	)
	(segment
		(start 128.080906 170.9955)
		(end 106.196962 170.9955)
		(width 0.127)
		(layer "In2.Cu")
		(net 237)
	)
	(segment
		(start 76.980287 157.304175)
		(end 76.980287 154.878802)
		(width 0.127)
		(layer "In2.Cu")
		(net 237)
	)
	(segment
		(start 133.640962 149.489501)
		(end 133.640962 151.406)
		(width 0.127)
		(layer "In2.Cu")
		(net 237)
	)
	(segment
		(start 76.629462 157.655)
		(end 76.980287 157.304175)
		(width 0.127)
		(layer "In2.Cu")
		(net 237)
	)
	(segment
		(start 76.980287 154.878802)
		(end 77.32618 154.532909)
		(width 0.127)
		(layer "In2.Cu")
		(net 237)
	)
	(segment
		(start 132.068962 153.577445)
		(end 131.186962 154.459445)
		(width 0.127)
		(layer "In2.Cu")
		(net 237)
	)
	(segment
		(start 133.640962 151.406)
		(end 132.879962 152.167)
		(width 0.127)
		(layer "In2.Cu")
		(net 237)
	)
	(segment
		(start 132.068962 153.573827)
		(end 132.068962 153.577445)
		(width 0.127)
		(layer "In2.Cu")
		(net 237)
	)
	(segment
		(start 132.879962 152.762826)
		(end 132.068962 153.573827)
		(width 0.127)
		(layer "In2.Cu")
		(net 237)
	)
	(segment
		(start 133.067961 148.9165)
		(end 133.640962 149.489501)
		(width 0.127)
		(layer "In2.Cu")
		(net 237)
	)
	(segment
		(start 77.026184 162.2845)
		(end 76.629462 161.887778)
		(width 0.127)
		(layer "In2.Cu")
		(net 237)
	)
	(segment
		(start 76.629462 161.887778)
		(end 76.629462 157.655)
		(width 0.127)
		(layer "In2.Cu")
		(net 237)
	)
	(segment
		(start 131.186962 154.459445)
		(end 131.186962 167.889444)
		(width 0.127)
		(layer "In2.Cu")
		(net 237)
	)
	(segment
		(start 131.186962 167.889444)
		(end 128.080906 170.9955)
		(width 0.127)
		(layer "In2.Cu")
		(net 237)
	)
	(segment
		(start 132.879962 152.167)
		(end 132.879962 152.762826)
		(width 0.127)
		(layer "In2.Cu")
		(net 237)
	)
	(segment
		(start 142.680462 148.3665)
		(end 142.992962 148.3665)
		(width 0.127)
		(layer "F.Cu")
		(net 238)
	)
	(segment
		(start 141.467962 148.3665)
		(end 141.066962 147.9655)
		(width 0.127)
		(layer "F.Cu")
		(net 238)
	)
	(segment
		(start 81.075101 154.516)
		(end 81.017962 154.458861)
		(width 0.127)
		(layer "F.Cu")
		(net 238)
	)
	(segment
		(start 83.968462 157.617)
		(end 83.968462 158.2165)
		(width 0.127)
		(layer "F.Cu")
		(net 238)
	)
	(segment
		(start 141.905462 148.3665)
		(end 142.680462 148.3665)
		(width 0.127)
		(layer "F.Cu")
		(net 238)
	)
	(segment
		(start 83.642962 157.2915)
		(end 83.968462 157.617)
		(width 0.127)
		(layer "F.Cu")
		(net 238)
	)
	(segment
		(start 81.554961 154.516)
		(end 81.075101 154.516)
		(width 0.127)
		(layer "F.Cu")
		(net 238)
	)
	(segment
		(start 82.667962 157.2915)
		(end 83.642962 157.2915)
		(width 0.127)
		(layer "F.Cu")
		(net 238)
	)
	(segment
		(start 142.992962 148.3665)
		(end 143.217962 148.5915)
		(width 0.127)
		(layer "F.Cu")
		(net 238)
	)
	(segment
		(start 80.210323 154.458861)
		(end 81.017962 154.458861)
		(width 0.127)
		(layer "F.Cu")
		(net 238)
	)
	(segment
		(start 79.758648 153.364314)
		(end 79.758648 154.007186)
		(width 0.127)
		(layer "F.Cu")
		(net 238)
	)
	(segment
		(start 79.758648 154.007186)
		(end 80.210323 154.458861)
		(width 0.127)
		(layer "F.Cu")
		(net 238)
	)
	(segment
		(start 79.856462 153.2665)
		(end 79.758648 153.364314)
		(width 0.127)
		(layer "F.Cu")
		(net 238)
	)
	(segment
		(start 141.905462 148.3665)
		(end 141.467962 148.3665)
		(width 0.127)
		(layer "F.Cu")
		(net 238)
	)
	(via
		(at 127.992962 159.3915)
		(size 0.45)
		(drill 0.1)
		(layers "F.Cu" "B.Cu")
		(free yes)
		(net 238)
	)
	(via
		(at 82.667962 157.2915)
		(size 0.45)
		(drill 0.1)
		(layers "F.Cu" "B.Cu")
		(net 238)
	)
	(via
		(at 79.856462 153.2665)
		(size 0.45)
		(drill 0.1)
		(layers "F.Cu" "B.Cu")
		(net 238)
	)
	(via
		(at 143.217962 148.5915)
		(size 0.45)
		(drill 0.1)
		(layers "F.Cu" "B.Cu")
		(net 238)
	)
	(segment
		(start 82.667962 157.2915)
		(end 82.346962 157.2915)
		(width 0.127)
		(layer "In2.Cu")
		(net 238)
	)
	(segment
		(start 127.992962 162.4515)
		(end 128.405462 162.864)
		(width 0.127)
		(layer "In2.Cu")
		(net 238)
	)
	(segment
		(start 128.405462 167.069854)
		(end 126.999816 168.4755)
		(width 0.127)
		(layer "In2.Cu")
		(net 238)
	)
	(segment
		(start 80.117962 154.4665)
		(end 81.06158 154.4665)
		(width 0.127)
		(layer "In2.Cu")
		(net 238)
	)
	(segment
		(start 126.999816 168.4755)
		(end 107.240782 168.4755)
		(width 0.127)
		(layer "In2.Cu")
		(net 238)
	)
	(segment
		(start 79.758648 153.364314)
		(end 79.758648 154.107186)
		(width 0.127)
		(layer "In2.Cu")
		(net 238)
	)
	(segment
		(start 82.346962 157.689118)
		(end 82.346962 157.2915)
		(width 0.127)
		(layer "In2.Cu")
		(net 238)
	)
	(segment
		(start 84.422344 159.7645)
		(end 82.346962 157.689118)
		(width 0.127)
		(layer "In2.Cu")
		(net 238)
	)
	(segment
		(start 82.346962 155.751882)
		(end 82.346962 157.2915)
		(width 0.127)
		(layer "In2.Cu")
		(net 238)
	)
	(segment
		(start 79.856462 153.2665)
		(end 79.758648 153.364314)
		(width 0.127)
		(layer "In2.Cu")
		(net 238)
	)
	(segment
		(start 98.529782 159.7645)
		(end 84.422344 159.7645)
		(width 0.127)
		(layer "In2.Cu")
		(net 238)
	)
	(segment
		(start 79.758648 154.107186)
		(end 80.117962 154.4665)
		(width 0.127)
		(layer "In2.Cu")
		(net 238)
	)
	(segment
		(start 128.405462 162.864)
		(end 128.405462 167.069854)
		(width 0.127)
		(layer "In2.Cu")
		(net 238)
	)
	(segment
		(start 107.240782 168.4755)
		(end 98.529782 159.7645)
		(width 0.127)
		(layer "In2.Cu")
		(net 238)
	)
	(segment
		(start 81.06158 154.4665)
		(end 82.346962 155.751882)
		(width 0.127)
		(layer "In2.Cu")
		(net 238)
	)
	(segment
		(start 127.992962 159.3915)
		(end 127.992962 162.4515)
		(width 0.127)
		(layer "In2.Cu")
		(net 238)
	)
	(segment
		(start 127.992962 159.24034)
		(end 128.484802 158.7485)
		(width 0.127)
		(layer "In3.Cu")
		(net 238)
	)
	(segment
		(start 127.992962 159.3915)
		(end 127.992962 159.24034)
		(width 0.127)
		(layer "In3.Cu")
		(net 238)
	)
	(segment
		(start 142.048462 149.761)
		(end 143.217962 148.5915)
		(width 0.127)
		(layer "In3.Cu")
		(net 238)
	)
	(segment
		(start 136.764052 158.7485)
		(end 142.048462 153.46409)
		(width 0.127)
		(layer "In3.Cu")
		(net 238)
	)
	(segment
		(start 142.048462 153.46409)
		(end 142.048462 149.761)
		(width 0.127)
		(layer "In3.Cu")
		(net 238)
	)
	(segment
		(start 128.484802 158.7485)
		(end 136.764052 158.7485)
		(width 0.127)
		(layer "In3.Cu")
		(net 238)
	)
	(segment
		(start 135.105962 150.6035)
		(end 135.492962 150.2165)
		(width 0.127)
		(layer "F.Cu")
		(net 239)
	)
	(segment
		(start 88.789962 153.584917)
		(end 88.789962 152.9695)
		(width 0.127)
		(layer "F.Cu")
		(net 239)
	)
	(segment
		(start 77.755832 154.917)
		(end 78.473961 154.917)
		(width 0.127)
		(layer "F.Cu")
		(net 239)
	)
	(segment
		(start 77.743324 154.929508)
		(end 77.755832 154.917)
		(width 0.127)
		(layer "F.Cu")
		(net 239)
	)
	(segment
		(start 133.680462 150.6295)
		(end 133.179962 150.6295)
		(width 0.127)
		(layer "F.Cu")
		(net 239)
	)
	(segment
		(start 133.179962 150.6295)
		(end 133.042962 150.7665)
		(width 0.127)
		(layer "F.Cu")
		(net 239)
	)
	(segment
		(start 88.667962 153.706917)
		(end 88.789962 153.584917)
		(width 0.127)
		(layer "F.Cu")
		(net 239)
	)
	(segment
		(start 135.643962 148.9655)
		(end 136.442962 148.9655)
		(width 0.127)
		(layer "F.Cu")
		(net 239)
	)
	(segment
		(start 135.492962 149.1165)
		(end 135.643962 148.9655)
		(width 0.127)
		(layer "F.Cu")
		(net 239)
	)
	(segment
		(start 133.692962 150.6415)
		(end 134.467962 150.6415)
		(width 0.127)
		(layer "F.Cu")
		(net 239)
	)
	(segment
		(start 134.455462 150.6035)
		(end 135.105962 150.6035)
		(width 0.127)
		(layer "F.Cu")
		(net 239)
	)
	(segment
		(start 135.492962 150.2165)
		(end 135.492962 149.1165)
		(width 0.127)
		(layer "F.Cu")
		(net 239)
	)
	(via
		(at 133.042962 150.7665)
		(size 0.45)
		(drill 0.1)
		(layers "F.Cu" "B.Cu")
		(net 239)
	)
	(via
		(at 130.904962 150.6295)
		(size 0.45)
		(drill 0.1)
		(layers "F.Cu" "B.Cu")
		(net 239)
	)
	(via
		(at 88.667962 153.706917)
		(size 0.45)
		(drill 0.1)
		(layers "F.Cu" "B.Cu")
		(net 239)
	)
	(via
		(at 77.743324 154.929508)
		(size 0.45)
		(drill 0.1)
		(layers "F.Cu" "B.Cu")
		(net 239)
	)
	(segment
		(start 130.904962 150.6295)
		(end 132.905962 150.6295)
		(width 0.127)
		(layer "B.Cu")
		(net 239)
	)
	(segment
		(start 132.905962 150.6295)
		(end 133.042962 150.7665)
		(width 0.127)
		(layer "B.Cu")
		(net 239)
	)
	(segment
		(start 88.667962 153.706917)
		(end 88.592962 153.781917)
		(width 0.127)
		(layer "In2.Cu")
		(net 239)
	)
	(segment
		(start 108.493366 165.4515)
		(end 118.570726 165.4515)
		(width 0.127)
		(layer "In2.Cu")
		(net 239)
	)
	(segment
		(start 122.911962 161.110264)
		(end 122.911962 159.475264)
		(width 0.127)
		(layer "In2.Cu")
		(net 239)
	)
	(segment
		(start 99.782366 156.7405)
		(end 108.493366 165.4515)
		(width 0.127)
		(layer "In2.Cu")
		(net 239)
	)
	(segment
		(start 88.592962 153.781917)
		(end 88.592962 155.1665)
		(width 0.127)
		(layer "In2.Cu")
		(net 239)
	)
	(segment
		(start 130.904962 151.482264)
		(end 130.904962 150.6295)
		(width 0.127)
		(layer "In2.Cu")
		(net 239)
	)
	(segment
		(start 90.166962 156.7405)
		(end 99.782366 156.7405)
		(width 0.127)
		(layer "In2.Cu")
		(net 239)
	)
	(segment
		(start 88.592962 155.1665)
		(end 90.166962 156.7405)
		(width 0.127)
		(layer "In2.Cu")
		(net 239)
	)
	(segment
		(start 122.911962 159.475264)
		(end 130.904962 151.482264)
		(width 0.127)
		(layer "In2.Cu")
		(net 239)
	)
	(segment
		(start 118.570726 165.4515)
		(end 122.911962 161.110264)
		(width 0.127)
		(layer "In2.Cu")
		(net 239)
	)
	(segment
		(start 81.872344 156.5145)
		(end 80.999344 155.6415)
		(width 0.127)
		(layer "In3.Cu")
		(net 239)
	)
	(segment
		(start 88.631163 153.706917)
		(end 85.82358 156.5145)
		(width 0.127)
		(layer "In3.Cu")
		(net 239)
	)
	(segment
		(start 85.82358 156.5145)
		(end 81.872344 156.5145)
		(width 0.127)
		(layer "In3.Cu")
		(net 239)
	)
	(segment
		(start 80.999344 155.6415)
		(end 78.455316 155.6415)
		(width 0.127)
		(layer "In3.Cu")
		(net 239)
	)
	(segment
		(start 78.455316 155.6415)
		(end 77.743324 154.929508)
		(width 0.127)
		(layer "In3.Cu")
		(net 239)
	)
	(segment
		(start 88.667962 153.706917)
		(end 88.631163 153.706917)
		(width 0.127)
		(layer "In3.Cu")
		(net 239)
	)
	(segment
		(start 141.442962 149.3415)
		(end 141.066962 148.9655)
		(width 0.127)
		(layer "F.Cu")
		(net 240)
	)
	(segment
		(start 80.854959 154.88)
		(end 80.854959 155.092998)
		(width 0.127)
		(layer "F.Cu")
		(net 240)
	)
	(segment
		(start 84.021962 153.9625)
		(end 85.12574 153.9625)
		(width 0.127)
		(layer "F.Cu")
		(net 240)
	)
	(segment
		(start 141.905462 149.3415)
		(end 142.680462 149.3415)
		(width 0.127)
		(layer "F.Cu")
		(net 240)
	)
	(segment
		(start 141.905462 149.3415)
		(end 141.442962 149.3415)
		(width 0.127)
		(layer "F.Cu")
		(net 240)
	)
	(segment
		(start 82.667962 155.3165)
		(end 84.021962 153.9625)
		(width 0.127)
		(layer "F.Cu")
		(net 240)
	)
	(segment
		(start 81.077961 155.316)
		(end 81.554961 155.316)
		(width 0.127)
		(layer "F.Cu")
		(net 240)
	)
	(segment
		(start 142.680462 149.3415)
		(end 143.067962 149.3415)
		(width 0.127)
		(layer "F.Cu")
		(net 240)
	)
	(segment
		(start 85.367962 153.720278)
		(end 85.367962 152.8995)
		(width 0.127)
		(layer "F.Cu")
		(net 240)
	)
	(segment
		(start 80.854959 155.092998)
		(end 81.077961 155.316)
		(width 0.127)
		(layer "F.Cu")
		(net 240)
	)
	(segment
		(start 143.067962 149.3415)
		(end 143.217962 149.1915)
		(width 0.127)
		(layer "F.Cu")
		(net 240)
	)
	(segment
		(start 85.12574 153.9625)
		(end 85.367962 153.720278)
		(width 0.127)
		(layer "F.Cu")
		(net 240)
	)
	(segment
		(start 81.555461 155.3165)
		(end 82.667962 155.3165)
		(width 0.127)
		(layer "F.Cu")
		(net 240)
	)
	(via
		(at 128.429462 160.13)
		(size 0.45)
		(drill 0.1)
		(layers "F.Cu" "B.Cu")
		(free yes)
		(net 240)
	)
	(via
		(at 143.217962 149.1915)
		(size 0.45)
		(drill 0.1)
		(layers "F.Cu" "B.Cu")
		(net 240)
	)
	(via
		(at 80.854959 154.88)
		(size 0.45)
		(drill 0.1)
		(layers "F.Cu" "B.Cu")
		(net 240)
	)
	(segment
		(start 128.657462 162.759618)
		(end 128.657462 167.174236)
		(width 0.127)
		(layer "In2.Cu")
		(net 240)
	)
	(segment
		(start 82.092962 157.7915)
		(end 82.092962 155.8915)
		(width 0.127)
		(layer "In2.Cu")
		(net 240)
	)
	(segment
		(start 81.081462 154.88)
		(end 80.854959 154.88)
		(width 0.127)
		(layer "In2.Cu")
		(net 240)
	)
	(segment
		(start 98.4254 160.0165)
		(end 84.317962 160.0165)
		(width 0.127)
		(layer "In2.Cu")
		(net 240)
	)
	(segment
		(start 127.104198 168.7275)
		(end 107.1364 168.7275)
		(width 0.127)
		(layer "In2.Cu")
		(net 240)
	)
	(segment
		(start 84.317962 160.0165)
		(end 82.092962 157.7915)
		(width 0.127)
		(layer "In2.Cu")
		(net 240)
	)
	(segment
		(start 107.1364 168.7275)
		(end 98.4254 160.0165)
		(width 0.127)
		(layer "In2.Cu")
		(net 240)
	)
	(segment
		(start 128.657462 167.174236)
		(end 127.104198 168.7275)
		(width 0.127)
		(layer "In2.Cu")
		(net 240)
	)
	(segment
		(start 128.429462 160.13)
		(end 128.429462 162.531618)
		(width 0.127)
		(layer "In2.Cu")
		(net 240)
	)
	(segment
		(start 82.092962 155.8915)
		(end 81.081462 154.88)
		(width 0.127)
		(layer "In2.Cu")
		(net 240)
	)
	(segment
		(start 128.429462 162.531618)
		(end 128.657462 162.759618)
		(width 0.127)
		(layer "In2.Cu")
		(net 240)
	)
	(segment
		(start 142.300462 150.099222)
		(end 143.208184 149.1915)
		(width 0.127)
		(layer "In3.Cu")
		(net 240)
	)
	(segment
		(start 136.868434 159.0005)
		(end 142.300462 153.568472)
		(width 0.127)
		(layer "In3.Cu")
		(net 240)
	)
	(segment
		(start 128.429462 160.13)
		(end 128.429462 159.160222)
		(width 0.127)
		(layer "In3.Cu")
		(net 240)
	)
	(segment
		(start 143.208184 149.1915)
		(end 143.217962 149.1915)
		(width 0.127)
		(layer "In3.Cu")
		(net 240)
	)
	(segment
		(start 128.429462 159.160222)
		(end 128.589184 159.0005)
		(width 0.127)
		(layer "In3.Cu")
		(net 240)
	)
	(segment
		(start 128.589184 159.0005)
		(end 136.868434 159.0005)
		(width 0.127)
		(layer "In3.Cu")
		(net 240)
	)
	(segment
		(start 142.300462 153.568472)
		(end 142.300462 150.099222)
		(width 0.127)
		(layer "In3.Cu")
		(net 240)
	)
	(segment
		(start 134.455462 149.6285)
		(end 134.880962 149.6285)
		(width 0.127)
		(layer "F.Cu")
		(net 241)
	)
	(segment
		(start 89.12158 154.120417)
		(end 89.192962 154.049035)
		(width 0.127)
		(layer "F.Cu")
		(net 241)
	)
	(segment
		(start 133.680462 149.6285)
		(end 133.129962 149.6285)
		(width 0.127)
		(layer "F.Cu")
		(net 241)
	)
	(segment
		(start 134.467962 149.6405)
		(end 133.693962 149.6405)
		(width 0.127)
		(layer "F.Cu")
		(net 241)
	)
	(segment
		(start 135.192962 148.8385)
		(end 135.565962 148.4655)
		(width 0.127)
		(layer "F.Cu")
		(net 241)
	)
	(segment
		(start 78.473961 155.716)
		(end 77.996961 155.716)
		(width 0.127)
		(layer "F.Cu")
		(net 241)
	)
	(segment
		(start 135.192962 149.3165)
		(end 135.192962 148.8385)
		(width 0.127)
		(layer "F.Cu")
		(net 241)
	)
	(segment
		(start 77.996961 155.716)
		(end 77.821461 155.8915)
		(width 0.127)
		(layer "F.Cu")
		(net 241)
	)
	(segment
		(start 135.565962 148.4655)
		(end 136.442962 148.4655)
		(width 0.127)
		(layer "F.Cu")
		(net 241)
	)
	(segment
		(start 134.880962 149.6285)
		(end 135.192962 149.3165)
		(width 0.127)
		(layer "F.Cu")
		(net 241)
	)
	(segment
		(start 77.821461 155.8915)
		(end 77.667962 155.8915)
		(width 0.127)
		(layer "F.Cu")
		(net 241)
	)
	(segment
		(start 89.192962 154.049035)
		(end 89.192962 152.9695)
		(width 0.127)
		(layer "F.Cu")
		(net 241)
	)
	(segment
		(start 133.129962 149.6285)
		(end 133.067962 149.5665)
		(width 0.127)
		(layer "F.Cu")
		(net 241)
	)
	(via
		(at 89.12158 154.120417)
		(size 0.45)
		(drill 0.1)
		(layers "F.Cu" "B.Cu")
		(net 241)
	)
	(via
		(at 133.067962 149.5665)
		(size 0.45)
		(drill 0.1)
		(layers "F.Cu" "B.Cu")
		(net 241)
	)
	(via
		(at 130.904962 149.683889)
		(size 0.45)
		(drill 0.1)
		(layers "F.Cu" "B.Cu")
		(net 241)
	)
	(via
		(at 77.667962 155.8915)
		(size 0.45)
		(drill 0.1)
		(layers "F.Cu" "B.Cu")
		(net 241)
	)
	(segment
		(start 132.950573 149.683889)
		(end 133.067962 149.5665)
		(width 0.127)
		(layer "B.Cu")
		(net 241)
	)
	(segment
		(start 130.904962 149.683889)
		(end 132.950573 149.683889)
		(width 0.127)
		(layer "B.Cu")
		(net 241)
	)
	(segment
		(start 88.844962 155.062118)
		(end 90.271344 156.4885)
		(width 0.127)
		(layer "In2.Cu")
		(net 241)
	)
	(segment
		(start 99.886748 156.4885)
		(end 108.597748 165.1995)
		(width 0.127)
		(layer "In2.Cu")
		(net 241)
	)
	(segment
		(start 108.597748 165.1995)
		(end 118.466344 165.1995)
		(width 0.127)
		(layer "In2.Cu")
		(net 241)
	)
	(segment
		(start 90.271344 156.4885)
		(end 99.886748 156.4885)
		(width 0.127)
		(layer "In2.Cu")
		(net 241)
	)
	(segment
		(start 130.389962 151.640882)
		(end 122.659962 159.370882)
		(width 0.127)
		(layer "In2.Cu")
		(net 241)
	)
	(segment
		(start 122.659962 159.370882)
		(end 122.659962 161.005882)
		(width 0.127)
		(layer "In2.Cu")
		(net 241)
	)
	(segment
		(start 130.389962 150.198889)
		(end 130.389962 151.640882)
		(width 0.127)
		(layer "In2.Cu")
		(net 241)
	)
	(segment
		(start 122.659962 161.005882)
		(end 118.466344 165.1995)
		(width 0.127)
		(layer "In2.Cu")
		(net 241)
	)
	(segment
		(start 88.844962 154.397035)
		(end 88.844962 155.062118)
		(width 0.127)
		(layer "In2.Cu")
		(net 241)
	)
	(segment
		(start 130.904962 149.683889)
		(end 130.389962 150.198889)
		(width 0.127)
		(layer "In2.Cu")
		(net 241)
	)
	(segment
		(start 89.12158 154.120417)
		(end 88.844962 154.397035)
		(width 0.127)
		(layer "In2.Cu")
		(net 241)
	)
	(segment
		(start 80.894962 155.8935)
		(end 77.669962 155.8935)
		(width 0.127)
		(layer "In3.Cu")
		(net 241)
	)
	(segment
		(start 81.767962 156.7665)
		(end 80.894962 155.8935)
		(width 0.127)
		(layer "In3.Cu")
		(net 241)
	)
	(segment
		(start 77.669962 155.8935)
		(end 77.667962 155.8915)
		(width 0.127)
		(layer "In3.Cu")
		(net 241)
	)
	(segment
		(start 89.12158 154.120417)
		(end 88.574045 154.120417)
		(width 0.127)
		(layer "In3.Cu")
		(net 241)
	)
	(segment
		(start 88.574045 154.120417)
		(end 85.927962 156.7665)
		(width 0.127)
		(layer "In3.Cu")
		(net 241)
	)
	(segment
		(start 85.927962 156.7665)
		(end 81.767962 156.7665)
		(width 0.127)
		(layer "In3.Cu")
		(net 241)
	)
	(segment
		(start 141.905462 149.8415)
		(end 141.442962 149.8415)
		(width 0.127)
		(layer "F.Cu")
		(net 242)
	)
	(segment
		(start 80.352579 155.182168)
		(end 80.465012 155.182168)
		(width 0.127)
		(layer "F.Cu")
		(net 242)
	)
	(segment
		(start 143.142962 149.8415)
		(end 143.217962 149.7665)
		(width 0.127)
		(layer "F.Cu")
		(net 242)
	)
	(segment
		(start 141.442962 149.8415)
		(end 141.066962 149.4655)
		(width 0.127)
		(layer "F.Cu")
		(net 242)
	)
	(segment
		(start 80.998844 155.716)
		(end 81.554961 155.716)
		(width 0.127)
		(layer "F.Cu")
		(net 242)
	)
	(segment
		(start 141.905462 149.8415)
		(end 142.680462 149.8415)
		(width 0.127)
		(layer "F.Cu")
		(net 242)
	)
	(segment
		(start 80.465012 155.182168)
		(end 80.998844 155.716)
		(width 0.127)
		(layer "F.Cu")
		(net 242)
	)
	(segment
		(start 142.680462 149.8415)
		(end 143.142962 149.8415)
		(width 0.127)
		(layer "F.Cu")
		(net 242)
	)
	(via
		(at 143.217962 149.7665)
		(size 0.45)
		(drill 0.1)
		(layers "F.Cu" "B.Cu")
		(net 242)
	)
	(via
		(at 128.867962 159.4165)
		(size 0.45)
		(drill 0.1)
		(layers "F.Cu" "B.Cu")
		(free yes)
		(net 242)
	)
	(via
		(at 80.352579 155.182168)
		(size 0.45)
		(drill 0.1)
		(layers "F.Cu" "B.Cu")
		(net 242)
	)
	(segment
		(start 128.909462 162.655236)
		(end 128.909462 167.278618)
		(width 0.127)
		(layer "In2.Cu")
		(net 242)
	)
	(segment
		(start 81.819962 155.974882)
		(end 81.819962 157.874882)
		(width 0.127)
		(layer "In2.Cu")
		(net 242)
	)
	(segment
		(start 80.352579 155.182168)
		(end 80.463911 155.2935)
		(width 0.127)
		(layer "In2.Cu")
		(net 242)
	)
	(segment
		(start 128.842962 159.4415)
		(end 128.842962 162.588736)
		(width 0.127)
		(layer "In2.Cu")
		(net 242)
	)
	(segment
		(start 81.527271 155.682191)
		(end 81.819962 155.974882)
		(width 0.127)
		(layer "In2.Cu")
		(net 242)
	)
	(segment
		(start 127.20858 168.9795)
		(end 107.032018 168.9795)
		(width 0.127)
		(layer "In2.Cu")
		(net 242)
	)
	(segment
		(start 98.321018 160.2685)
		(end 84.21358 160.2685)
		(width 0.127)
		(layer "In2.Cu")
		(net 242)
	)
	(segment
		(start 107.032018 168.9795)
		(end 98.321018 160.2685)
		(width 0.127)
		(layer "In2.Cu")
		(net 242)
	)
	(segment
		(start 81.13858 155.2935)
		(end 81.527271 155.682191)
		(width 0.127)
		(layer "In2.Cu")
		(net 242)
	)
	(segment
		(start 80.463911 155.2935)
		(end 81.13858 155.2935)
		(width 0.127)
		(layer "In2.Cu")
		(net 242)
	)
	(segment
		(start 128.842962 162.588736)
		(end 128.909462 162.655236)
		(width 0.127)
		(layer "In2.Cu")
		(net 242)
	)
	(segment
		(start 128.909462 167.278618)
		(end 127.20858 168.9795)
		(width 0.127)
		(layer "In2.Cu")
		(net 242)
	)
	(segment
		(start 84.21358 160.2685)
		(end 81.819962 157.874882)
		(width 0.127)
		(layer "In2.Cu")
		(net 242)
	)
	(segment
		(start 128.867962 159.4165)
		(end 128.842962 159.4415)
		(width 0.127)
		(layer "In2.Cu")
		(net 242)
	)
	(segment
		(start 128.999962 159.2845)
		(end 136.940816 159.2845)
		(width 0.127)
		(layer "In3.Cu")
		(net 242)
	)
	(segment
		(start 142.552462 150.432)
		(end 143.217962 149.7665)
		(width 0.127)
		(layer "In3.Cu")
		(net 242)
	)
	(segment
		(start 142.552462 153.672854)
		(end 142.552462 150.432)
		(width 0.127)
		(layer "In3.Cu")
		(net 242)
	)
	(segment
		(start 136.940816 159.2845)
		(end 142.552462 153.672854)
		(width 0.127)
		(layer "In3.Cu")
		(net 242)
	)
	(segment
		(start 128.867962 159.4165)
		(end 128.999962 159.2845)
		(width 0.127)
		(layer "In3.Cu")
		(net 242)
	)
	(segment
		(start 80.767962 155.8415)
		(end 81.041462 156.115)
		(width 0.127)
		(layer "F.Cu")
		(net 243)
	)
	(segment
		(start 141.905462 150.8425)
		(end 142.679462 150.8425)
		(width 0.127)
		(layer "F.Cu")
		(net 243)
	)
	(segment
		(start 141.568962 150.8425)
		(end 141.33858 150.612118)
		(width 0.127)
		(layer "F.Cu")
		(net 243)
	)
	(segment
		(start 79.856462 155.43)
		(end 80.267962 155.8415)
		(width 0.127)
		(layer "F.Cu")
		(net 243)
	)
	(segment
		(start 141.33858 150.612118)
		(end 141.33858 150.237118)
		(width 0.127)
		(layer "F.Cu")
		(net 243)
	)
	(segment
		(start 141.33858 150.237118)
		(end 141.065962 149.9645)
		(width 0.127)
		(layer "F.Cu")
		(net 243)
	)
	(segment
		(start 143.092962 150.8415)
		(end 143.217961 150.966499)
		(width 0.127)
		(layer "F.Cu")
		(net 243)
	)
	(segment
		(start 81.041462 156.115)
		(end 81.554961 156.115)
		(width 0.127)
		(layer "F.Cu")
		(net 243)
	)
	(segment
		(start 79.856462 154.88)
		(end 79.856462 155.43)
		(width 0.127)
		(layer "F.Cu")
		(net 243)
	)
	(segment
		(start 141.905462 150.8425)
		(end 141.568962 150.8425)
		(width 0.127)
		(layer "F.Cu")
		(net 243)
	)
	(segment
		(start 80.267962 155.8415)
		(end 80.767962 155.8415)
		(width 0.127)
		(layer "F.Cu")
		(net 243)
	)
	(segment
		(start 142.680462 150.8415)
		(end 143.167962 150.8415)
		(width 0.127)
		(layer "F.Cu")
		(net 243)
	)
	(via
		(at 79.856462 154.88)
		(size 0.45)
		(drill 0.1)
		(layers "F.Cu" "B.Cu")
		(net 243)
	)
	(via
		(at 143.217961 150.966499)
		(size 0.45)
		(drill 0.1)
		(layers "F.Cu" "B.Cu")
		(net 243)
	)
	(via
		(at 129.261462 160.1665)
		(size 0.45)
		(drill 0.1)
		(layers "F.Cu" "B.Cu")
		(free yes)
		(net 243)
	)
	(segment
		(start 129.161462 167.383)
		(end 129.161462 160.2665)
		(width 0.127)
		(layer "In2.Cu")
		(net 243)
	)
	(segment
		(start 129.161462 160.2665)
		(end 129.261462 160.1665)
		(width 0.127)
		(layer "In2.Cu")
		(net 243)
	)
	(segment
		(start 98.216636 160.5205)
		(end 106.927636 169.2315)
		(width 0.127)
		(layer "In2.Cu")
		(net 243)
	)
	(segment
		(start 80.922344 155.6645)
		(end 81.542962 156.285118)
		(width 0.127)
		(layer "In2.Cu")
		(net 243)
	)
	(segment
		(start 84.109198 160.5205)
		(end 98.216636 160.5205)
		(width 0.127)
		(layer "In2.Cu")
		(net 243)
	)
	(segment
		(start 81.542962 156.285118)
		(end 81.542962 157.954264)
		(width 0.127)
		(layer "In2.Cu")
		(net 243)
	)
	(segment
		(start 127.312962 169.2315)
		(end 129.161462 167.383)
		(width 0.127)
		(layer "In2.Cu")
		(net 243)
	)
	(segment
		(start 79.856462 155.27083)
		(end 80.250132 155.6645)
		(width 0.127)
		(layer "In2.Cu")
		(net 243)
	)
	(segment
		(start 81.542962 157.954264)
		(end 84.109198 160.5205)
		(width 0.127)
		(layer "In2.Cu")
		(net 243)
	)
	(segment
		(start 106.927636 169.2315)
		(end 127.312962 169.2315)
		(width 0.127)
		(layer "In2.Cu")
		(net 243)
	)
	(segment
		(start 79.856462 154.88)
		(end 79.856462 155.27083)
		(width 0.127)
		(layer "In2.Cu")
		(net 243)
	)
	(segment
		(start 80.250132 155.6645)
		(end 80.922344 155.6645)
		(width 0.127)
		(layer "In2.Cu")
		(net 243)
	)
	(segment
		(start 137.045198 159.5365)
		(end 142.804462 153.777236)
		(width 0.127)
		(layer "In3.Cu")
		(net 243)
	)
	(segment
		(start 142.804462 151.379998)
		(end 143.217961 150.966499)
		(width 0.127)
		(layer "In3.Cu")
		(net 243)
	)
	(segment
		(start 129.891462 159.5365)
		(end 137.045198 159.5365)
		(width 0.127)
		(layer "In3.Cu")
		(net 243)
	)
	(segment
		(start 129.261462 160.1665)
		(end 129.891462 159.5365)
		(width 0.127)
		(layer "In3.Cu")
		(net 243)
	)
	(segment
		(start 142.804462 153.777236)
		(end 142.804462 151.379998)
		(width 0.127)
		(layer "In3.Cu")
		(net 243)
	)
	(segment
		(start 77.143462 162.516)
		(end 78.473961 162.516)
		(width 0.127)
		(layer "F.Cu")
		(net 247)
	)
	(segment
		(start 77.540372 162.916)
		(end 77.201372 163.255)
		(width 0.127)
		(layer "F.Cu")
		(net 248)
	)
	(segment
		(start 76.734552 163.255)
		(end 76.436052 162.9565)
		(width 0.127)
		(layer "F.Cu")
		(net 248)
	)
	(segment
		(start 76.436052 162.9565)
		(end 76 162.9565)
		(width 0.127)
		(layer "F.Cu")
		(net 248)
	)
	(segment
		(start 78.473961 162.916)
		(end 77.540372 162.916)
		(width 0.127)
		(layer "F.Cu")
		(net 248)
	)
	(segment
		(start 77.201372 163.255)
		(end 76.734552 163.255)
		(width 0.127)
		(layer "F.Cu")
		(net 248)
	)
	(segment
		(start 80.973962 163.779646)
		(end 80.973962 163.019999)
		(width 0.127)
		(layer "F.Cu")
		(net 249)
	)
	(segment
		(start 80.973962 163.019999)
		(end 81.077961 162.916)
		(width 0.127)
		(layer "F.Cu")
		(net 249)
	)
	(segment
		(start 81.077961 162.916)
		(end 81.554961 162.916)
		(width 0.127)
		(layer "F.Cu")
		(net 249)
	)
	(segment
		(start 77.017962 166.1915)
		(end 76.692962 166.1915)
		(width 0.127)
		(layer "F.Cu")
		(net 249)
	)
	(segment
		(start 80.400962 166.8665)
		(end 77.692962 166.8665)
		(width 0.127)
		(layer "F.Cu")
		(net 249)
	)
	(segment
		(start 80.425962 166.8915)
		(end 80.400962 166.8665)
		(width 0.127)
		(layer "F.Cu")
		(net 249)
	)
	(segment
		(start 80.425962 166.8915)
		(end 80.425962 167.1995)
		(width 0.127)
		(layer "F.Cu")
		(net 249)
	)
	(segment
		(start 80.425962 167.1995)
		(end 82.269962 169.0435)
		(width 0.127)
		(layer "F.Cu")
		(net 249)
	)
	(segment
		(start 77.692962 166.8665)
		(end 77.017962 166.1915)
		(width 0.127)
		(layer "F.Cu")
		(net 249)
	)
	(segment
		(start 82.767962 169.0435)
		(end 82.269962 169.0435)
		(width 0.127)
		(layer "F.Cu")
		(net 249)
	)
	(segment
		(start 80.425962 164.327646)
		(end 80.425962 166.8915)
		(width 0.127)
		(layer "F.Cu")
		(net 249)
	)
	(segment
		(start 80.425962 164.327646)
		(end 80.973962 163.779646)
		(width 0.127)
		(layer "F.Cu")
		(net 249)
	)
	(segment
		(start 77.16158 163.6665)
		(end 77.51208 163.316)
		(width 0.127)
		(layer "F.Cu")
		(net 250)
	)
	(segment
		(start 76.417962 163.6665)
		(end 77.16158 163.6665)
		(width 0.127)
		(layer "F.Cu")
		(net 250)
	)
	(segment
		(start 141.727962 128.7335)
		(end 141.727962 129.1565)
		(width 0.2)
		(layer "F.Cu")
		(net 250)
	)
	(segment
		(start 141.727962 129.1565)
		(end 141.107962 129.7765)
		(width 0.2)
		(layer "F.Cu")
		(net 250)
	)
	(segment
		(start 77.51208 163.316)
		(end 78.473961 163.316)
		(width 0.127)
		(layer "F.Cu")
		(net 250)
	)
	(via
		(at 141.107962 129.7765)
		(size 0.45)
		(drill 0.1)
		(layers "F.Cu" "B.Cu")
		(net 250)
	)
	(via
		(at 76.417962 163.6665)
		(size 0.45)
		(drill 0.1)
		(layers "F.Cu" "B.Cu")
		(net 250)
	)
	(segment
		(start 86.63208 169.857)
		(end 100.493684 169.857)
		(width 0.127)
		(layer "In2.Cu")
		(net 250)
	)
	(segment
		(start 102.915184 172.2785)
		(end 128.612344 172.2785)
		(width 0.127)
		(layer "In2.Cu")
		(net 250)
	)
	(segment
		(start 80.588184 164.8965)
		(end 82.321684 166.63)
		(width 0.127)
		(layer "In2.Cu")
		(net 250)
	)
	(segment
		(start 132.469962 168.420882)
		(end 132.469962 156.53208)
		(width 0.127)
		(layer "In2.Cu")
		(net 250)
	)
	(segment
		(start 78.385947 164.424485)
		(end 78.857962 164.8965)
		(width 0.127)
		(layer "In2.Cu")
		(net 250)
	)
	(segment
		(start 141.727962 134.41672)
		(end 141.727962 130.3965)
		(width 0.127)
		(layer "In2.Cu")
		(net 250)
	)
	(segment
		(start 128.612344 172.2785)
		(end 132.469962 168.420882)
		(width 0.127)
		(layer "In2.Cu")
		(net 250)
	)
	(segment
		(start 100.493684 169.857)
		(end 102.915184 172.2785)
		(width 0.127)
		(layer "In2.Cu")
		(net 250)
	)
	(segment
		(start 82.321684 166.63)
		(end 83.40508 166.63)
		(width 0.127)
		(layer "In2.Cu")
		(net 250)
	)
	(segment
		(start 83.40508 166.63)
		(end 86.63208 169.857)
		(width 0.127)
		(layer "In2.Cu")
		(net 250)
	)
	(segment
		(start 140.24274 137.0765)
		(end 141.731463 135.587777)
		(width 0.127)
		(layer "In2.Cu")
		(net 250)
	)
	(segment
		(start 141.731463 135.587777)
		(end 141.731463 134.420221)
		(width 0.127)
		(layer "In2.Cu")
		(net 250)
	)
	(segment
		(start 141.731463 134.420221)
		(end 141.727962 134.41672)
		(width 0.127)
		(layer "In2.Cu")
		(net 250)
	)
	(segment
		(start 135.727962 150.0765)
		(end 135.727962 140.9965)
		(width 0.127)
		(layer "In2.Cu")
		(net 250)
	)
	(segment
		(start 141.727962 130.3965)
		(end 141.107962 129.7765)
		(width 0.127)
		(layer "In2.Cu")
		(net 250)
	)
	(segment
		(start 135.041462 153.96058)
		(end 135.041462 150.763)
		(width 0.127)
		(layer "In2.Cu")
		(net 250)
	)
	(segment
		(start 135.727962 140.9965)
		(end 139.647962 137.0765)
		(width 0.127)
		(layer "In2.Cu")
		(net 250)
	)
	(segment
		(start 76.417962 163.6765)
		(end 77.165947 164.424485)
		(width 0.127)
		(layer "In2.Cu")
		(net 250)
	)
	(segment
		(start 135.041462 150.763)
		(end 135.727962 150.0765)
		(width 0.127)
		(layer "In2.Cu")
		(net 250)
	)
	(segment
		(start 77.165947 164.424485)
		(end 78.385947 164.424485)
		(width 0.127)
		(layer "In2.Cu")
		(net 250)
	)
	(segment
		(start 139.647962 137.0765)
		(end 140.24274 137.0765)
		(width 0.127)
		(layer "In2.Cu")
		(net 250)
	)
	(segment
		(start 76.417962 163.6665)
		(end 76.417962 163.6765)
		(width 0.127)
		(layer "In2.Cu")
		(net 250)
	)
	(segment
		(start 78.857962 164.8965)
		(end 80.588184 164.8965)
		(width 0.127)
		(layer "In2.Cu")
		(net 250)
	)
	(segment
		(start 132.469962 156.53208)
		(end 135.041462 153.96058)
		(width 0.127)
		(layer "In2.Cu")
		(net 250)
	)
	(segment
		(start 134.892962 148.1665)
		(end 135.593962 147.4655)
		(width 0.127)
		(layer "F.Cu")
		(net 251)
	)
	(segment
		(start 81.554961 163.316)
		(end 82.284462 163.316)
		(width 0.15)
		(layer "F.Cu")
		(net 251)
	)
	(segment
		(start 133.680462 148.1665)
		(end 133.217961 148.1665)
		(width 0.127)
		(layer "F.Cu")
		(net 251)
	)
	(segment
		(start 135.593962 147.4655)
		(end 136.442962 147.4655)
		(width 0.127)
		(layer "F.Cu")
		(net 251)
	)
	(segment
		(start 134.455462 148.1665)
		(end 134.892962 148.1665)
		(width 0.127)
		(layer "F.Cu")
		(net 251)
	)
	(segment
		(start 82.284462 163.316)
		(end 82.297962 163.3025)
		(width 0.15)
		(layer "F.Cu")
		(net 251)
	)
	(segment
		(start 133.217961 148.1665)
		(end 133.067961 148.3165)
		(width 0.127)
		(layer "F.Cu")
		(net 251)
	)
	(segment
		(start 133.692962 148.1665)
		(end 134.467962 148.1665)
		(width 0.127)
		(layer "F.Cu")
		(net 251)
	)
	(via
		(at 82.297962 163.3025)
		(size 0.45)
		(drill 0.1)
		(layers "F.Cu" "B.Cu")
		(net 251)
	)
	(via
		(at 133.067961 148.3165)
		(size 0.45)
		(drill 0.1)
		(layers "F.Cu" "B.Cu")
		(net 251)
	)
	(segment
		(start 102.72049 168.26)
		(end 105.97149 171.511)
		(width 0.15)
		(layer "In2.Cu")
		(net 251)
	)
	(segment
		(start 133.904462 152.467354)
		(end 133.904462 149.028)
		(width 0.15)
		(layer "In2.Cu")
		(net 251)
	)
	(segment
		(start 131.702462 168.102972)
		(end 131.702462 154.672972)
		(width 0.15)
		(layer "In2.Cu")
		(net 251)
	)
	(segment
		(start 82.297962 163.987472)
		(end 86.57049 168.26)
		(width 0.15)
		(layer "In2.Cu")
		(net 251)
	)
	(segment
		(start 82.297962 163.3025)
		(end 82.297962 163.987472)
		(width 0.15)
		(layer "In2.Cu")
		(net 251)
	)
	(segment
		(start 133.904462 149.028)
		(end 133.192962 148.3165)
		(width 0.15)
		(layer "In2.Cu")
		(net 251)
	)
	(segment
		(start 128.294434 171.511)
		(end 131.702462 168.102972)
		(width 0.15)
		(layer "In2.Cu")
		(net 251)
	)
	(segment
		(start 132.584462 153.790972)
		(end 132.584462 153.787354)
		(width 0.15)
		(layer "In2.Cu")
		(net 251)
	)
	(segment
		(start 131.702462 154.672972)
		(end 132.584462 153.790972)
		(width 0.15)
		(layer "In2.Cu")
		(net 251)
	)
	(segment
		(start 133.192962 148.3165)
		(end 133.067961 148.3165)
		(width 0.15)
		(layer "In2.Cu")
		(net 251)
	)
	(segment
		(start 86.57049 168.26)
		(end 102.72049 168.26)
		(width 0.15)
		(layer "In2.Cu")
		(net 251)
	)
	(segment
		(start 105.97149 171.511)
		(end 128.294434 171.511)
		(width 0.15)
		(layer "In2.Cu")
		(net 251)
	)
	(segment
		(start 132.584462 153.787354)
		(end 133.904462 152.467354)
		(width 0.15)
		(layer "In2.Cu")
		(net 251)
	)
	(segment
		(start 77.468462 163.716)
		(end 78.473961 163.716)
		(width 0.127)
		(layer "F.Cu")
		(net 252)
	)
	(segment
		(start 68.192962 145.4415)
		(end 67.742962 145.4415)
		(width 0.127)
		(layer "F.Cu")
		(net 252)
	)
	(segment
		(start 67.742962 145.4415)
		(end 67.344462 145.84)
		(width 0.127)
		(layer "F.Cu")
		(net 252)
	)
	(segment
		(start 75.931462 157.848439)
		(end 75.931462 161.3665)
		(width 0.127)
		(layer "F.Cu")
		(net 252)
	)
	(segment
		(start 75.931462 161.3665)
		(end 75.431462 161.8665)
		(width 0.127)
		(layer "F.Cu")
		(net 252)
	)
	(segment
		(start 75.497962 156.2465)
		(end 76.006462 156.755)
		(width 0.127)
		(layer "F.Cu")
		(net 252)
	)
	(segment
		(start 74.950804 154.2435)
		(end 75.1035 154.2435)
		(width 0.127)
		(layer "F.Cu")
		(net 252)
	)
	(segment
		(start 67.344462 146.343)
		(end 67.763462 146.762)
		(width 0.127)
		(layer "F.Cu")
		(net 252)
	)
	(segment
		(start 67.344462 145.84)
		(end 67.344462 146.343)
		(width 0.127)
		(layer "F.Cu")
		(net 252)
	)
	(segment
		(start 70.296108 146.762)
		(end 72.201462 148.667355)
		(width 0.127)
		(layer "F.Cu")
		(net 252)
	)
	(segment
		(start 68.772962 144.8615)
		(end 68.192962 145.4415)
		(width 0.127)
		(layer "F.Cu")
		(net 252)
	)
	(segment
		(start 74.755849 154.243501)
		(end 74.950804 154.2435)
		(width 0.127)
		(layer "F.Cu")
		(net 252)
	)
	(segment
		(start 75.431462 163.558292)
		(end 75.95517 164.082)
		(width 0.127)
		(layer "F.Cu")
		(net 252)
	)
	(segment
		(start 75.1035 154.2435)
		(end 75.497962 154.637962)
		(width 0.127)
		(layer "F.Cu")
		(net 252)
	)
	(segment
		(start 72.201462 148.667355)
		(end 72.201462 151.908372)
		(width 0.127)
		(layer "F.Cu")
		(net 252)
	)
	(segment
		(start 75.95517 164.082)
		(end 77.102462 164.082)
		(width 0.127)
		(layer "F.Cu")
		(net 252)
	)
	(segment
		(start 68.772962 143.9065)
		(end 68.772962 144.8615)
		(width 0.127)
		(layer "F.Cu")
		(net 252)
	)
	(segment
		(start 75.497962 154.637962)
		(end 75.497962 156.2465)
		(width 0.127)
		(layer "F.Cu")
		(net 252)
	)
	(segment
		(start 72.201462 151.908372)
		(end 74.381554 154.088464)
		(width 0.127)
		(layer "F.Cu")
		(net 252)
	)
	(segment
		(start 76.006462 157.773439)
		(end 75.931462 157.848439)
		(width 0.127)
		(layer "F.Cu")
		(net 252)
	)
	(segment
		(start 75.431462 161.8665)
		(end 75.431462 163.558292)
		(width 0.127)
		(layer "F.Cu")
		(net 252)
	)
	(segment
		(start 77.102462 164.082)
		(end 77.468462 163.716)
		(width 0.127)
		(layer "F.Cu")
		(net 252)
	)
	(segment
		(start 76.006462 156.755)
		(end 76.006462 157.773439)
		(width 0.127)
		(layer "F.Cu")
		(net 252)
	)
	(segment
		(start 67.763462 146.762)
		(end 70.296108 146.762)
		(width 0.127)
		(layer "F.Cu")
		(net 252)
	)
	(arc
		(start 74.381554 154.088464)
		(mid 74.553282 154.203209)
		(end 74.755849 154.243501)
		(width 0.127)
		(layer "F.Cu")
		(net 252)
	)
	(segment
		(start 135.029962 143.1785)
		(end 135.317962 143.4665)
		(width 0.127)
		(layer "F.Cu")
		(net 253)
	)
	(segment
		(start 133.067961 142.9665)
		(end 133.279961 143.1785)
		(width 0.127)
		(layer "F.Cu")
		(net 253)
	)
	(segment
		(start 134.467462 143.1785)
		(end 135.029962 143.1785)
		(width 0.127)
		(layer "F.Cu")
		(net 253)
	)
	(segment
		(start 82.722962 163.716)
		(end 81.554961 163.716)
		(width 0.127)
		(layer "F.Cu")
		(net 253)
	)
	(segment
		(start 133.692962 143.1915)
		(end 134.467962 143.1915)
		(width 0.127)
		(layer "F.Cu")
		(net 253)
	)
	(segment
		(start 135.317962 143.4665)
		(end 136.442962 143.4665)
		(width 0.127)
		(layer "F.Cu")
		(net 253)
	)
	(segment
		(start 133.692462 143.1785)
		(end 133.279961 143.1785)
		(width 0.127)
		(layer "F.Cu")
		(net 253)
	)
	(via
		(at 82.722962 163.716)
		(size 0.45)
		(drill 0.1)
		(layers "F.Cu" "B.Cu")
		(net 253)
	)
	(via
		(at 133.067961 142.9665)
		(size 0.45)
		(drill 0.1)
		(layers "F.Cu" "B.Cu")
		(net 253)
	)
	(via
		(at 133.417962 152.2165)
		(size 0.45)
		(drill 0.1)
		(layers "F.Cu" "B.Cu")
		(net 253)
	)
	(segment
		(start 132.320962 153.678208)
		(end 132.320962 153.681827)
		(width 0.127)
		(layer "In2.Cu")
		(net 253)
	)
	(segment
		(start 131.438962 154.563827)
		(end 131.438962 167.993826)
		(width 0.127)
		(layer "In2.Cu")
		(net 253)
	)
	(segment
		(start 128.185288 171.2475)
		(end 106.080636 171.2475)
		(width 0.127)
		(layer "In2.Cu")
		(net 253)
	)
	(segment
		(start 133.417962 152.2165)
		(end 133.417962 152.581208)
		(width 0.127)
		(layer "In2.Cu")
		(net 253)
	)
	(segment
		(start 133.417962 152.581208)
		(end 132.320962 153.678208)
		(width 0.127)
		(layer "In2.Cu")
		(net 253)
	)
	(segment
		(start 131.438962 167.993826)
		(end 128.185288 171.2475)
		(width 0.127)
		(layer "In2.Cu")
		(net 253)
	)
	(segment
		(start 106.080636 171.2475)
		(end 102.829636 167.9965)
		(width 0.127)
		(layer "In2.Cu")
		(net 253)
	)
	(segment
		(start 102.829636 167.9965)
		(end 86.679636 167.9965)
		(width 0.127)
		(layer "In2.Cu")
		(net 253)
	)
	(segment
		(start 86.679636 167.9965)
		(end 82.722962 164.039826)
		(width 0.127)
		(layer "In2.Cu")
		(net 253)
	)
	(segment
		(start 82.722962 164.039826)
		(end 82.722962 163.716)
		(width 0.127)
		(layer "In2.Cu")
		(net 253)
	)
	(segment
		(start 132.320962 153.681827)
		(end 131.438962 154.563827)
		(width 0.127)
		(layer "In2.Cu")
		(net 253)
	)
	(segment
		(start 133.481462 143.380001)
		(end 133.067961 142.9665)
		(width 0.127)
		(layer "In3.Cu")
		(net 253)
	)
	(segment
		(start 133.481462 152.153)
		(end 133.481462 143.380001)
		(width 0.127)
		(layer "In3.Cu")
		(net 253)
	)
	(segment
		(start 133.417962 152.2165)
		(end 133.481462 152.153)
		(width 0.127)
		(layer "In3.Cu")
		(net 253)
	)
	(segment
		(start 78.473961 164.117)
		(end 77.514372 164.117)
		(width 0.127)
		(layer "F.Cu")
		(net 254)
	)
	(segment
		(start 78.899462 164.117)
		(end 78.473961 164.117)
		(width 0.127)
		(layer "F.Cu")
		(net 254)
	)
	(segment
		(start 77.514372 164.117)
		(end 76.939872 164.6915)
		(width 0.127)
		(layer "F.Cu")
		(net 254)
	)
	(segment
		(start 79.256462 164.474)
		(end 78.899462 164.117)
		(width 0.127)
		(layer "F.Cu")
		(net 254)
	)
	(via
		(at 79.256462 164.474)
		(size 0.45)
		(drill 0.1)
		(layers "F.Cu" "B.Cu")
		(net 254)
	)
	(segment
		(start 84.452962 164.1365)
		(end 84.452962 165.0965)
		(width 0.127)
		(layer "B.Cu")
		(net 254)
	)
	(segment
		(start 79.878962 165.0965)
		(end 84.452962 165.0965)
		(width 0.127)
		(layer "B.Cu")
		(net 254)
	)
	(segment
		(start 79.256462 164.474)
		(end 79.878962 165.0965)
		(width 0.127)
		(layer "B.Cu")
		(net 254)
	)
	(segment
		(start 78.507962 167.2165)
		(end 79.532962 168.2415)
		(width 0.127)
		(layer "F.Cu")
		(net 255)
	)
	(segment
		(start 79.140962 168.6335)
		(end 79.532962 168.2415)
		(width 0.127)
		(layer "F.Cu")
		(net 255)
	)
	(segment
		(start 79.140962 169.8415)
		(end 79.140962 168.6335)
		(width 0.127)
		(layer "F.Cu")
		(net 255)
	)
	(segment
		(start 77.822997 164.517)
		(end 78.473961 164.517)
		(width 0.127)
		(layer "F.Cu")
		(net 255)
	)
	(segment
		(start 77.502012 164.837985)
		(end 77.822997 164.517)
		(width 0.127)
		(layer "F.Cu")
		(net 255)
	)
	(segment
		(start 76.692962 167.2165)
		(end 78.507962 167.2165)
		(width 0.127)
		(layer "F.Cu")
		(net 255)
	)
	(via
		(at 77.502012 164.837985)
		(size 0.45)
		(drill 0.1)
		(layers "F.Cu" "B.Cu")
		(net 255)
	)
	(via
		(at 76.692962 167.2165)
		(size 0.45)
		(drill 0.1)
		(layers "F.Cu" "B.Cu")
		(net 255)
	)
	(segment
		(start 77.092962 165.247035)
		(end 77.502012 164.837985)
		(width 0.127)
		(layer "B.Cu")
		(net 255)
	)
	(segment
		(start 76.692962 167.2165)
		(end 77.092962 166.8165)
		(width 0.127)
		(layer "B.Cu")
		(net 255)
	)
	(segment
		(start 77.092962 166.8165)
		(end 77.092962 165.247035)
		(width 0.127)
		(layer "B.Cu")
		(net 255)
	)
	(segment
		(start 111.692962 147.2665)
		(end 112.042462 146.917)
		(width 0.127)
		(layer "F.Cu")
		(net 256)
	)
	(segment
		(start 112.042462 146.917)
		(end 112.473961 146.917)
		(width 0.127)
		(layer "F.Cu")
		(net 256)
	)
	(segment
		(start 111.117962 147.2665)
		(end 111.692962 147.2665)
		(width 0.127)
		(layer "F.Cu")
		(net 256)
	)
	(segment
		(start 110.742962 146.8915)
		(end 111.117962 147.2665)
		(width 0.127)
		(layer "F.Cu")
		(net 256)
	)
	(segment
		(start 112.473961 153.318)
		(end 111.919782 153.318)
		(width 0.18)
		(layer "F.Cu")
		(net 257)
	)
	(segment
		(start 109.467962 153.5665)
		(end 108.867962 153.5665)
		(width 0.18)
		(layer "F.Cu")
		(net 257)
	)
	(segment
		(start 108.867962 153.5665)
		(end 108.592962 153.2915)
		(width 0.18)
		(layer "F.Cu")
		(net 257)
	)
	(segment
		(start 111.919782 153.318)
		(end 111.394282 153.8435)
		(width 0.18)
		(layer "F.Cu")
		(net 257)
	)
	(segment
		(start 109.940962 153.5665)
		(end 110.217962 153.8435)
		(width 0.18)
		(layer "F.Cu")
		(net 257)
	)
	(segment
		(start 108.592962 153.2915)
		(end 108.592962 152.6915)
		(width 0.18)
		(layer "F.Cu")
		(net 257)
	)
	(segment
		(start 108.592962 152.8415)
		(end 108.592962 152.6915)
		(width 0.18)
		(layer "F.Cu")
		(net 257)
	)
	(segment
		(start 111.394282 153.8435)
		(end 110.217962 153.8435)
		(width 0.18)
		(layer "F.Cu")
		(net 257)
	)
	(segment
		(start 109.467962 153.5665)
		(end 109.940962 153.5665)
		(width 0.18)
		(layer "F.Cu")
		(net 257)
	)
	(segment
		(start 107.792962 149.2415)
		(end 108.567962 148.4665)
		(width 0.18)
		(layer "F.Cu")
		(net 258)
	)
	(segment
		(start 109.004134 154.1565)
		(end 107.792962 152.945328)
		(width 0.18)
		(layer "F.Cu")
		(net 258)
	)
	(segment
		(start 111.952117 153.717)
		(end 111.512617 154.1565)
		(width 0.18)
		(layer "F.Cu")
		(net 258)
	)
	(segment
		(start 112.473961 153.717)
		(end 111.952117 153.717)
		(width 0.18)
		(layer "F.Cu")
		(net 258)
	)
	(segment
		(start 107.792962 152.945328)
		(end 107.792962 149.2415)
		(width 0.18)
		(layer "F.Cu")
		(net 258)
	)
	(segment
		(start 111.512617 154.1565)
		(end 109.004134 154.1565)
		(width 0.18)
		(layer "F.Cu")
		(net 258)
	)
	(segment
		(start 108.567962 148.4665)
		(end 108.567962 147.7665)
		(width 0.18)
		(layer "F.Cu")
		(net 258)
	)
	(segment
		(start 108.567962 147.7665)
		(end 108.867962 147.4665)
		(width 0.18)
		(layer "F.Cu")
		(net 258)
	)
	(segment
		(start 111.638952 154.4615)
		(end 111.983453 154.117)
		(width 0.18)
		(layer "F.Cu")
		(net 259)
	)
	(segment
		(start 107.417962 153.001663)
		(end 108.877799 154.4615)
		(width 0.18)
		(layer "F.Cu")
		(net 259)
	)
	(segment
		(start 107.417962 150.9665)
		(end 107.417962 153.001663)
		(width 0.18)
		(layer "F.Cu")
		(net 259)
	)
	(segment
		(start 108.877799 154.4615)
		(end 111.638952 154.4615)
		(width 0.18)
		(layer "F.Cu")
		(net 259)
	)
	(segment
		(start 107.042962 150.5915)
		(end 107.417962 150.9665)
		(width 0.18)
		(layer "F.Cu")
		(net 259)
	)
	(segment
		(start 105.942962 150.5915)
		(end 107.042962 150.5915)
		(width 0.18)
		(layer "F.Cu")
		(net 259)
	)
	(segment
		(start 111.983453 154.117)
		(end 112.473961 154.117)
		(width 0.18)
		(layer "F.Cu")
		(net 259)
	)
	(segment
		(start 112.015788 154.516)
		(end 112.473961 154.516)
		(width 0.18)
		(layer "F.Cu")
		(net 260)
	)
	(segment
		(start 106.017962 154.7665)
		(end 106.6835 154.7665)
		(width 0.18)
		(layer "F.Cu")
		(net 260)
	)
	(segment
		(start 106.95 154.5)
		(end 107.55 154.5)
		(width 0.18)
		(layer "F.Cu")
		(net 260)
	)
	(segment
		(start 107.55 154.5)
		(end 107.8165 154.7665)
		(width 0.18)
		(layer "F.Cu")
		(net 260)
	)
	(segment
		(start 107.8165 154.7665)
		(end 111.765288 154.7665)
		(width 0.18)
		(layer "F.Cu")
		(net 260)
	)
	(segment
		(start 111.765288 154.7665)
		(end 112.015788 154.516)
		(width 0.18)
		(layer "F.Cu")
		(net 260)
	)
	(segment
		(start 106.6835 154.7665)
		(end 106.95 154.5)
		(width 0.18)
		(layer "F.Cu")
		(net 260)
	)
	(segment
		(start 113.173963 154.8665)
		(end 113.001461 154.8665)
		(width 0.127)
		(layer "F.Cu")
		(net 261)
	)
	(segment
		(start 112.950961 154.917)
		(end 112.473961 154.917)
		(width 0.127)
		(layer "F.Cu")
		(net 261)
	)
	(segment
		(start 113.001461 154.8665)
		(end 112.950961 154.917)
		(width 0.127)
		(layer "F.Cu")
		(net 261)
	)
	(via
		(at 113.173963 154.8665)
		(size 0.45)
		(drill 0.1)
		(layers "F.Cu" "B.Cu")
		(net 261)
	)
	(via
		(at 110.592962 115.1415)
		(size 0.45)
		(drill 0.1)
		(layers "F.Cu" "B.Cu")
		(net 261)
	)
	(segment
		(start 110.592962 115.1415)
		(end 110.592962 116.328)
		(width 0.127)
		(layer "B.Cu")
		(net 261)
	)
	(segment
		(start 110.337962 118.044823)
		(end 110.337962 118.4765)
		(width 0.15)
		(layer "B.Cu")
		(net 261)
	)
	(segment
		(start 110.592962 117.789823)
		(end 110.337962 118.044823)
		(width 0.15)
		(layer "B.Cu")
		(net 261)
	)
	(segment
		(start 110.592962 117.104)
		(end 110.592962 117.789823)
		(width 0.15)
		(layer "B.Cu")
		(net 261)
	)
	(segment
		(start 110.593962 116.329)
		(end 110.593962 117.103)
		(width 0.127)
		(layer "B.Cu")
		(net 261)
	)
	(segment
		(start 110.790962 124.812118)
		(end 109.992962 125.610118)
		(width 0.127)
		(layer "In2.Cu")
		(net 261)
	)
	(segment
		(start 110.592962 115.1415)
		(end 110.592962 118.4165)
		(width 0.127)
		(layer "In2.Cu")
		(net 261)
	)
	(segment
		(start 108.761462 121.723618)
		(end 110.790962 123.753118)
		(width 0.127)
		(layer "In2.Cu")
		(net 261)
	)
	(segment
		(start 109.992962 125.610118)
		(end 109.992962 146.254264)
		(width 0.127)
		(layer "In2.Cu")
		(net 261)
	)
	(segment
		(start 110.592962 118.4165)
		(end 108.761462 120.248)
		(width 0.127)
		(layer "In2.Cu")
		(net 261)
	)
	(segment
		(start 109.992962 146.254264)
		(end 107.915962 148.331264)
		(width 0.127)
		(layer "In2.Cu")
		(net 261)
	)
	(segment
		(start 107.915962 148.331264)
		(end 107.915962 149.545882)
		(width 0.127)
		(layer "In2.Cu")
		(net 261)
	)
	(segment
		(start 110.790962 123.753118)
		(end 110.790962 124.812118)
		(width 0.127)
		(layer "In2.Cu")
		(net 261)
	)
	(segment
		(start 113.173963 154.803883)
		(end 113.173963 154.8665)
		(width 0.127)
		(layer "In2.Cu")
		(net 261)
	)
	(segment
		(start 108.761462 120.248)
		(end 108.761462 121.723618)
		(width 0.127)
		(layer "In2.Cu")
		(net 261)
	)
	(segment
		(start 107.915962 149.545882)
		(end 113.173963 154.803883)
		(width 0.127)
		(layer "In2.Cu")
		(net 261)
	)
	(segment
		(start 113.748966 154.8665)
		(end 113.748966 155.035496)
		(width 0.127)
		(layer "F.Cu")
		(net 262)
	)
	(segment
		(start 113.748966 155.035496)
		(end 113.481462 155.303)
		(width 0.127)
		(layer "F.Cu")
		(net 262)
	)
	(segment
		(start 113.481462 155.303)
		(end 112.486961 155.303)
		(width 0.127)
		(layer "F.Cu")
		(net 262)
	)
	(via
		(at 113.748966 154.8665)
		(size 0.45)
		(drill 0.1)
		(layers "F.Cu" "B.Cu")
		(net 262)
	)
	(via
		(at 111.067962 115.4915)
		(size 0.45)
		(drill 0.1)
		(layers "F.Cu" "B.Cu")
		(net 262)
	)
	(segment
		(start 110.975462 118.4765)
		(end 110.975462 117.804)
		(width 0.15)
		(layer "B.Cu")
		(net 262)
	)
	(segment
		(start 110.975462 117.804)
		(end 111.092962 117.6865)
		(width 0.15)
		(layer "B.Cu")
		(net 262)
	)
	(segment
		(start 111.092962 116.329)
		(end 111.092962 117.104)
		(width 0.127)
		(layer "B.Cu")
		(net 262)
	)
	(segment
		(start 111.092962 117.6865)
		(end 111.092962 117.104)
		(width 0.15)
		(layer "B.Cu")
		(net 262)
	)
	(segment
		(start 111.067962 115.4915)
		(end 111.092962 115.5165)
		(width 0.127)
		(layer "B.Cu")
		(net 262)
	)
	(segment
		(start 111.092962 115.5165)
		(end 111.092962 116.329)
		(width 0.127)
		(layer "B.Cu")
		(net 262)
	)
	(segment
		(start 112.767962 153.8665)
		(end 113.748966 154.847504)
		(width 0.127)
		(layer "In2.Cu")
		(net 262)
	)
	(segment
		(start 110.244962 146.358646)
		(end 108.167962 148.435646)
		(width 0.127)
		(layer "In2.Cu")
		(net 262)
	)
	(segment
		(start 112.592962 153.8665)
		(end 112.767962 153.8665)
		(width 0.127)
		(layer "In2.Cu")
		(net 262)
	)
	(segment
		(start 108.167962 149.4415)
		(end 112.592962 153.8665)
		(width 0.127)
		(layer "In2.Cu")
		(net 262)
	)
	(segment
		(start 109.013462 121.619236)
		(end 111.042962 123.648736)
		(width 0.127)
		(layer "In2.Cu")
		(net 262)
	)
	(segment
		(start 111.067962 115.4915)
		(end 110.844962 115.7145)
		(width 0.127)
		(layer "In2.Cu")
		(net 262)
	)
	(segment
		(start 108.167962 148.435646)
		(end 108.167962 149.4415)
		(width 0.127)
		(layer "In2.Cu")
		(net 262)
	)
	(segment
		(start 110.844962 115.7145)
		(end 110.844962 118.520882)
		(width 0.127)
		(layer "In2.Cu")
		(net 262)
	)
	(segment
		(start 110.844962 118.520882)
		(end 109.013462 120.352382)
		(width 0.127)
		(layer "In2.Cu")
		(net 262)
	)
	(segment
		(start 109.013462 120.352382)
		(end 109.013462 121.619236)
		(width 0.127)
		(layer "In2.Cu")
		(net 262)
	)
	(segment
		(start 111.042962 123.648736)
		(end 111.042962 124.9165)
		(width 0.127)
		(layer "In2.Cu")
		(net 262)
	)
	(segment
		(start 113.748966 154.847504)
		(end 113.748966 154.8665)
		(width 0.127)
		(layer "In2.Cu")
		(net 262)
	)
	(segment
		(start 110.244962 125.7145)
		(end 110.244962 146.358646)
		(width 0.127)
		(layer "In2.Cu")
		(net 262)
	)
	(segment
		(start 111.042962 124.9165)
		(end 110.244962 125.7145)
		(width 0.127)
		(layer "In2.Cu")
		(net 262)
	)
	(segment
		(start 128.269462 168.9905)
		(end 126.9395 168.9905)
		(width 0.254)
		(layer "B.Cu")
		(net 263)
	)
	(segment
		(start 126.9395 168.9905)
		(end 126.88 169.05)
		(width 0.254)
		(layer "B.Cu")
		(net 263)
	)
	(segment
		(start 126.88 170)
		(end 126.88 169.05)
		(width 0.254)
		(layer "B.Cu")
		(net 263)
	)
	(segment
		(start 111.627962 162.9435)
		(end 111.627962 164.148001)
		(width 0.127)
		(layer "F.Cu")
		(net 266)
	)
	(segment
		(start 111.996961 164.517)
		(end 112.473961 164.517)
		(width 0.127)
		(layer "F.Cu")
		(net 266)
	)
	(segment
		(start 111.627962 164.148001)
		(end 111.996961 164.517)
		(width 0.127)
		(layer "F.Cu")
		(net 266)
	)
	(via
		(at 109.092962 115.4915)
		(size 0.45)
		(drill 0.1)
		(layers "F.Cu" "B.Cu")
		(net 266)
	)
	(via
		(at 111.627962 162.9435)
		(size 0.45)
		(drill 0.1)
		(layers "F.Cu" "B.Cu")
		(net 266)
	)
	(segment
		(start 109.092962 117.6765)
		(end 109.092962 117.104)
		(width 0.15)
		(layer "B.Cu")
		(net 266)
	)
	(segment
		(start 109.092962 115.4915)
		(end 109.092962 116.329)
		(width 0.127)
		(layer "B.Cu")
		(net 266)
	)
	(segment
		(start 109.200462 118.4765)
		(end 109.200462 117.784)
		(width 0.15)
		(layer "B.Cu")
		(net 266)
	)
	(segment
		(start 109.092962 117.104)
		(end 109.092962 116.329)
		(width 0.15)
		(layer "B.Cu")
		(net 266)
	)
	(segment
		(start 109.200462 117.784)
		(end 109.092962 117.6765)
		(width 0.15)
		(layer "B.Cu")
		(net 266)
	)
	(segment
		(start 109.092962 115.4915)
		(end 109.092962 118.9915)
		(width 0.127)
		(layer "In2.Cu")
		(net 266)
	)
	(segment
		(start 109.488962 146.0455)
		(end 107.411962 148.1225)
		(width 0.127)
		(layer "In2.Cu")
		(net 266)
	)
	(segment
		(start 110.286962 123.99818)
		(end 110.286962 124.603354)
		(width 0.127)
		(layer "In2.Cu")
		(net 266)
	)
	(segment
		(start 109.22 162.44)
		(end 111.377962 162.44)
		(width 0.127)
		(layer "In2.Cu")
		(net 266)
	)
	(segment
		(start 109.488962 125.401354)
		(end 109.488962 146.0455)
		(width 0.127)
		(layer "In2.Cu")
		(net 266)
	)
	(segment
		(start 107.667962 121.37918)
		(end 110.286962 123.99818)
		(width 0.127)
		(layer "In2.Cu")
		(net 266)
	)
	(segment
		(start 111.627962 162.69)
		(end 111.627962 162.9435)
		(width 0.127)
		(layer "In2.Cu")
		(net 266)
	)
	(segment
		(start 105.02 158.24)
		(end 109.22 162.44)
		(width 0.127)
		(layer "In2.Cu")
		(net 266)
	)
	(segment
		(start 105.02 152.283462)
		(end 105.02 158.24)
		(width 0.127)
		(layer "In2.Cu")
		(net 266)
	)
	(segment
		(start 107.411962 148.1225)
		(end 107.411962 149.8915)
		(width 0.127)
		(layer "In2.Cu")
		(net 266)
	)
	(segment
		(start 107.667962 120.4165)
		(end 107.667962 121.37918)
		(width 0.127)
		(layer "In2.Cu")
		(net 266)
	)
	(segment
		(start 111.377962 162.44)
		(end 111.627962 162.69)
		(width 0.127)
		(layer "In2.Cu")
		(net 266)
	)
	(segment
		(start 110.286962 124.603354)
		(end 109.488962 125.401354)
		(width 0.127)
		(layer "In2.Cu")
		(net 266)
	)
	(segment
		(start 107.411962 149.8915)
		(end 105.02 152.283462)
		(width 0.127)
		(layer "In2.Cu")
		(net 266)
	)
	(segment
		(start 109.092962 118.9915)
		(end 107.667962 120.4165)
		(width 0.127)
		(layer "In2.Cu")
		(net 266)
	)
	(segment
		(start 114.822712 163.70525)
		(end 114.822712 164.26175)
		(width 0.127)
		(layer "F.Cu")
		(net 267)
	)
	(segment
		(start 114.822712 164.26175)
		(end 115.077961 164.517)
		(width 0.127)
		(layer "F.Cu")
		(net 267)
	)
	(segment
		(start 114.017962 162.9005)
		(end 114.822712 163.70525)
		(width 0.127)
		(layer "F.Cu")
		(net 267)
	)
	(segment
		(start 115.077961 164.517)
		(end 115.554961 164.517)
		(width 0.127)
		(layer "F.Cu")
		(net 267)
	)
	(via
		(at 109.592962 115.1665)
		(size 0.45)
		(drill 0.1)
		(layers "F.Cu" "B.Cu")
		(net 267)
	)
	(via
		(at 114.017962 162.9005)
		(size 0.45)
		(drill 0.1)
		(layers "F.Cu" "B.Cu")
		(net 267)
	)
	(segment
		(start 109.837962 118.084823)
		(end 109.837962 118.4765)
		(width 0.15)
		(layer "B.Cu")
		(net 267)
	)
	(segment
		(start 109.592962 117.104)
		(end 109.592962 117.839823)
		(width 0.15)
		(layer "B.Cu")
		(net 267)
	)
	(segment
		(start 109.592962 117.104)
		(end 109.592962 116.329)
		(width 0.15)
		(layer "B.Cu")
		(net 267)
	)
	(segment
		(start 109.592962 115.1665)
		(end 109.592962 116.329)
		(width 0.127)
		(layer "B.Cu")
		(net 267)
	)
	(segment
		(start 109.592962 117.839823)
		(end 109.837962 118.084823)
		(width 0.15)
		(layer "B.Cu")
		(net 267)
	)
	(segment
		(start 107.934462 121.253)
		(end 107.934462 120.625)
		(width 0.127)
		(layer "In2.Cu")
		(net 267)
	)
	(segment
		(start 110.538962 124.707736)
		(end 110.538962 123.8575)
		(width 0.127)
		(layer "In2.Cu")
		(net 267)
	)
	(segment
		(start 114.017962 162.8165)
		(end 113.331462 162.13)
		(width 0.127)
		(layer "In2.Cu")
		(net 267)
	)
	(segment
		(start 107.663962 150.006038)
		(end 107.663962 148.226882)
		(width 0.127)
		(layer "In2.Cu")
		(net 267)
	)
	(segment
		(start 105.272 152.398)
		(end 107.663962 150.006038)
		(width 0.127)
		(layer "In2.Cu")
		(net 267)
	)
	(segment
		(start 109.592962 118.9665)
		(end 109.592962 115.1665)
		(width 0.127)
		(layer "In2.Cu")
		(net 267)
	)
	(segment
		(start 105.272 158.135618)
		(end 105.272 152.398)
		(width 0.127)
		(layer "In2.Cu")
		(net 267)
	)
	(segment
		(start 107.934462 120.625)
		(end 109.592962 118.9665)
		(width 0.127)
		(layer "In2.Cu")
		(net 267)
	)
	(segment
		(start 113.331462 162.13)
		(end 109.266382 162.13)
		(width 0.127)
		(layer "In2.Cu")
		(net 267)
	)
	(segment
		(start 110.538962 123.8575)
		(end 107.934462 121.253)
		(width 0.127)
		(layer "In2.Cu")
		(net 267)
	)
	(segment
		(start 107.663962 148.226882)
		(end 109.740962 146.149882)
		(width 0.127)
		(layer "In2.Cu")
		(net 267)
	)
	(segment
		(start 114.017962 162.9005)
		(end 114.017962 162.8165)
		(width 0.127)
		(layer "In2.Cu")
		(net 267)
	)
	(segment
		(start 109.266382 162.13)
		(end 105.272 158.135618)
		(width 0.127)
		(layer "In2.Cu")
		(net 267)
	)
	(segment
		(start 109.740962 146.149882)
		(end 109.740962 125.505736)
		(width 0.127)
		(layer "In2.Cu")
		(net 267)
	)
	(segment
		(start 109.740962 125.505736)
		(end 110.538962 124.707736)
		(width 0.127)
		(layer "In2.Cu")
		(net 267)
	)
	(segment
		(start 129.752962 156.5415)
		(end 129.752962 157.889)
		(width 0.254)
		(layer "B.Cu")
		(net 268)
	)
	(segment
		(start 99.723962 152.2475)
		(end 98.967962 151.4915)
		(width 0.127)
		(layer "F.Cu")
		(net 274)
	)
	(segment
		(start 89.25158 160.9965)
		(end 89.27358 160.9745)
		(width 0.127)
		(layer "F.Cu")
		(net 274)
	)
	(segment
		(start 89.237962 160.9965)
		(end 89.25158 160.9965)
		(width 0.127)
		(layer "F.Cu")
		(net 274)
	)
	(segment
		(start 86.242962 163.9915)
		(end 89.237962 160.9965)
		(width 0.127)
		(layer "F.Cu")
		(net 274)
	)
	(segment
		(start 89.27358 160.9745)
		(end 94.66358 160.9745)
		(width 0.127)
		(layer "F.Cu")
		(net 274)
	)
	(segment
		(start 98.067962 151.4915)
		(end 98.967962 151.4915)
		(width 0.127)
		(layer "F.Cu")
		(net 274)
	)
	(segment
		(start 99.723962 155.914118)
		(end 99.723962 152.2475)
		(width 0.127)
		(layer "F.Cu")
		(net 274)
	)
	(segment
		(start 86.242962 164.3415)
		(end 86.242962 163.9915)
		(width 0.127)
		(layer "F.Cu")
		(net 274)
	)
	(segment
		(start 94.66358 160.9745)
		(end 99.723962 155.914118)
		(width 0.127)
		(layer "F.Cu")
		(net 274)
	)
	(via
		(at 98.967962 151.4915)
		(size 0.45)
		(drill 0.1)
		(layers "F.Cu" "B.Cu")
		(net 274)
	)
	(via
		(at 86.242962 164.3415)
		(size 0.45)
		(drill 0.1)
		(layers "F.Cu" "B.Cu")
		(net 274)
	)
	(via
		(at 128.07 149.69)
		(size 0.45)
		(drill 0.1)
		(layers "F.Cu" "B.Cu")
		(net 274)
	)
	(segment
		(start 131.905962 146.6485)
		(end 131.905962 144.7285)
		(width 0.127)
		(layer "B.Cu")
		(net 274)
	)
	(segment
		(start 134.051802 144.2165)
		(end 136.390962 141.87734)
		(width 0.127)
		(layer "B.Cu")
		(net 274)
	)
	(segment
		(start 86.242962 164.3415)
		(end 86.037962 164.1365)
		(width 0.127)
		(layer "B.Cu")
		(net 274)
	)
	(segment
		(start 136.390962 141.87734)
		(end 136.390962 139.3235)
		(width 0.127)
		(layer "B.Cu")
		(net 274)
	)
	(segment
		(start 136.390962 139.3235)
		(end 136.748962 138.9655)
		(width 0.127)
		(layer "B.Cu")
		(net 274)
	)
	(segment
		(start 136.748962 138.9655)
		(end 137.467962 138.9655)
		(width 0.127)
		(layer "B.Cu")
		(net 274)
	)
	(segment
		(start 131.905962 144.7285)
		(end 132.417962 144.2165)
		(width 0.127)
		(layer "B.Cu")
		(net 274)
	)
	(segment
		(start 129.674462 148.88)
		(end 131.905962 146.6485)
		(width 0.127)
		(layer "B.Cu")
		(net 274)
	)
	(segment
		(start 128.07 149.69)
		(end 128.88 148.88)
		(width 0.127)
		(layer "B.Cu")
		(net 274)
	)
	(segment
		(start 128.88 148.88)
		(end 129.674462 148.88)
		(width 0.127)
		(layer "B.Cu")
		(net 274)
	)
	(segment
		(start 132.417962 144.2165)
		(end 134.051802 144.2165)
		(width 0.127)
		(layer "B.Cu")
		(net 274)
	)
	(segment
		(start 86.037962 164.1365)
		(end 85.422962 164.1365)
		(width 0.127)
		(layer "B.Cu")
		(net 274)
	)
	(segment
		(start 128.07 151.98)
		(end 126.61 153.44)
		(width 0.127)
		(layer "In2.Cu")
		(net 274)
	)
	(segment
		(start 128.07 149.69)
		(end 128.07 151.98)
		(width 0.127)
		(layer "In2.Cu")
		(net 274)
	)
	(segment
		(start 99.445962 154.600882)
		(end 99.445962 151.9695)
		(width 0.127)
		(layer "In2.Cu")
		(net 274)
	)
	(segment
		(start 126.61 154.29)
		(end 121.8 159.1)
		(width 0.127)
		(layer "In2.Cu")
		(net 274)
	)
	(segment
		(start 99.445962 151.9695)
		(end 98.967962 151.4915)
		(width 0.127)
		(layer "In2.Cu")
		(net 274)
	)
	(segment
		(start 108.45408 163.609)
		(end 99.445962 154.600882)
		(width 0.127)
		(layer "In2.Cu")
		(net 274)
	)
	(segment
		(start 126.61 153.44)
		(end 126.61 154.29)
		(width 0.127)
		(layer "In2.Cu")
		(net 274)
	)
	(segment
		(start 121.8 159.1)
		(end 121.8 159.359462)
		(width 0.127)
		(layer "In2.Cu")
		(net 274)
	)
	(segment
		(start 121.8 159.359462)
		(end 117.550462 163.609)
		(width 0.127)
		(layer "In2.Cu")
		(net 274)
	)
	(segment
		(start 117.550462 163.609)
		(end 108.45408 163.609)
		(width 0.127)
		(layer "In2.Cu")
		(net 274)
	)
	(segment
		(start 86.107962 165.0965)
		(end 86.671462 164.533)
		(width 0.127)
		(layer "F.Cu")
		(net 275)
	)
	(segment
		(start 98.067962 150.8415)
		(end 99.008806 150.8415)
		(width 0.127)
		(layer "F.Cu")
		(net 275)
	)
	(segment
		(start 99.975962 156.0185)
		(end 99.975962 151.808656)
		(width 0.127)
		(layer "F.Cu")
		(net 275)
	)
	(segment
		(start 99.975962 151.808656)
		(end 99.008806 150.8415)
		(width 0.127)
		(layer "F.Cu")
		(net 275)
	)
	(segment
		(start 94.767962 161.2265)
		(end 99.975962 156.0185)
		(width 0.127)
		(layer "F.Cu")
		(net 275)
	)
	(segment
		(start 89.377962 161.2265)
		(end 94.767962 161.2265)
		(width 0.127)
		(layer "F.Cu")
		(net 275)
	)
	(segment
		(start 86.671462 164.533)
		(end 86.671462 163.933)
		(width 0.127)
		(layer "F.Cu")
		(net 275)
	)
	(segment
		(start 86.671462 163.933)
		(end 89.377962 161.2265)
		(width 0.127)
		(layer "F.Cu")
		(net 275)
	)
	(via
		(at 99.008806 150.8415)
		(size 0.45)
		(drill 0.1)
		(layers "F.Cu" "B.Cu")
		(net 275)
	)
	(via
		(at 86.107962 165.0965)
		(size 0.45)
		(drill 0.1)
		(layers "F.Cu" "B.Cu")
		(net 275)
	)
	(via
		(at 126.0665 154.13)
		(size 0.45)
		(drill 0.1)
		(layers "F.Cu" "B.Cu")
		(net 275)
	)
	(segment
		(start 127.18 152.82)
		(end 127.18 151.730844)
		(width 0.127)
		(layer "B.Cu")
		(net 275)
	)
	(segment
		(start 126.0665 154.13)
		(end 126.0665 153.9335)
		(width 0.127)
		(layer "B.Cu")
		(net 275)
	)
	(segment
		(start 136.642962 140.0915)
		(end 136.769962 139.9645)
		(width 0.127)
		(layer "B.Cu")
		(net 275)
	)
	(segment
		(start 127.18 151.730844)
		(end 132.157962 146.752882)
		(width 0.127)
		(layer "B.Cu")
		(net 275)
	)
	(segment
		(start 86.107962 165.0965)
		(end 85.422962 165.0965)
		(width 0.127)
		(layer "B.Cu")
		(net 275)
	)
	(segment
		(start 134.156184 144.4685)
		(end 136.642962 141.981722)
		(width 0.127)
		(layer "B.Cu")
		(net 275)
	)
	(segment
		(start 136.642962 141.981722)
		(end 136.642962 140.0915)
		(width 0.127)
		(layer "B.Cu")
		(net 275)
	)
	(segment
		(start 132.157962 146.752882)
		(end 132.157962 144.832882)
		(width 0.127)
		(layer "B.Cu")
		(net 275)
	)
	(segment
		(start 126.0665 153.9335)
		(end 127.18 152.82)
		(width 0.127)
		(layer "B.Cu")
		(net 275)
	)
	(segment
		(start 132.522344 144.4685)
		(end 134.156184 144.4685)
		(width 0.127)
		(layer "B.Cu")
		(net 275)
	)
	(segment
		(start 136.769962 139.9645)
		(end 137.467962 139.9645)
		(width 0.127)
		(layer "B.Cu")
		(net 275)
	)
	(segment
		(start 132.157962 144.832882)
		(end 132.522344 144.4685)
		(width 0.127)
		(layer "B.Cu")
		(net 275)
	)
	(segment
		(start 121.548 159.25508)
		(end 117.44608 163.357)
		(width 0.127)
		(layer "In2.Cu")
		(net 275)
	)
	(segment
		(start 117.44608 163.357)
		(end 108.558462 163.357)
		(width 0.127)
		(layer "In2.Cu")
		(net 275)
	)
	(segment
		(start 99.697962 154.4965)
		(end 99.697962 151.530656)
		(width 0.127)
		(layer "In2.Cu")
		(net 275)
	)
	(segment
		(start 108.558462 163.357)
		(end 99.697962 154.4965)
		(width 0.127)
		(layer "In2.Cu")
		(net 275)
	)
	(segment
		(start 126.0665 154.477118)
		(end 121.548 158.995618)
		(width 0.127)
		(layer "In2.Cu")
		(net 275)
	)
	(segment
		(start 121.548 158.995618)
		(end 121.548 159.25508)
		(width 0.127)
		(layer "In2.Cu")
		(net 275)
	)
	(segment
		(start 99.697962 151.530656)
		(end 99.008806 150.8415)
		(width 0.127)
		(layer "In2.Cu")
		(net 275)
	)
	(segment
		(start 126.0665 154.13)
		(end 126.0665 154.477118)
		(width 0.127)
		(layer "In2.Cu")
		(net 275)
	)
	(segment
		(start 78.693231 170.23)
		(end 79.479462 170.23)
		(width 0.127)
		(layer "F.Cu")
		(net 276)
	)
	(segment
		(start 82.022962 169.9415)
		(end 82.311462 169.653)
		(width 0.127)
		(layer "F.Cu")
		(net 276)
	)
	(segment
		(start 94.037288 159.4625)
		(end 96.517962 156.981826)
		(width 0.127)
		(layer "F.Cu")
		(net 276)
	)
	(segment
		(start 78.044731 169.5815)
		(end 78.693231 170.23)
		(width 0.127)
		(layer "F.Cu")
		(net 276)
	)
	(segment
		(start 83.917962 169.0255)
		(end 83.917962 164.178208)
		(width 0.127)
		(layer "F.Cu")
		(net 276)
	)
	(segment
		(start 82.311462 169.653)
		(end 83.290462 169.653)
		(width 0.127)
		(layer "F.Cu")
		(net 276)
	)
	(segment
		(start 83.917962 164.178208)
		(end 88.63367 159.4625)
		(width 0.127)
		(layer "F.Cu")
		(net 276)
	)
	(segment
		(start 79.767962 169.9415)
		(end 82.022962 169.9415)
		(width 0.127)
		(layer "F.Cu")
		(net 276)
	)
	(segment
		(start 79.479462 170.23)
		(end 79.767962 169.9415)
		(width 0.127)
		(layer "F.Cu")
		(net 276)
	)
	(segment
		(start 76.617962 169.5815)
		(end 78.044731 169.5815)
		(width 0.127)
		(layer "F.Cu")
		(net 276)
	)
	(segment
		(start 96.517962 156.981826)
		(end 96.517962 155.6415)
		(width 0.127)
		(layer "F.Cu")
		(net 276)
	)
	(segment
		(start 88.63367 159.4625)
		(end 94.037288 159.4625)
		(width 0.127)
		(layer "F.Cu")
		(net 276)
	)
	(segment
		(start 83.290462 169.653)
		(end 83.917962 169.0255)
		(width 0.127)
		(layer "F.Cu")
		(net 276)
	)
	(segment
		(start 91.256962 133.421235)
		(end 91.256962 126.263212)
		(width 0.182)
		(layer "F.Cu")
		(net 277)
	)
	(segment
		(start 85.517963 122.2665)
		(end 84.842962 122.2665)
		(width 0.182)
		(layer "F.Cu")
		(net 277)
	)
	(segment
		(start 87.47125 122.4775)
		(end 85.728963 122.4775)
		(width 0.182)
		(layer "F.Cu")
		(net 277)
	)
	(segment
		(start 91.256962 126.263212)
		(end 87.47125 122.4775)
		(width 0.182)
		(layer "F.Cu")
		(net 277)
	)
	(segment
		(start 91.267962 133.957236)
		(end 91.267962 133.432235)
		(width 0.182)
		(layer "F.Cu")
		(net 277)
	)
	(segment
		(start 91.267962 133.432235)
		(end 91.256962 133.421235)
		(width 0.182)
		(layer "F.Cu")
		(net 277)
	)
	(segment
		(start 85.728963 122.4775)
		(end 85.517963 122.2665)
		(width 0.182)
		(layer "F.Cu")
		(net 277)
	)
	(segment
		(start 84.842962 123.0665)
		(end 85.517963 123.0665)
		(width 0.182)
		(layer "F.Cu")
		(net 278)
	)
	(segment
		(start 87.177962 122.8555)
		(end 87.314674 122.8555)
		(width 0.182)
		(layer "F.Cu")
		(net 278)
	)
	(segment
		(start 86.127962 123.0555)
		(end 86.127962 123.140335)
		(width 0.182)
		(layer "F.Cu")
		(net 278)
	)
	(segment
		(start 90.878962 133.421235)
		(end 90.867962 133.432235)
		(width 0.182)
		(layer "F.Cu")
		(net 278)
	)
	(segment
		(start 86.727962 122.8555)
		(end 87.177962 122.8555)
		(width 0.182)
		(layer "F.Cu")
		(net 278)
	)
	(segment
		(start 85.728963 122.8555)
		(end 85.927962 122.8555)
		(width 0.182)
		(layer "F.Cu")
		(net 278)
	)
	(segment
		(start 90.878962 126.419788)
		(end 90.878962 133.421235)
		(width 0.182)
		(layer "F.Cu")
		(net 278)
	)
	(segment
		(start 86.527962 123.140335)
		(end 86.527962 123.0555)
		(width 0.182)
		(layer "F.Cu")
		(net 278)
	)
	(segment
		(start 85.517963 123.0665)
		(end 85.728963 122.8555)
		(width 0.182)
		(layer "F.Cu")
		(net 278)
	)
	(segment
		(start 90.867962 133.432235)
		(end 90.867962 133.957236)
		(width 0.182)
		(layer "F.Cu")
		(net 278)
	)
	(segment
		(start 87.314674 122.8555)
		(end 90.878962 126.419788)
		(width 0.182)
		(layer "F.Cu")
		(net 278)
	)
	(arc
		(start 85.927962 122.8555)
		(mid 86.069383 122.914079)
		(end 86.127962 123.0555)
		(width 0.182)
		(layer "F.Cu")
		(net 278)
	)
	(arc
		(start 86.527962 123.0555)
		(mid 86.586541 122.914079)
		(end 86.727962 122.8555)
		(width 0.182)
		(layer "F.Cu")
		(net 278)
	)
	(arc
		(start 86.327962 123.340335)
		(mid 86.469383 123.281756)
		(end 86.527962 123.140335)
		(width 0.182)
		(layer "F.Cu")
		(net 278)
	)
	(arc
		(start 86.127962 123.140335)
		(mid 86.186541 123.281756)
		(end 86.327962 123.340335)
		(width 0.182)
		(layer "F.Cu")
		(net 278)
	)
	(segment
		(start 105.532962 139.6515)
		(end 105.532962 139.6215)
		(width 0.127)
		(layer "F.Cu")
		(net 279)
	)
	(segment
		(start 121.808962 114.0155)
		(end 122.154462 113.67)
		(width 0.2)
		(layer "F.Cu")
		(net 279)
	)
	(segment
		(start 138.5665 121.0165)
		(end 140.429962 121.0165)
		(width 0.2)
		(layer "F.Cu")
		(net 279)
	)
	(segment
		(start 98.017962 123.561722)
		(end 98.017962 124.2665)
		(width 0.127)
		(layer "F.Cu")
		(net 279)
	)
	(segment
		(start 122.154462 113.67)
		(end 123.911462 113.67)
		(width 0.2)
		(layer "F.Cu")
		(net 279)
	)
	(segment
		(start 98.06583 132.184368)
		(end 98.06583 130.039368)
		(width 0.127)
		(layer "F.Cu")
		(net 279)
	)
	(segment
		(start 103.457962 117.7865)
		(end 103.457962 117.3865)
		(width 0.2)
		(layer "F.Cu")
		(net 279)
	)
	(segment
		(start 123.911462 113.67)
		(end 124.267962 114.0265)
		(width 0.2)
		(layer "F.Cu")
		(net 279)
	)
	(segment
		(start 135.107962 117.557962)
		(end 138.5665 121.0165)
		(width 0.2)
		(layer "F.Cu")
		(net 279)
	)
	(segment
		(start 98.06583 130.039368)
		(end 97.567962 129.5415)
		(width 0.127)
		(layer "F.Cu")
		(net 279)
	)
	(segment
		(start 98.969962 122.275)
		(end 98.969962 122.609722)
		(width 0.127)
		(layer "F.Cu")
		(net 279)
	)
	(segment
		(start 105.532962 139.6515)
		(end 98.06583 132.184368)
		(width 0.127)
		(layer "F.Cu")
		(net 279)
	)
	(segment
		(start 106.828962 114.0155)
		(end 121.808962 114.0155)
		(width 0.2)
		(layer "F.Cu")
		(net 279)
	)
	(segment
		(start 110.797462 144.916)
		(end 105.532962 139.6515)
		(width 0.127)
		(layer "F.Cu")
		(net 279)
	)
	(segment
		(start 112.473961 144.916)
		(end 110.797462 144.916)
		(width 0.127)
		(layer "F.Cu")
		(net 279)
	)
	(segment
		(start 105.532962 139.6215)
		(end 105.987962 139.1665)
		(width 0.127)
		(layer "F.Cu")
		(net 279)
	)
	(segment
		(start 97.567962 129.5415)
		(end 97.567962 128.9915)
		(width 0.15)
		(layer "F.Cu")
		(net 279)
	)
	(segment
		(start 124.267962 114.0265)
		(end 134.487962 114.0265)
		(width 0.2)
		(layer "F.Cu")
		(net 279)
	)
	(segment
		(start 135.107962 114.6465)
		(end 135.107962 117.557962)
		(width 0.2)
		(layer "F.Cu")
		(net 279)
	)
	(segment
		(start 134.487962 114.0265)
		(end 135.107962 114.6465)
		(width 0.2)
		(layer "F.Cu")
		(net 279)
	)
	(segment
		(start 98.969962 122.609722)
		(end 98.017962 123.561722)
		(width 0.127)
		(layer "F.Cu")
		(net 279)
	)
	(segment
		(start 103.457962 117.3865)
		(end 106.828962 114.0155)
		(width 0.2)
		(layer "F.Cu")
		(net 279)
	)
	(via
		(at 103.457962 117.7865)
		(size 0.45)
		(drill 0.1)
		(layers "F.Cu" "B.Cu")
		(net 279)
	)
	(via
		(at 98.017962 124.2665)
		(size 0.45)
		(drill 0.1)
		(layers "F.Cu" "B.Cu")
		(net 279)
	)
	(via
		(at 97.567962 128.9915)
		(size 0.45)
		(drill 0.1)
		(layers "F.Cu" "B.Cu")
		(net 279)
	)
	(segment
		(start 103.457962 122.699358)
		(end 102.24082 123.9165)
		(width 0.2)
		(layer "B.Cu")
		(net 279)
	)
	(segment
		(start 98.017962 124.2665)
		(end 97.567962 124.7165)
		(width 0.15)
		(layer "B.Cu")
		(net 279)
	)
	(segment
		(start 102.24082 123.9165)
		(end 98.992859 123.9165)
		(width 0.2)
		(layer "B.Cu")
		(net 279)
	)
	(segment
		(start 98.617859 124.2915)
		(end 98.042962 124.2915)
		(width 0.2)
		(layer "B.Cu")
		(net 279)
	)
	(segment
		(start 98.042962 124.2915)
		(end 98.017962 124.2665)
		(width 0.2)
		(layer "B.Cu")
		(net 279)
	)
	(segment
		(start 103.457962 117.7865)
		(end 103.457962 122.699358)
		(width 0.2)
		(layer "B.Cu")
		(net 279)
	)
	(segment
		(start 97.567962 124.7165)
		(end 97.567962 128.9915)
		(width 0.15)
		(layer "B.Cu")
		(net 279)
	)
	(segment
		(start 98.992859 123.9165)
		(end 98.617859 124.2915)
		(width 0.2)
		(layer "B.Cu")
		(net 279)
	)
	(segment
		(start 77.903962 135.089236)
		(end 79.024962 135.089236)
		(width 0.15)
		(layer "F.Cu")
		(net 281)
	)
	(segment
		(start 84.075354 135.657236)
		(end 84.625354 135.107236)
		(width 0.15)
		(layer "F.Cu")
		(net 281)
	)
	(segment
		(start 79.027226 135.0915)
		(end 79.617962 135.0915)
		(width 0.15)
		(layer "F.Cu")
		(net 281)
	)
	(segment
		(start 80.183698 135.657236)
		(end 84.075354 135.657236)
		(width 0.15)
		(layer "F.Cu")
		(net 281)
	)
	(segment
		(start 79.024962 135.089236)
		(end 79.027226 135.0915)
		(width 0.15)
		(layer "F.Cu")
		(net 281)
	)
	(segment
		(start 79.615698 135.089236)
		(end 80.183698 135.657236)
		(width 0.15)
		(layer "F.Cu")
		(net 281)
	)
	(segment
		(start 84.625354 135.107236)
		(end 85.317962 135.107236)
		(width 0.15)
		(layer "F.Cu")
		(net 281)
	)
	(segment
		(start 79.024962 135.089236)
		(end 79.615698 135.089236)
		(width 0.15)
		(layer "F.Cu")
		(net 281)
	)
	(via
		(at 79.617962 135.0915)
		(size 0.45)
		(drill 0.1)
		(layers "F.Cu" "B.Cu")
		(net 281)
	)
	(segment
		(start 79.617962 135.0915)
		(end 80.332962 135.0915)
		(width 0.15)
		(layer "B.Cu")
		(net 281)
	)
	(segment
		(start 84.439462 134.707236)
		(end 85.317962 134.707236)
		(width 0.15)
		(layer "F.Cu")
		(net 282)
	)
	(segment
		(start 77.903962 133.822236)
		(end 79.598698 133.822236)
		(width 0.15)
		(layer "F.Cu")
		(net 282)
	)
	(segment
		(start 79.598698 133.822236)
		(end 80.162198 134.385736)
		(width 0.15)
		(layer "F.Cu")
		(net 282)
	)
	(segment
		(start 79.598698 133.822236)
		(end 79.617962 133.8415)
		(width 0.15)
		(layer "F.Cu")
		(net 282)
	)
	(segment
		(start 80.162198 134.385736)
		(end 84.117962 134.385736)
		(width 0.15)
		(layer "F.Cu")
		(net 282)
	)
	(segment
		(start 84.117962 134.385736)
		(end 84.439462 134.707236)
		(width 0.15)
		(layer "F.Cu")
		(net 282)
	)
	(via
		(at 79.617962 133.8415)
		(size 0.45)
		(drill 0.1)
		(layers "F.Cu" "B.Cu")
		(net 282)
	)
	(segment
		(start 79.617962 133.8415)
		(end 80.332962 133.8415)
		(width 0.15)
		(layer "B.Cu")
		(net 282)
	)
	(segment
		(start 80.192198 133.115736)
		(end 84.671878 133.115736)
		(width 0.15)
		(layer "F.Cu")
		(net 283)
	)
	(segment
		(start 79.603698 132.552236)
		(end 79.617962 132.5665)
		(width 0.15)
		(layer "F.Cu")
		(net 283)
	)
	(segment
		(start 85.513378 133.957236)
		(end 86.067962 133.957236)
		(width 0.15)
		(layer "F.Cu")
		(net 283)
	)
	(segment
		(start 79.104462 132.552236)
		(end 79.628698 132.552236)
		(width 0.15)
		(layer "F.Cu")
		(net 283)
	)
	(segment
		(start 77.903962 132.552236)
		(end 79.104462 132.552236)
		(width 0.15)
		(layer "F.Cu")
		(net 283)
	)
	(segment
		(start 84.671878 133.115736)
		(end 85.513378 133.957236)
		(width 0.15)
		(layer "F.Cu")
		(net 283)
	)
	(segment
		(start 79.104462 132.552236)
		(end 79.603698 132.552236)
		(width 0.15)
		(layer "F.Cu")
		(net 283)
	)
	(segment
		(start 79.628698 132.552236)
		(end 80.192198 133.115736)
		(width 0.15)
		(layer "F.Cu")
		(net 283)
	)
	(via
		(at 79.617962 132.5665)
		(size 0.45)
		(drill 0.1)
		(layers "F.Cu" "B.Cu")
		(net 283)
	)
	(segment
		(start 79.617962 132.5665)
		(end 80.307962 132.5665)
		(width 0.15)
		(layer "B.Cu")
		(net 283)
	)
	(segment
		(start 95.877962 148.7365)
		(end 95.877962 149.9315)
		(width 0.15)
		(layer "F.Cu")
		(net 284)
	)
	(segment
		(start 95.877962 149.9315)
		(end 95.867962 149.9415)
		(width 0.15)
		(layer "F.Cu")
		(net 284)
	)
	(segment
		(start 81.66739 167.75185)
		(end 83.161962 166.257278)
		(width 0.127)
		(layer "F.Cu")
		(net 285)
	)
	(segment
		(start 94.567962 157.86268)
		(end 94.567962 155.6415)
		(width 0.127)
		(layer "F.Cu")
		(net 285)
	)
	(segment
		(start 68.25 168.25)
		(end 68.8415 168.8415)
		(width 0.15)
		(layer "F.Cu")
		(net 285)
	)
	(segment
		(start 68.8415 168.8415)
		(end 69.317962 168.8415)
		(width 0.15)
		(layer "F.Cu")
		(net 285)
	)
	(segment
		(start 83.161962 166.257278)
		(end 83.161962 163.865062)
		(width 0.127)
		(layer "F.Cu")
		(net 285)
	)
	(segment
		(start 93.724142 158.7065)
		(end 94.567962 157.86268)
		(width 0.127)
		(layer "F.Cu")
		(net 285)
	)
	(segment
		(start 88.320524 158.7065)
		(end 93.724142 158.7065)
		(width 0.127)
		(layer "F.Cu")
		(net 285)
	)
	(segment
		(start 83.161962 163.865062)
		(end 88.320524 158.7065)
		(width 0.127)
		(layer "F.Cu")
		(net 285)
	)
	(segment
		(start 81.66739 167.85615)
		(end 81.66739 167.75185)
		(width 0.127)
		(layer "F.Cu")
		(net 285)
	)
	(via
		(at 68.25 168.25)
		(size 0.45)
		(drill 0.1)
		(layers "F.Cu" "B.Cu")
		(net 285)
	)
	(via
		(at 81.66739 167.85615)
		(size 0.45)
		(drill 0.1)
		(layers "F.Cu" "B.Cu")
		(net 285)
	)
	(segment
		(start 79.888962 169.2455)
		(end 81.278312 167.85615)
		(width 0.127)
		(layer "B.Cu")
		(net 285)
	)
	(segment
		(start 69.2455 169.2455)
		(end 79.888962 169.2455)
		(width 0.127)
		(layer "B.Cu")
		(net 285)
	)
	(segment
		(start 68.25 168.25)
		(end 69.2455 169.2455)
		(width 0.127)
		(layer "B.Cu")
		(net 285)
	)
	(segment
		(start 81.278312 167.85615)
		(end 81.66739 167.85615)
		(width 0.127)
		(layer "B.Cu")
		(net 285)
	)
	(segment
		(start 93.828524 158.9585)
		(end 95.217962 157.569062)
		(width 0.127)
		(layer "F.Cu")
		(net 286)
	)
	(segment
		(start 70.317962 168.1165)
		(end 70.192962 167.9915)
		(width 0.15)
		(layer "F.Cu")
		(net 286)
	)
	(segment
		(start 82.244857 167.862661)
		(end 83.413962 166.693556)
		(width 0.127)
		(layer "F.Cu")
		(net 286)
	)
	(segment
		(start 83.413962 163.969444)
		(end 88.424906 158.9585)
		(width 0.127)
		(layer "F.Cu")
		(net 286)
	)
	(segment
		(start 83.413962 166.693556)
		(end 83.413962 163.969444)
		(width 0.127)
		(layer "F.Cu")
		(net 286)
	)
	(segment
		(start 88.424906 158.9585)
		(end 93.828524 158.9585)
		(width 0.127)
		(layer "F.Cu")
		(net 286)
	)
	(segment
		(start 70.317962 168.8415)
		(end 70.317962 168.1165)
		(width 0.15)
		(layer "F.Cu")
		(net 286)
	)
	(segment
		(start 95.217962 157.569062)
		(end 95.217962 155.6415)
		(width 0.127)
		(layer "F.Cu")
		(net 286)
	)
	(via
		(at 82.244857 167.862661)
		(size 0.45)
		(drill 0.1)
		(layers "F.Cu" "B.Cu")
		(net 286)
	)
	(via
		(at 70.192962 167.9915)
		(size 0.45)
		(drill 0.1)
		(layers "F.Cu" "B.Cu")
		(net 286)
	)
	(segment
		(start 81.817962 167.4165)
		(end 82.244857 167.843395)
		(width 0.127)
		(layer "B.Cu")
		(net 286)
	)
	(segment
		(start 81.36158 167.4165)
		(end 81.817962 167.4165)
		(width 0.127)
		(layer "B.Cu")
		(net 286)
	)
	(segment
		(start 70.192962 167.9915)
		(end 71.194962 168.9935)
		(width 0.127)
		(layer "B.Cu")
		(net 286)
	)
	(segment
		(start 79.78458 168.9935)
		(end 81.36158 167.4165)
		(width 0.127)
		(layer "B.Cu")
		(net 286)
	)
	(segment
		(start 71.194962 168.9935)
		(end 79.78458 168.9935)
		(width 0.127)
		(layer "B.Cu")
		(net 286)
	)
	(segment
		(start 82.244857 167.843395)
		(end 82.244857 167.862661)
		(width 0.127)
		(layer "B.Cu")
		(net 286)
	)
	(segment
		(start 73.317962 168.0965)
		(end 73.317962 168.8415)
		(width 0.127)
		(layer "F.Cu")
		(net 287)
	)
	(segment
		(start 83.665962 167.144106)
		(end 83.665962 164.073826)
		(width 0.127)
		(layer "F.Cu")
		(net 287)
	)
	(segment
		(start 95.867962 157.275444)
		(end 95.867962 155.6415)
		(width 0.127)
		(layer "F.Cu")
		(net 287)
	)
	(segment
		(start 82.800876 168.009192)
		(end 83.665962 167.144106)
		(width 0.127)
		(layer "F.Cu")
		(net 287)
	)
	(segment
		(start 88.529288 159.2105)
		(end 93.932906 159.2105)
		(width 0.127)
		(layer "F.Cu")
		(net 287)
	)
	(segment
		(start 93.932906 159.2105)
		(end 95.867962 157.275444)
		(width 0.127)
		(layer "F.Cu")
		(net 287)
	)
	(segment
		(start 83.665962 164.073826)
		(end 88.529288 159.2105)
		(width 0.127)
		(layer "F.Cu")
		(net 287)
	)
	(via
		(at 82.800876 168.009192)
		(size 0.45)
		(drill 0.1)
		(layers "F.Cu" "B.Cu")
		(net 287)
	)
	(via
		(at 73.317962 168.0965)
		(size 0.45)
		(drill 0.1)
		(layers "F.Cu" "B.Cu")
		(net 287)
	)
	(segment
		(start 82.800876 168.009192)
		(end 82.800876 167.833902)
		(width 0.127)
		(layer "B.Cu")
		(net 287)
	)
	(segment
		(start 79.680198 168.7415)
		(end 73.962962 168.7415)
		(width 0.127)
		(layer "B.Cu")
		(net 287)
	)
	(segment
		(start 73.962962 168.7415)
		(end 73.317962 168.0965)
		(width 0.127)
		(layer "B.Cu")
		(net 287)
	)
	(segment
		(start 82.131474 167.1645)
		(end 81.257198 167.1645)
		(width 0.127)
		(layer "B.Cu")
		(net 287)
	)
	(segment
		(start 81.257198 167.1645)
		(end 79.680198 168.7415)
		(width 0.127)
		(layer "B.Cu")
		(net 287)
	)
	(segment
		(start 82.800876 167.833902)
		(end 82.131474 167.1645)
		(width 0.127)
		(layer "B.Cu")
		(net 287)
	)
	(segment
		(start 98.869962 129.2685)
		(end 98.011292 128.40983)
		(width 0.15)
		(layer "F.Cu")
		(net 288)
	)
	(segment
		(start 98.869962 130.3895)
		(end 98.869962 130.0415)
		(width 0.15)
		(layer "F.Cu")
		(net 288)
	)
	(segment
		(start 98.869962 130.0415)
		(end 98.869962 129.2685)
		(width 0.15)
		(layer "F.Cu")
		(net 288)
	)
	(segment
		(start 98.557962 130.7015)
		(end 98.869962 130.3895)
		(width 0.15)
		(layer "F.Cu")
		(net 288)
	)
	(segment
		(start 98.557962 131.6165)
		(end 98.557962 130.7015)
		(width 0.15)
		(layer "F.Cu")
		(net 288)
	)
	(segment
		(start 98.011292 128.40983)
		(end 98.011292 127.9705)
		(width 0.15)
		(layer "F.Cu")
		(net 288)
	)
	(segment
		(start 98.567962 173.429)
		(end 97.984462 173.429)
		(width 0.15)
		(layer "B.Cu")
		(net 301)
	)
	(segment
		(start 96.809962 173.1875)
		(end 97.742962 173.1875)
		(width 0.15)
		(layer "B.Cu")
		(net 301)
	)
	(segment
		(start 97.984462 173.429)
		(end 97.742962 173.1875)
		(width 0.15)
		(layer "B.Cu")
		(net 301)
	)
	(segment
		(start 97.763962 172.6875)
		(end 97.867962 172.7915)
		(width 0.15)
		(layer "B.Cu")
		(net 302)
	)
	(segment
		(start 96.809962 172.6875)
		(end 97.763962 172.6875)
		(width 0.15)
		(layer "B.Cu")
		(net 302)
	)
	(segment
		(start 98.567962 172.7915)
		(end 97.867962 172.7915)
		(width 0.15)
		(layer "B.Cu")
		(net 302)
	)
	(segment
		(start 96.809962 172.1875)
		(end 97.767962 172.1875)
		(width 0.15)
		(layer "B.Cu")
		(net 303)
	)
	(segment
		(start 98.567962 172.2915)
		(end 97.871962 172.2915)
		(width 0.15)
		(layer "B.Cu")
		(net 303)
	)
	(segment
		(start 97.871962 172.2915)
		(end 97.767962 172.1875)
		(width 0.15)
		(layer "B.Cu")
		(net 303)
	)
	(segment
		(start 96.809962 171.6875)
		(end 97.767962 171.6875)
		(width 0.15)
		(layer "B.Cu")
		(net 304)
	)
	(segment
		(start 98.567962 171.654)
		(end 97.801462 171.654)
		(width 0.15)
		(layer "B.Cu")
		(net 304)
	)
	(segment
		(start 97.801462 171.654)
		(end 97.767962 171.6875)
		(width 0.15)
		(layer "B.Cu")
		(net 304)
	)
	(segment
		(start 97.717962 171.1875)
		(end 96.809962 171.1875)
		(width 0.15)
		(layer "B.Cu")
		(net 305)
	)
	(segment
		(start 98.567962 170.879)
		(end 98.026462 170.879)
		(width 0.15)
		(layer "B.Cu")
		(net 305)
	)
	(segment
		(start 98.026462 170.879)
		(end 97.717962 171.1875)
		(width 0.15)
		(layer "B.Cu")
		(net 305)
	)
	(segment
		(start 98.192962 170.2415)
		(end 97.746962 170.6875)
		(width 0.15)
		(layer "B.Cu")
		(net 306)
	)
	(segment
		(start 97.746962 170.6875)
		(end 96.809962 170.6875)
		(width 0.15)
		(layer "B.Cu")
		(net 306)
	)
	(segment
		(start 98.567962 170.2415)
		(end 98.192962 170.2415)
		(width 0.15)
		(layer "B.Cu")
		(net 306)
	)
	(segment
		(start 98.567962 169.7415)
		(end 97.967054 169.7415)
		(width 0.15)
		(layer "B.Cu")
		(net 307)
	)
	(segment
		(start 97.521054 170.1875)
		(end 96.809962 170.1875)
		(width 0.15)
		(layer "B.Cu")
		(net 307)
	)
	(segment
		(start 97.967054 169.7415)
		(end 97.521054 170.1875)
		(width 0.15)
		(layer "B.Cu")
		(net 307)
	)
	(segment
		(start 97.521054 169.6885)
		(end 98.105554 169.104)
		(width 0.15)
		(layer "B.Cu")
		(net 308)
	)
	(segment
		(start 96.809962 169.6885)
		(end 97.521054 169.6885)
		(width 0.15)
		(layer "B.Cu")
		(net 308)
	)
	(segment
		(start 98.105554 169.104)
		(end 98.567962 169.104)
		(width 0.15)
		(layer "B.Cu")
		(net 308)
	)
	(segment
		(start 132.842962 118.554)
		(end 132.842962 116.7915)
		(width 0.15)
		(layer "F.Cu")
		(net 317)
	)
	(segment
		(start 133.767962 120.7065)
		(end 132.817962 120.7065)
		(width 0.254)
		(layer "F.Cu")
		(net 317)
	)
	(segment
		(start 132.842962 119.329)
		(end 132.842962 118.554)
		(width 0.15)
		(layer "F.Cu")
		(net 317)
	)
	(segment
		(start 132.842962 119.329)
		(end 132.842962 120.6815)
		(width 0.15)
		(layer "F.Cu")
		(net 317)
	)
	(segment
		(start 57.168962 176.3255)
		(end 58.507962 176.3255)
		(width 0.254)
		(layer "F.Cu")
		(net 319)
	)
	(segment
		(start 57.168962 177.3205)
		(end 58.502962 177.3205)
		(width 0.254)
		(layer "F.Cu")
		(net 320)
	)
	(segment
		(start 69.317962 175.8065)
		(end 69.067962 176.0565)
		(width 0.254)
		(layer "F.Cu")
		(net 325)
	)
	(segment
		(start 69.067962 176.0565)
		(end 68.367962 176.0565)
		(width 0.254)
		(layer "F.Cu")
		(net 325)
	)
	(segment
		(start 69.317962 174.7915)
		(end 69.317962 175.8065)
		(width 0.254)
		(layer "F.Cu")
		(net 325)
	)
	(segment
		(start 68.592962 173.5665)
		(end 67.727962 173.5665)
		(width 0.254)
		(layer "F.Cu")
		(net 326)
	)
	(segment
		(start 67.727962 173.5665)
		(end 67.327962 173.9665)
		(width 0.254)
		(layer "F.Cu")
		(net 326)
	)
	(segment
		(start 102.570962 149.6175)
		(end 103.719462 149.6175)
		(width 0.254)
		(layer "F.Cu")
		(net 327)
	)
	(segment
		(start 103.792962 153.841)
		(end 102.577462 153.841)
		(width 0.254)
		(layer "F.Cu")
		(net 327)
	)
	(segment
		(start 106.143462 151.741)
		(end 104.043462 153.841)
		(width 0.254)
		(layer "F.Cu")
		(net 327)
	)
	(segment
		(start 103.968462 149.641)
		(end 106.093462 147.516)
		(width 0.254)
		(layer "F.Cu")
		(net 327)
	)
	(segment
		(start 102.165962 153.4295)
		(end 102.165962 150.0205)
		(width 0.254)
		(layer "F.Cu")
		(net 327)
	)
	(segment
		(start 102.577462 153.841)
		(end 102.165962 153.4295)
		(width 0.254)
		(layer "F.Cu")
		(net 327)
	)
	(segment
		(start 102.165962 150.0205)
		(end 102.569962 149.6165)
		(width 0.254)
		(layer "F.Cu")
		(net 327)
	)
	(segment
		(start 76.132962 170.0665)
		(end 76.617962 170.5515)
		(width 0.127)
		(layer "F.Cu")
		(net 328)
	)
	(segment
		(start 74.542962 170.0665)
		(end 76.132962 170.0665)
		(width 0.127)
		(layer "F.Cu")
		(net 328)
	)
	(segment
		(start 142.227962 127.4315)
		(end 142.227962 126.4715)
		(width 0.15)
		(layer "F.Cu")
		(net 329)
	)
	(segment
		(start 142.242962 126.4565)
		(end 141.337962 126.4565)
		(width 0.15)
		(layer "F.Cu")
		(net 329)
	)
	(segment
		(start 81.017962 168.2415)
		(end 80.502962 168.2415)
		(width 0.127)
		(layer "F.Cu")
		(net 330)
	)
	(segment
		(start 81.465962 169.5415)
		(end 81.465962 168.6895)
		(width 0.127)
		(layer "F.Cu")
		(net 330)
	)
	(segment
		(start 81.465962 168.6895)
		(end 81.017962 168.2415)
		(width 0.127)
		(layer "F.Cu")
		(net 330)
	)
	(segment
		(start 74.994962 150.6165)
		(end 75.957962 150.6165)
		(width 0.15)
		(layer "B.Cu")
		(net 331)
	)
	(segment
		(start 45.817962 164.0955)
		(end 45.817962 165.4375)
		(width 0.2)
		(layer "B.Cu")
		(net 332)
	)
	(segment
		(start 44.854962 163.6325)
		(end 45.354962 163.6325)
		(width 0.2)
		(layer "B.Cu")
		(net 332)
	)
	(segment
		(start 45.354962 163.6325)
		(end 45.817962 164.0955)
		(width 0.2)
		(layer "B.Cu")
		(net 332)
	)
	(segment
		(start 44.854962 162.8855)
		(end 44.854962 161.8445)
		(width 0.2)
		(layer "B.Cu")
		(net 333)
	)
	(segment
		(start 44.847962 161.8375)
		(end 43.597962 161.8375)
		(width 0.2)
		(layer "B.Cu")
		(net 333)
	)
	(segment
		(start 60.277962 164.2835)
		(end 59.669962 163.6755)
		(width 0.2)
		(layer "B.Cu")
		(net 334)
	)
	(segment
		(start 60.277962 165.4805)
		(end 60.277962 164.2835)
		(width 0.2)
		(layer "B.Cu")
		(net 334)
	)
	(segment
		(start 59.669962 163.6755)
		(end 59.169962 163.6755)
		(width 0.2)
		(layer "B.Cu")
		(net 334)
	)
	(segment
		(start 59.182962 161.8805)
		(end 57.905962 161.8805)
		(width 0.2)
		(layer "B.Cu")
		(net 335)
	)
	(segment
		(start 59.182962 161.8805)
		(end 59.182962 162.9155)
		(width 0.2)
		(layer "B.Cu")
		(net 335)
	)
	(segment
		(start 53.001962 165.4145)
		(end 53.001962 164.0995)
		(width 0.2)
		(layer "B.Cu")
		(net 336)
	)
	(segment
		(start 53.001962 164.0995)
		(end 52.518962 163.6165)
		(width 0.2)
		(layer "B.Cu")
		(net 336)
	)
	(segment
		(start 52.518962 163.6165)
		(end 52.018962 163.6165)
		(width 0.2)
		(layer "B.Cu")
		(net 336)
	)
	(segment
		(start 52.031962 161.8145)
		(end 50.811962 161.8145)
		(width 0.2)
		(layer "B.Cu")
		(net 337)
	)
	(segment
		(start 52.018962 162.8695)
		(end 52.018962 161.9345)
		(width 0.2)
		(layer "B.Cu")
		(net 337)
	)
	(segment
		(start 84.567964 136.307236)
		(end 84.567962 136.307238)
		(width 0.127)
		(layer "F.Cu")
		(net 338)
	)
	(segment
		(start 85.317962 136.307236)
		(end 84.567964 136.307236)
		(width 0.127)
		(layer "F.Cu")
		(net 338)
	)
	(via
		(at 84.567962 136.307238)
		(size 0.45)
		(drill 0.1)
		(layers "F.Cu" "B.Cu")
		(net 338)
	)
	(segment
		(start 77.217962 137.1665)
		(end 75.627962 138.7565)
		(width 0.127)
		(layer "B.Cu")
		(net 338)
	)
	(segment
		(start 75.627962 138.7565)
		(end 74.467962 138.7565)
		(width 0.127)
		(layer "B.Cu")
		(net 338)
	)
	(segment
		(start 84.567962 136.307238)
		(end 83.7087 137.1665)
		(width 0.127)
		(layer "B.Cu")
		(net 338)
	)
	(segment
		(start 75.287962 132.0865)
		(end 75.287962 130.6665)
		(width 0.127)
		(layer "B.Cu")
		(net 338)
	)
	(segment
		(start 83.7087 137.1665)
		(end 77.217962 137.1665)
		(width 0.127)
		(layer "B.Cu")
		(net 338)
	)
	(segment
		(start 75.287962 130.6665)
		(end 76.142962 129.8115)
		(width 0.127)
		(layer "B.Cu")
		(net 338)
	)
	(segment
		(start 76.142962 129.8115)
		(end 76.142962 128.9165)
		(width 0.127)
		(layer "B.Cu")
		(net 338)
	)
	(segment
		(start 73.947962 138.2365)
		(end 73.947962 133.4265)
		(width 0.127)
		(layer "B.Cu")
		(net 338)
	)
	(segment
		(start 73.947962 133.4265)
		(end 75.287962 132.0865)
		(width 0.127)
		(layer "B.Cu")
		(net 338)
	)
	(segment
		(start 74.467962 138.7565)
		(end 73.947962 138.2365)
		(width 0.127)
		(layer "B.Cu")
		(net 338)
	)
	(segment
		(start 51.537962 134.8315)
		(end 52.242962 134.8315)
		(width 0.2)
		(layer "F.Cu")
		(net 339)
	)
	(segment
		(start 54.067962 134.8165)
		(end 54.067962 133.9915)
		(width 0.2)
		(layer "F.Cu")
		(net 339)
	)
	(segment
		(start 54.047962 134.8365)
		(end 53.047962 134.8365)
		(width 0.2)
		(layer "F.Cu")
		(net 339)
	)
	(segment
		(start 54.067962 133.9915)
		(end 54.332962 133.7265)
		(width 0.2)
		(layer "F.Cu")
		(net 339)
	)
	(segment
		(start 54.332962 133.7265)
		(end 54.332962 132.9565)
		(width 0.2)
		(layer "F.Cu")
		(net 339)
	)
	(segment
		(start 53.032962 134.8315)
		(end 52.242962 134.8315)
		(width 0.2)
		(layer "F.Cu")
		(net 339)
	)
	(via
		(at 52.242962 134.8315)
		(size 0.45)
		(drill 0.1)
		(layers "F.Cu" "B.Cu")
		(net 339)
	)
	(segment
		(start 53.668962 134.8315)
		(end 52.242962 134.8315)
		(width 0.2)
		(layer "B.Cu")
		(net 339)
	)
	(segment
		(start 98.8 119.498538)
		(end 98.8 119.151962)
		(width 0.127)
		(layer "F.Cu")
		(net 340)
	)
	(segment
		(start 99.367962 120.0665)
		(end 98.8 119.498538)
		(width 0.127)
		(layer "F.Cu")
		(net 340)
	)
	(segment
		(start 98.8 119.151962)
		(end 98.847962 119.104)
		(width 0.127)
		(layer "F.Cu")
		(net 340)
	)
	(segment
		(start 99.367962 120.625)
		(end 99.367962 120.0665)
		(width 0.127)
		(layer "F.Cu")
		(net 340)
	)
	(segment
		(start 74.354962 127.3045)
		(end 74.367962 127.2915)
		(width 0.15)
		(layer "F.Cu")
		(net 341)
	)
	(segment
		(start 74.354962 128.2555)
		(end 74.354962 127.3045)
		(width 0.15)
		(layer "F.Cu")
		(net 341)
	)
	(via
		(at 74.367962 127.2915)
		(size 0.45)
		(drill 0.1)
		(layers "F.Cu" "B.Cu")
		(net 341)
	)
	(segment
		(start 75.642962 127.6145)
		(end 74.690962 127.6145)
		(width 0.15)
		(layer "B.Cu")
		(net 341)
	)
	(segment
		(start 75.642962 127.6145)
		(end 75.642962 126.6315)
		(width 0.15)
		(layer "B.Cu")
		(net 341)
	)
	(segment
		(start 74.690962 127.6145)
		(end 74.367962 127.2915)
		(width 0.15)
		(layer "B.Cu")
		(net 341)
	)
	(segment
		(start 142.728962 124.2825)
		(end 143.212962 124.7665)
		(width 0.2)
		(layer "F.Cu")
		(net 342)
	)
	(segment
		(start 142.728962 122.7665)
		(end 142.728962 124.2825)
		(width 0.2)
		(layer "F.Cu")
		(net 342)
	)
	(segment
		(start 143.212962 126.4565)
		(end 143.212962 124.7665)
		(width 0.2)
		(layer "F.Cu")
		(net 342)
	)
	(segment
		(start 87.327962 122.1665)
		(end 87.327962 123.1415)
		(width 0.2)
		(layer "B.Cu")
		(net 343)
	)
	(segment
		(start 87.327962 123.1415)
		(end 87.327962 124.3035)
		(width 0.2)
		(layer "B.Cu")
		(net 343)
	)
	(segment
		(start 85.152962 124.6665)
		(end 86.014962 124.6665)
		(width 0.254)
		(layer "B.Cu")
		(net 344)
	)
	(segment
		(start 86.014962 124.6665)
		(end 86.363962 124.3175)
		(width 0.254)
		(layer "B.Cu")
		(net 344)
	)
	(segment
		(start 85.152962 123.7165)
		(end 85.152962 124.6665)
		(width 0.254)
		(layer "B.Cu")
		(net 344)
	)
	(segment
		(start 92.367962 154.0915)
		(end 91.642962 154.0915)
		(width 0.127)
		(layer "F.Cu")
		(net 345)
	)
	(segment
		(start 91.447962 154.2865)
		(end 91.447962 154.3665)
		(width 0.127)
		(layer "F.Cu")
		(net 345)
	)
	(segment
		(start 91.642962 154.0915)
		(end 91.447962 154.2865)
		(width 0.127)
		(layer "F.Cu")
		(net 345)
	)
	(via
		(at 91.447962 154.3665)
		(size 0.45)
		(drill 0.1)
		(layers "F.Cu" "B.Cu")
		(net 345)
	)
	(segment
		(start 90.847962 154.3565)
		(end 91.437962 154.3565)
		(width 0.127)
		(layer "B.Cu")
		(net 345)
	)
	(segment
		(start 92.037962 154.3665)
		(end 91.447962 154.3665)
		(width 0.127)
		(layer "B.Cu")
		(net 345)
	)
	(segment
		(start 91.437962 154.3565)
		(end 91.447962 154.3665)
		(width 0.127)
		(layer "B.Cu")
		(net 345)
	)
	(segment
		(start 92.367962 153.4415)
		(end 91.767962 153.4415)
		(width 0.127)
		(layer "F.Cu")
		(net 346)
	)
	(segment
		(start 91.447962 153.3665)
		(end 91.692962 153.3665)
		(width 0.127)
		(layer "F.Cu")
		(net 346)
	)
	(segment
		(start 91.692962 153.3665)
		(end 91.767962 153.4415)
		(width 0.127)
		(layer "F.Cu")
		(net 346)
	)
	(via
		(at 91.447962 153.3665)
		(size 0.45)
		(drill 0.1)
		(layers "F.Cu" "B.Cu")
		(net 346)
	)
	(segment
		(start 91.437962 153.3565)
		(end 91.447962 153.3665)
		(width 0.127)
		(layer "B.Cu")
		(net 346)
	)
	(segment
		(start 90.847962 153.3565)
		(end 91.437962 153.3565)
		(width 0.127)
		(layer "B.Cu")
		(net 346)
	)
	(segment
		(start 92.037962 153.3665)
		(end 91.447962 153.3665)
		(width 0.127)
		(layer "B.Cu")
		(net 346)
	)
	(segment
		(start 93.917962 155.6415)
		(end 93.917962 156.5565)
		(width 0.127)
		(layer "F.Cu")
		(net 347)
	)
	(segment
		(start 91.877962 158.1915)
		(end 93.302962 156.7665)
		(width 0.127)
		(layer "F.Cu")
		(net 347)
	)
	(segment
		(start 93.917962 156.5565)
		(end 93.707962 156.7665)
		(width 0.127)
		(layer "F.Cu")
		(net 347)
	)
	(segment
		(start 93.707962 156.7665)
		(end 93.302962 156.7665)
		(width 0.127)
		(layer "F.Cu")
		(net 347)
	)
	(segment
		(start 91.342962 158.1915)
		(end 91.877962 158.1915)
		(width 0.127)
		(layer "F.Cu")
		(net 347)
	)
	(segment
		(start 91.740962 154.7415)
		(end 91.445962 155.0365)
		(width 0.127)
		(layer "F.Cu")
		(net 348)
	)
	(segment
		(start 92.367962 154.7415)
		(end 91.740962 154.7415)
		(width 0.127)
		(layer "F.Cu")
		(net 348)
	)
	(segment
		(start 92.367962 152.7915)
		(end 91.692962 152.7915)
		(width 0.127)
		(layer "F.Cu")
		(net 349)
	)
	(segment
		(start 91.462962 152.5615)
		(end 91.462962 152.4165)
		(width 0.127)
		(layer "F.Cu")
		(net 349)
	)
	(segment
		(start 91.692962 152.7915)
		(end 91.462962 152.5615)
		(width 0.127)
		(layer "F.Cu")
		(net 349)
	)
	(via
		(at 91.462962 152.4165)
		(size 0.45)
		(drill 0.1)
		(layers "F.Cu" "B.Cu")
		(net 349)
	)
	(segment
		(start 90.862962 152.4065)
		(end 91.452962 152.4065)
		(width 0.127)
		(layer "B.Cu")
		(net 349)
	)
	(segment
		(start 91.452962 152.4065)
		(end 91.462962 152.4165)
		(width 0.127)
		(layer "B.Cu")
		(net 349)
	)
	(segment
		(start 92.052962 152.4165)
		(end 91.462962 152.4165)
		(width 0.127)
		(layer "B.Cu")
		(net 349)
	)
	(segment
		(start 63.977962 162.2365)
		(end 63.977962 163.1915)
		(width 0.254)
		(layer "B.Cu")
		(net 350)
	)
	(segment
		(start 66.158962 163.3015)
		(end 66.158962 162.4475)
		(width 0.254)
		(layer "B.Cu")
		(net 350)
	)
	(segment
		(start 64.432962 163.6465)
		(end 65.813962 163.6465)
		(width 0.254)
		(layer "B.Cu")
		(net 350)
	)
	(segment
		(start 65.813962 163.6465)
		(end 66.158962 163.3015)
		(width 0.254)
		(layer "B.Cu")
		(net 350)
	)
	(segment
		(start 63.992962 163.1515)
		(end 63.992962 162.2515)
		(width 0.127)
		(layer "B.Cu")
		(net 350)
	)
	(segment
		(start 63.977962 163.1915)
		(end 64.432962 163.6465)
		(width 0.254)
		(layer "B.Cu")
		(net 350)
	)
	(segment
		(start 53.417962 154.3665)
		(end 53.417962 153.3265)
		(width 0.2)
		(layer "B.Cu")
		(net 351)
	)
	(segment
		(start 53.417962 153.3265)
		(end 53.427962 153.3165)
		(width 0.2)
		(layer "B.Cu")
		(net 351)
	)
	(segment
		(start 52.972962 153.3165)
		(end 53.427962 153.3165)
		(width 0.2)
		(layer "B.Cu")
		(net 351)
	)
	(segment
		(start 53.427962 153.3165)
		(end 53.867962 153.3165)
		(width 0.2)
		(layer "B.Cu")
		(net 351)
	)
	(segment
		(start 55.622962 153.9815)
		(end 55.567962 154.0365)
		(width 0.2)
		(layer "B.Cu")
		(net 352)
	)
	(segment
		(start 55.702962 153.9015)
		(end 55.622962 153.8215)
		(width 0.2)
		(layer "B.Cu")
		(net 352)
	)
	(segment
		(start 55.622962 153.8215)
		(end 55.622962 153.9815)
		(width 0.2)
		(layer "B.Cu")
		(net 352)
	)
	(segment
		(start 55.622962 153.8215)
		(end 55.622962 152.8915)
		(width 0.2)
		(layer "B.Cu")
		(net 352)
	)
	(segment
		(start 55.702962 153.9015)
		(end 56.167962 153.9015)
		(width 0.2)
		(layer "B.Cu")
		(net 352)
	)
	(segment
		(start 55.567962 154.0365)
		(end 55.702962 153.9015)
		(width 0.2)
		(layer "B.Cu")
		(net 352)
	)
	(segment
		(start 55.622962 152.8915)
		(end 55.267962 152.5365)
		(width 0.2)
		(layer "B.Cu")
		(net 352)
	)
	(segment
		(start 55.237962 154.3665)
		(end 55.567962 154.0365)
		(width 0.2)
		(layer "B.Cu")
		(net 352)
	)
	(segment
		(start 54.915962 154.3665)
		(end 55.237962 154.3665)
		(width 0.2)
		(layer "B.Cu")
		(net 352)
	)
	(segment
		(start 53.327962 158.4265)
		(end 53.327962 157.9565)
		(width 0.2)
		(layer "B.Cu")
		(net 353)
	)
	(segment
		(start 53.417962 157.8665)
		(end 53.417962 157.2655)
		(width 0.2)
		(layer "B.Cu")
		(net 353)
	)
	(segment
		(start 52.362962 159.3915)
		(end 53.327962 158.4265)
		(width 0.15)
		(layer "B.Cu")
		(net 353)
	)
	(segment
		(start 53.327962 157.9565)
		(end 53.417962 157.8665)
		(width 0.2)
		(layer "B.Cu")
		(net 353)
	)
	(segment
		(start 108.077962 132.5565)
		(end 108.542962 132.5565)
		(width 0.254)
		(layer "B.Cu")
		(net 354)
	)
	(segment
		(start 108.077962 132.5565)
		(end 107.127962 132.5565)
		(width 0.254)
		(layer "B.Cu")
		(net 354)
	)
	(segment
		(start 108.811962 132.2875)
		(end 108.542962 132.5565)
		(width 0.254)
		(layer "B.Cu")
		(net 354)
	)
	(segment
		(start 109.313962 132.2875)
		(end 108.811962 132.2875)
		(width 0.254)
		(layer "B.Cu")
		(net 354)
	)
	(segment
		(start 65.207962 161.2165)
		(end 64.277962 161.2165)
		(width 0.254)
		(layer "B.Cu")
		(net 355)
	)
	(segment
		(start 65.208962 162.4475)
		(end 65.208962 161.1675)
		(width 0.254)
		(layer "B.Cu")
		(net 355)
	)
	(segment
		(start 47.700462 131.4165)
		(end 48.236962 131.4165)
		(width 0.2)
		(layer "F.Cu")
		(net 356)
	)
	(segment
		(start 47.400462 131.7165)
		(end 47.700462 131.4165)
		(width 0.2)
		(layer "F.Cu")
		(net 356)
	)
	(segment
		(start 47.027962 131.7165)
		(end 47.400462 131.7165)
		(width 0.2)
		(layer "F.Cu")
		(net 356)
	)
	(segment
		(start 47.542962 130.7665)
		(end 47.544962 130.7645)
		(width 0.2)
		(layer "F.Cu")
		(net 357)
	)
	(segment
		(start 47.027962 130.7665)
		(end 47.542962 130.7665)
		(width 0.2)
		(layer "F.Cu")
		(net 357)
	)
	(segment
		(start 47.544962 130.7645)
		(end 48.236962 130.7645)
		(width 0.2)
		(layer "F.Cu")
		(net 357)
	)
	(segment
		(start 47.032962 132.80987)
		(end 47.776332 132.0665)
		(width 0.2)
		(layer "F.Cu")
		(net 358)
	)
	(segment
		(start 47.776332 132.0665)
		(end 48.236962 132.0665)
		(width 0.2)
		(layer "F.Cu")
		(net 358)
	)
	(segment
		(start 51.257962 125.2365)
		(end 51.257962 125.9265)
		(width 0.2)
		(layer "F.Cu")
		(net 359)
	)
	(segment
		(start 50.917962 126.2665)
		(end 50.917962 128.1865)
		(width 0.2)
		(layer "F.Cu")
		(net 359)
	)
	(segment
		(start 50.561962 128.5425)
		(end 50.561962 129.0895)
		(width 0.2)
		(layer "F.Cu")
		(net 359)
	)
	(segment
		(start 50.917962 128.1865)
		(end 50.561962 128.5425)
		(width 0.2)
		(layer "F.Cu")
		(net 359)
	)
	(segment
		(start 51.257962 125.9265)
		(end 50.917962 126.2665)
		(width 0.2)
		(layer "F.Cu")
		(net 359)
	)
	(segment
		(start 47.779962 130.1155)
		(end 48.236962 130.1155)
		(width 0.2)
		(layer "F.Cu")
		(net 360)
	)
	(segment
		(start 47.455962 129.7915)
		(end 47.779962 130.1155)
		(width 0.2)
		(layer "F.Cu")
		(net 360)
	)
	(segment
		(start 47.027962 129.7915)
		(end 47.455962 129.7915)
		(width 0.2)
		(layer "F.Cu")
		(net 360)
	)
	(segment
		(start 52.136462 129.828)
		(end 53.067962 128.8965)
		(width 0.127)
		(layer "F.Cu")
		(net 361)
	)
	(segment
		(start 53.067962 128.8965)
		(end 54.362962 128.8965)
		(width 0.127)
		(layer "F.Cu")
		(net 361)
	)
	(segment
		(start 51.213962 129.6025)
		(end 51.439462 129.828)
		(width 0.127)
		(layer "F.Cu")
		(net 361)
	)
	(segment
		(start 51.213962 129.0895)
		(end 51.213962 129.6025)
		(width 0.127)
		(layer "F.Cu")
		(net 361)
	)
	(segment
		(start 51.439462 129.828)
		(end 52.136462 129.828)
		(width 0.127)
		(layer "F.Cu")
		(net 361)
	)
	(segment
		(start 53.94545 130.8765)
		(end 54.342962 130.8765)
		(width 0.2)
		(layer "F.Cu")
		(net 362)
	)
	(segment
		(start 52.888962 131.4165)
		(end 53.405448 131.4165)
		(width 0.2)
		(layer "F.Cu")
		(net 362)
	)
	(segment
		(start 53.405448 131.4165)
		(end 53.94545 130.8765)
		(width 0.2)
		(layer "F.Cu")
		(net 362)
	)
	(segment
		(start 50.612962 134.4075)
		(end 50.612962 134.8565)
		(width 0.2)
		(layer "F.Cu")
		(net 363)
	)
	(segment
		(start 50.561962 134.3565)
		(end 50.612962 134.4075)
		(width 0.2)
		(layer "F.Cu")
		(net 363)
	)
	(segment
		(start 50.561962 134.3565)
		(end 50.561962 133.7415)
		(width 0.2)
		(layer "F.Cu")
		(net 363)
	)
	(segment
		(start 53.607962 132.0665)
		(end 53.847962 131.8265)
		(width 0.2)
		(layer "F.Cu")
		(net 364)
	)
	(segment
		(start 53.847962 131.8265)
		(end 54.282962 131.8265)
		(width 0.2)
		(layer "F.Cu")
		(net 364)
	)
	(segment
		(start 52.888962 132.0665)
		(end 53.607962 132.0665)
		(width 0.2)
		(layer "F.Cu")
		(net 364)
	)
	(segment
		(start 53.663962 130.4305)
		(end 53.329962 130.7645)
		(width 0.2)
		(layer "F.Cu")
		(net 365)
	)
	(segment
		(start 54.342962 129.9265)
		(end 53.977962 129.9265)
		(width 0.2)
		(layer "F.Cu")
		(net 365)
	)
	(segment
		(start 53.663962 130.2405)
		(end 53.663962 130.4305)
		(width 0.2)
		(layer "F.Cu")
		(net 365)
	)
	(segment
		(start 53.329962 130.7645)
		(end 52.888962 130.7645)
		(width 0.2)
		(layer "F.Cu")
		(net 365)
	)
	(segment
		(start 53.977962 129.9265)
		(end 53.663962 130.2405)
		(width 0.2)
		(layer "F.Cu")
		(net 365)
	)
	(segment
		(start 52.027962 136.1165)
		(end 53.652962 136.1165)
		(width 0.2)
		(layer "B.Cu")
		(net 366)
	)
	(segment
		(start 61.632962 136.1165)
		(end 59.933962 136.1165)
		(width 0.2)
		(layer "B.Cu")
		(net 367)
	)
	(segment
		(start 52.338962 167.7545)
		(end 52.338962 169.8775)
		(width 0.2)
		(layer "B.Cu")
		(net 368)
	)
	(segment
		(start 51.477962 169.9165)
		(end 52.377962 169.9165)
		(width 0.2)
		(layer "B.Cu")
		(net 368)
	)
	(segment
		(start 136.443962 161.0175)
		(end 136.443962 161.625278)
		(width 0.127)
		(layer "F.Cu")
		(net 369)
	)
	(segment
		(start 136.20174 161.8675)
		(end 134.166962 161.8675)
		(width 0.127)
		(layer "F.Cu")
		(net 369)
	)
	(segment
		(start 131.497962 162.4865)
		(end 131.307962 162.2965)
		(width 0.127)
		(layer "F.Cu")
		(net 369)
	)
	(segment
		(start 136.443962 161.625278)
		(end 136.20174 161.8675)
		(width 0.127)
		(layer "F.Cu")
		(net 369)
	)
	(segment
		(start 131.307962 161.2565)
		(end 131.547962 161.0165)
		(width 0.127)
		(layer "F.Cu")
		(net 369)
	)
	(segment
		(start 98.792962 152.1415)
		(end 98.977962 152.3265)
		(width 0.127)
		(layer "F.Cu")
		(net 369)
	)
	(segment
		(start 136.367962 160.9415)
		(end 136.443962 161.0175)
		(width 0.127)
		(layer "F.Cu")
		(net 369)
	)
	(segment
		(start 98.067962 152.1415)
		(end 98.792962 152.1415)
		(width 0.127)
		(layer "F.Cu")
		(net 369)
	)
	(segment
		(start 133.547962 162.4865)
		(end 131.497962 162.4865)
		(width 0.127)
		(layer "F.Cu")
		(net 369)
	)
	(segment
		(start 131.547962 161.0165)
		(end 131.937962 161.0165)
		(width 0.127)
		(layer "F.Cu")
		(net 369)
	)
	(segment
		(start 134.166962 161.8675)
		(end 133.547962 162.4865)
		(width 0.127)
		(layer "F.Cu")
		(net 369)
	)
	(segment
		(start 136.367962 160.9415)
		(end 136.367962 159.9195)
		(width 0.127)
		(layer "F.Cu")
		(net 369)
	)
	(segment
		(start 131.307962 162.2965)
		(end 131.307962 161.2565)
		(width 0.127)
		(layer "F.Cu")
		(net 369)
	)
	(segment
		(start 131.963962 159.9155)
		(end 131.963962 160.9855)
		(width 0.2)
		(layer "F.Cu")
		(net 369)
	)
	(via
		(at 136.367962 160.9415)
		(size 0.45)
		(drill 0.1)
		(layers "F.Cu" "B.Cu")
		(net 369)
	)
	(via
		(at 98.977962 152.3265)
		(size 0.45)
		(drill 0.1)
		(layers "F.Cu" "B.Cu")
		(net 369)
	)
	(via
		(at 120.572962 161.2715)
		(size 0.45)
		(drill 0.1)
		(layers "F.Cu" "B.Cu")
		(net 369)
	)
	(segment
		(start 117.983462 163.861)
		(end 108.349698 163.861)
		(width 0.127)
		(layer "In2.Cu")
		(net 369)
	)
	(segment
		(start 108.349698 163.861)
		(end 98.977962 154.489264)
		(width 0.127)
		(layer "In2.Cu")
		(net 369)
	)
	(segment
		(start 98.977962 154.489264)
		(end 98.977962 152.3265)
		(width 0.127)
		(layer "In2.Cu")
		(net 369)
	)
	(segment
		(start 120.572962 161.2715)
		(end 117.983462 163.861)
		(width 0.127)
		(layer "In2.Cu")
		(net 369)
	)
	(segment
		(start 136.130462 161.955)
		(end 136.443962 161.6415)
		(width 0.127)
		(layer "In3.Cu")
		(net 369)
	)
	(segment
		(start 132.517962 160.9265)
		(end 133.546462 161.955)
		(width 0.127)
		(layer "In3.Cu")
		(net 369)
	)
	(segment
		(start 133.546462 161.955)
		(end 136.130462 161.955)
		(width 0.127)
		(layer "In3.Cu")
		(net 369)
	)
	(segment
		(start 120.917962 160.9265)
		(end 132.517962 160.9265)
		(width 0.127)
		(layer "In3.Cu")
		(net 369)
	)
	(segment
		(start 120.572962 161.2715)
		(end 120.917962 160.9265)
		(width 0.127)
		(layer "In3.Cu")
		(net 369)
	)
	(segment
		(start 136.443962 161.6415)
		(end 136.443962 161.282722)
		(width 0.127)
		(layer "In3.Cu")
		(net 369)
	)
	(segment
		(start 136.367962 161.206722)
		(end 136.367962 160.9415)
		(width 0.127)
		(layer "In3.Cu")
		(net 369)
	)
	(segment
		(start 136.443962 161.282722)
		(end 136.367962 161.206722)
		(width 0.127)
		(layer "In3.Cu")
		(net 369)
	)
	(segment
		(start 135.137962 157.1615)
		(end 135.137962 156.4665)
		(width 0.2)
		(layer "F.Cu")
		(net 370)
	)
	(segment
		(start 135.137962 157.1615)
		(end 136.209962 157.1615)
		(width 0.2)
		(layer "F.Cu")
		(net 370)
	)
	(segment
		(start 135.137962 156.4665)
		(end 134.787962 156.1165)
		(width 0.2)
		(layer "F.Cu")
		(net 370)
	)
	(segment
		(start 130.717962 156.627962)
		(end 130.39 156.3)
		(width 0.2)
		(layer "F.Cu")
		(net 371)
	)
	(segment
		(start 131.963962 157.3155)
		(end 130.726962 157.3155)
		(width 0.2)
		(layer "F.Cu")
		(net 371)
	)
	(segment
		(start 130.717962 157.3065)
		(end 130.717962 156.627962)
		(width 0.2)
		(layer "F.Cu")
		(net 371)
	)
	(segment
		(start 137.217962 160.9815)
		(end 137.217962 160.0115)
		(width 0.2)
		(layer "F.Cu")
		(net 372)
	)
	(segment
		(start 132.913962 159.9155)
		(end 132.913962 160.9875)
		(width 0.2)
		(layer "F.Cu")
		(net 373)
	)
	(segment
		(start 73.817962 168.8415)
		(end 73.817962 168.2415)
		(width 0.2)
		(layer "F.Cu")
		(net 374)
	)
	(segment
		(start 74.582962 167.6665)
		(end 74.582962 166.7165)
		(width 0.2)
		(layer "F.Cu")
		(net 374)
	)
	(segment
		(start 73.817962 168.2415)
		(end 74.392962 167.6665)
		(width 0.2)
		(layer "F.Cu")
		(net 374)
	)
	(segment
		(start 72.817962 167.9415)
		(end 73.347962 167.4115)
		(width 0.127)
		(layer "F.Cu")
		(net 375)
	)
	(segment
		(start 72.817962 168.8415)
		(end 72.817962 167.9415)
		(width 0.127)
		(layer "F.Cu")
		(net 375)
	)
	(segment
		(start 73.347962 166.4365)
		(end 73.347962 167.4115)
		(width 0.127)
		(layer "F.Cu")
		(net 375)
	)
	(segment
		(start 98.011292 127.0205)
		(end 97.284292 127.0205)
		(width 0.127)
		(layer "F.Cu")
		(net 376)
	)
	(segment
		(start 96.627962 127.67683)
		(end 96.627962 129.1415)
		(width 0.127)
		(layer "F.Cu")
		(net 376)
	)
	(segment
		(start 97.284292 127.0205)
		(end 96.627962 127.67683)
		(width 0.127)
		(layer "F.Cu")
		(net 376)
	)
	(segment
		(start 79.000226 136.359236)
		(end 77.903962 136.359236)
		(width 0.15)
		(layer "F.Cu")
		(net 377)
	)
	(segment
		(start 79.030463 136.328999)
		(end 79.000226 136.359236)
		(width 0.15)
		(layer "F.Cu")
		(net 377)
	)
	(via
		(at 79.030463 136.328999)
		(size 0.45)
		(drill 0.1)
		(layers "F.Cu" "B.Cu")
		(net 377)
	)
	(segment
		(start 79.332962 136.0265)
		(end 80.342962 136.0265)
		(width 0.15)
		(layer "B.Cu")
		(net 377)
	)
	(segment
		(start 81.342962 136.0265)
		(end 80.342962 136.0265)
		(width 0.127)
		(layer "B.Cu")
		(net 377)
	)
	(segment
		(start 81.292962 136.0265)
		(end 80.342962 136.0265)
		(width 0.15)
		(layer "B.Cu")
		(net 377)
	)
	(segment
		(start 79.030463 136.328999)
		(end 79.332962 136.0265)
		(width 0.15)
		(layer "B.Cu")
		(net 377)
	)
	(segment
		(start 93.342962 134.607236)
		(end 93.657962 134.292236)
		(width 0.127)
		(layer "F.Cu")
		(net 378)
	)
	(segment
		(start 93.657962 134.292236)
		(end 95.092962 134.292236)
		(width 0.127)
		(layer "F.Cu")
		(net 378)
	)
	(segment
		(start 90.548962 134.607236)
		(end 93.342962 134.607236)
		(width 0.127)
		(layer "F.Cu")
		(net 378)
	)
	(segment
		(start 90.467962 134.526236)
		(end 90.548962 134.607236)
		(width 0.127)
		(layer "F.Cu")
		(net 378)
	)
	(segment
		(start 90.467962 133.957236)
		(end 90.467962 134.526236)
		(width 0.127)
		(layer "F.Cu")
		(net 378)
	)
	(segment
		(start 84.825241 135.907236)
		(end 84.635921 135.717916)
		(width 0.127)
		(layer "F.Cu")
		(net 379)
	)
	(segment
		(start 85.317962 135.907236)
		(end 84.825241 135.907236)
		(width 0.127)
		(layer "F.Cu")
		(net 379)
	)
	(via
		(at 84.635921 135.717916)
		(size 0.45)
		(drill 0.1)
		(layers "F.Cu" "B.Cu")
		(net 379)
	)
	(segment
		(start 83.4835 136.0165)
		(end 82.477962 136.0165)
		(width 0.127)
		(layer "B.Cu")
		(net 379)
	)
	(segment
		(start 83.5 136)
		(end 84.05 136)
		(width 0.127)
		(layer "B.Cu")
		(net 379)
	)
	(segment
		(start 83.5 136)
		(end 83.4835 136.0165)
		(width 0.127)
		(layer "B.Cu")
		(net 379)
	)
	(segment
		(start 84.332084 135.717916)
		(end 84.635921 135.717916)
		(width 0.127)
		(layer "B.Cu")
		(net 379)
	)
	(segment
		(start 84.05 136)
		(end 84.332084 135.717916)
		(width 0.127)
		(layer "B.Cu")
		(net 379)
	)
	(segment
		(start 109.589962 137.4665)
		(end 109.589962 132.0945)
		(width 0.2)
		(layer "F.Cu")
		(net 380)
	)
	(segment
		(start 108.867962 137.4665)
		(end 109.417962 137.4665)
		(width 0.2)
		(layer "F.Cu")
		(net 380)
	)
	(segment
		(start 116.092962 141.5165)
		(end 117.717962 141.5165)
		(width 0.2)
		(layer "F.Cu")
		(net 380)
	)
	(segment
		(start 114.242962 139.6665)
		(end 112.042962 137.4665)
		(width 0.2)
		(layer "F.Cu")
		(net 380)
	)
	(segment
		(start 109.417962 137.4665)
		(end 109.589962 137.4665)
		(width 0.2)
		(layer "F.Cu")
		(net 380)
	)
	(segment
		(start 112.042962 137.4665)
		(end 109.417962 137.4665)
		(width 0.2)
		(layer "F.Cu")
		(net 380)
	)
	(segment
		(start 96.517962 149.9415)
		(end 96.517962 148.9365)
		(width 0.127)
		(layer "F.Cu")
		(net 380)
	)
	(segment
		(start 96.517962 148.9365)
		(end 96.597962 148.8565)
		(width 0.127)
		(layer "F.Cu")
		(net 380)
	)
	(segment
		(start 116.092962 141.5165)
		(end 114.242962 139.6665)
		(width 0.2)
		(layer "F.Cu")
		(net 380)
	)
	(segment
		(start 110.667962 131.0165)
		(end 109.589962 132.0945)
		(width 0.2)
		(layer "F.Cu")
		(net 380)
	)
	(via
		(at 110.667962 131.0165)
		(size 0.45)
		(drill 0.1)
		(layers "F.Cu" "B.Cu")
		(net 380)
	)
	(via
		(at 96.597962 148.8565)
		(size 0.45)
		(drill 0.1)
		(layers "F.Cu" "B.Cu")
		(net 380)
	)
	(via
		(at 108.867962 137.4665)
		(size 0.45)
		(drill 0.1)
		(layers "F.Cu" "B.Cu")
		(net 380)
	)
	(segment
		(start 110.667962 131.0165)
		(end 110.263962 131.4205)
		(width 0.2)
		(layer "B.Cu")
		(net 380)
	)
	(segment
		(start 110.263962 131.4205)
		(end 110.263962 132.2875)
		(width 0.2)
		(layer "B.Cu")
		(net 380)
	)
	(segment
		(start 98.56274 148.8565)
		(end 96.597962 148.8565)
		(width 0.127)
		(layer "In2.Cu")
		(net 380)
	)
	(segment
		(start 108.867962 137.4665)
		(end 107.567962 138.7665)
		(width 0.127)
		(layer "In2.Cu")
		(net 380)
	)
	(segment
		(start 107.567962 139.851278)
		(end 98.56274 148.8565)
		(width 0.127)
		(layer "In2.Cu")
		(net 380)
	)
	(segment
		(start 107.567962 138.7665)
		(end 107.567962 139.851278)
		(width 0.127)
		(layer "In2.Cu")
		(net 380)
	)
	(segment
		(start 74.542962 171.0665)
		(end 75.287962 171.0665)
		(width 0.127)
		(layer "F.Cu")
		(net 381)
	)
	(segment
		(start 75.287962 171.0665)
		(end 75.707962 170.6465)
		(width 0.127)
		(layer "F.Cu")
		(net 381)
	)
	(segment
		(start 74.542962 169.5665)
		(end 75.617962 169.5665)
		(width 0.127)
		(layer "F.Cu")
		(net 382)
	)
	(segment
		(start 71.317962 175.456577)
		(end 71.231462 175.543077)
		(width 0.127)
		(layer "F.Cu")
		(net 383)
	)
	(segment
		(start 71.231462 176.083153)
		(end 70.567962 176.746653)
		(width 0.127)
		(layer "F.Cu")
		(net 383)
	)
	(segment
		(start 71.317962 174.7915)
		(end 71.317962 175.456577)
		(width 0.127)
		(layer "F.Cu")
		(net 383)
	)
	(segment
		(start 71.231462 175.543077)
		(end 71.231462 176.083153)
		(width 0.127)
		(layer "F.Cu")
		(net 383)
	)
	(segment
		(start 70.567962 176.746653)
		(end 70.567962 178.2915)
		(width 0.127)
		(layer "F.Cu")
		(net 383)
	)
	(segment
		(start 94.494962 139.107236)
		(end 94.715726 139.328)
		(width 0.127)
		(layer "F.Cu")
		(net 384)
	)
	(segment
		(start 95.088726 139.328)
		(end 95.517962 139.757236)
		(width 0.127)
		(layer "F.Cu")
		(net 384)
	)
	(segment
		(start 94.715726 139.328)
		(end 95.088726 139.328)
		(width 0.127)
		(layer "F.Cu")
		(net 384)
	)
	(segment
		(start 94.017962 139.107236)
		(end 94.494962 139.107236)
		(width 0.127)
		(layer "F.Cu")
		(net 384)
	)
	(segment
		(start 94.167226 133.957236)
		(end 94.5 133.624462)
		(width 0.127)
		(layer "F.Cu")
		(net 385)
	)
	(segment
		(start 94.5 132.95)
		(end 95.1 132.35)
		(width 0.127)
		(layer "F.Cu")
		(net 385)
	)
	(segment
		(start 94.5 133.624462)
		(end 94.5 132.95)
		(width 0.127)
		(layer "F.Cu")
		(net 385)
	)
	(segment
		(start 93.267962 133.957236)
		(end 94.167226 133.957236)
		(width 0.127)
		(layer "F.Cu")
		(net 385)
	)
	(segment
		(start 93.367962 146.7665)
		(end 94.317962 146.7665)
		(width 0.15)
		(layer "F.Cu")
		(net 386)
	)
	(segment
		(start 93.167962 146.9665)
		(end 93.367962 146.7665)
		(width 0.15)
		(layer "F.Cu")
		(net 386)
	)
	(segment
		(start 95.217962 147.6665)
		(end 95.217962 149.9415)
		(width 0.15)
		(layer "F.Cu")
		(net 386)
	)
	(segment
		(start 94.317962 146.7665)
		(end 95.217962 147.6665)
		(width 0.15)
		(layer "F.Cu")
		(net 386)
	)
	(via
		(at 93.167962 146.9665)
		(size 0.45)
		(drill 0.1)
		(layers "F.Cu" "B.Cu")
		(net 386)
	)
	(via
		(at 77.007962 143.4465)
		(size 0.45)
		(drill 0.1)
		(layers "F.Cu" "B.Cu")
		(net 386)
	)
	(segment
		(start 63.782962 134.8315)
		(end 69.542962 140.5915)
		(width 0.2)
		(layer "B.Cu")
		(net 386)
	)
	(segment
		(start 69.542962 140.5915)
		(end 74.092962 140.5915)
		(width 0.2)
		(layer "B.Cu")
		(net 386)
	)
	(segment
		(start 59.917962 134.8315)
		(end 63.782962 134.8315)
		(width 0.2)
		(layer "B.Cu")
		(net 386)
	)
	(segment
		(start 74.092962 140.5915)
		(end 76.947962 143.4465)
		(width 0.2)
		(layer "B.Cu")
		(net 386)
	)
	(segment
		(start 76.947962 143.4465)
		(end 77.007962 143.4465)
		(width 0.2)
		(layer "B.Cu")
		(net 386)
	)
	(segment
		(start 93.167962 146.9665)
		(end 92.781862 146.5804)
		(width 0.2)
		(layer "In2.Cu")
		(net 386)
	)
	(segment
		(start 81.797962 143.4465)
		(end 77.007962 143.4465)
		(width 0.2)
		(layer "In2.Cu")
		(net 386)
	)
	(segment
		(start 92.781862 146.5804)
		(end 84.931862 146.5804)
		(width 0.2)
		(layer "In2.Cu")
		(net 386)
	)
	(segment
		(start 84.931862 146.5804)
		(end 81.797962 143.4465)
		(width 0.2)
		(layer "In2.Cu")
		(net 386)
	)
	(segment
		(start 100.167962 120.625)
		(end 100.167962 120.204)
		(width 0.127)
		(layer "F.Cu")
		(net 432)
	)
	(segment
		(start 100.167962 120.204)
		(end 100.767962 119.604)
		(width 0.127)
		(layer "F.Cu")
		(net 432)
	)
	(segment
		(start 99.441462 123.203)
		(end 99.441462 123.313)
		(width 0.127)
		(layer "F.Cu")
		(net 433)
	)
	(segment
		(start 99.769962 122.8745)
		(end 99.441462 123.203)
		(width 0.127)
		(layer "F.Cu")
		(net 433)
	)
	(segment
		(start 99.441462 123.313)
		(end 98.775 123.979462)
		(width 0.127)
		(layer "F.Cu")
		(net 433)
	)
	(segment
		(start 99.769962 122.275)
		(end 99.769962 122.8745)
		(width 0.127)
		(layer "F.Cu")
		(net 433)
	)
	(segment
		(start 98.775 123.979462)
		(end 98.775 124.375)
		(width 0.127)
		(layer "F.Cu")
		(net 433)
	)
	(segment
		(start 99.769962 120.625)
		(end 99.769962 119.547)
		(width 0.127)
		(layer "F.Cu")
		(net 434)
	)
	(segment
		(start 98.892962 120.0165)
		(end 98.181462 120.0165)
		(width 0.127)
		(layer "F.Cu")
		(net 435)
	)
	(segment
		(start 98.969962 120.625)
		(end 98.969962 120.0935)
		(width 0.127)
		(layer "F.Cu")
		(net 435)
	)
	(segment
		(start 98.181462 120.0165)
		(end 97.697962 120.5)
		(width 0.127)
		(layer "F.Cu")
		(net 435)
	)
	(segment
		(start 98.969962 120.0935)
		(end 98.892962 120.0165)
		(width 0.127)
		(layer "F.Cu")
		(net 435)
	)
	(segment
		(start 98.844962 121.249)
		(end 98.260462 121.249)
		(width 0.127)
		(layer "F.Cu")
		(net 436)
	)
	(segment
		(start 98.042962 121.4665)
		(end 97.592962 121.4665)
		(width 0.127)
		(layer "F.Cu")
		(net 436)
	)
	(segment
		(start 98.260462 121.249)
		(end 98.042962 121.4665)
		(width 0.127)
		(layer "F.Cu")
		(net 436)
	)
	(segment
		(start 98.233462 121.651)
		(end 98.844962 121.651)
		(width 0.127)
		(layer "F.Cu")
		(net 437)
	)
	(segment
		(start 97.697962 122.1865)
		(end 98.233462 121.651)
		(width 0.127)
		(layer "F.Cu")
		(net 437)
	)
	(segment
		(start 87.519962 133.332236)
		(end 87.519962 132.495882)
		(width 0.127)
		(layer "F.Cu")
		(net 438)
	)
	(segment
		(start 87.667962 133.480236)
		(end 87.519962 133.332236)
		(width 0.127)
		(layer "F.Cu")
		(net 438)
	)
	(segment
		(start 87.667962 133.957236)
		(end 87.667962 133.480236)
		(width 0.127)
		(layer "F.Cu")
		(net 438)
	)
	(segment
		(start 87.519962 132.495882)
		(end 87.974344 132.0415)
		(width 0.127)
		(layer "F.Cu")
		(net 438)
	)
	(segment
		(start 88.067962 133.957236)
		(end 88.067962 132.9665)
		(width 0.127)
		(layer "F.Cu")
		(net 439)
	)
	(segment
		(start 87.267962 131.94459)
		(end 87.267962 133.957236)
		(width 0.127)
		(layer "F.Cu")
		(net 440)
	)
	(segment
		(start 87.625117 130.925117)
		(end 87.625117 131.587435)
		(width 0.127)
		(layer "F.Cu")
		(net 440)
	)
	(segment
		(start 87.625117 131.587435)
		(end 87.267962 131.94459)
		(width 0.127)
		(layer "F.Cu")
		(net 440)
	)
	(segment
		(start 87.23 130.53)
		(end 87.625117 130.925117)
		(width 0.127)
		(layer "F.Cu")
		(net 440)
	)
	(segment
		(start 82.170306 136.955)
		(end 80.995 136.955)
		(width 0.127)
		(layer "F.Cu")
		(net 441)
	)
	(segment
		(start 80.995 136.955)
		(end 80.3 137.65)
		(width 0.127)
		(layer "F.Cu")
		(net 441)
	)
	(segment
		(start 85.317962 136.707236)
		(end 84.840962 136.707236)
		(width 0.127)
		(layer "F.Cu")
		(net 441)
	)
	(segment
		(start 84.840962 136.707236)
		(end 84.675462 136.872736)
		(width 0.127)
		(layer "F.Cu")
		(net 441)
	)
	(segment
		(start 84.675462 136.872736)
		(end 82.25257 136.872736)
		(width 0.127)
		(layer "F.Cu")
		(net 441)
	)
	(segment
		(start 82.25257 136.872736)
		(end 82.170306 136.955)
		(width 0.127)
		(layer "F.Cu")
		(net 441)
	)
	(segment
		(start 81.831688 137.65)
		(end 81.3 137.65)
		(width 0.127)
		(layer "F.Cu")
		(net 442)
	)
	(segment
		(start 85.300462 137.124736)
		(end 82.356952 137.124736)
		(width 0.127)
		(layer "F.Cu")
		(net 442)
	)
	(segment
		(start 82.356952 137.124736)
		(end 81.831688 137.65)
		(width 0.127)
		(layer "F.Cu")
		(net 442)
	)
	(segment
		(start 73.707962 130.6365)
		(end 74.537962 130.6365)
		(width 0.5)
		(layer "F.Cu")
		(net 443)
	)
	(segment
		(start 74.537962 129.8365)
		(end 74.542962 129.8415)
		(width 0.5)
		(layer "F.Cu")
		(net 443)
	)
	(segment
		(start 74.537962 130.6365)
		(end 74.542962 130.6415)
		(width 0.5)
		(layer "F.Cu")
		(net 443)
	)
	(segment
		(start 73.707962 129.8365)
		(end 74.537962 129.8365)
		(width 0.5)
		(layer "F.Cu")
		(net 443)
	)
	(via
		(at 73.707962 130.6365)
		(size 0.5)
		(drill 0.15)
		(layers "F.Cu" "B.Cu")
		(net 443)
	)
	(via
		(at 48.057962 164.2365)
		(size 0.5)
		(drill 0.15)
		(layers "F.Cu" "B.Cu")
		(net 443)
	)
	(via
		(at 50.757962 165.5565)
		(size 0.5)
		(drill 0.15)
		(layers "F.Cu" "B.Cu")
		(net 443)
	)
	(via
		(at 73.887962 131.8865)
		(size 0.5)
		(drill 0.15)
		(layers "F.Cu" "B.Cu")
		(net 443)
	)
	(via
		(at 73.227962 131.7065)
		(size 0.5)
		(drill 0.15)
		(layers "F.Cu" "B.Cu")
		(net 443)
	)
	(via
		(at 50.757962 166.3565)
		(size 0.5)
		(drill 0.15)
		(layers "F.Cu" "B.Cu")
		(net 443)
	)
	(via
		(at 49.417962 165.5565)
		(size 0.5)
		(drill 0.15)
		(layers "F.Cu" "B.Cu")
		(net 443)
	)
	(via
		(at 48.067962 163.5365)
		(size 0.5)
		(drill 0.15)
		(layers "F.Cu" "B.Cu")
		(net 443)
	)
	(via
		(at 75.342962 129.8415)
		(size 0.5)
		(drill 0.15)
		(layers "F.Cu" "B.Cu")
		(net 443)
	)
	(via
		(at 50.097962 166.3565)
		(size 0.5)
		(drill 0.15)
		(layers "F.Cu" "B.Cu")
		(net 443)
	)
	(via
		(at 73.707962 129.8365)
		(size 0.5)
		(drill 0.15)
		(layers "F.Cu" "B.Cu")
		(net 443)
	)
	(via
		(at 74.542962 130.6415)
		(size 0.5)
		(drill 0.15)
		(layers "F.Cu" "B.Cu")
		(net 443)
	)
	(via
		(at 49.417962 166.3565)
		(size 0.5)
		(drill 0.15)
		(layers "F.Cu" "B.Cu")
		(net 443)
	)
	(via
		(at 73.297962 132.4565)
		(size 0.5)
		(drill 0.15)
		(layers "F.Cu" "B.Cu")
		(net 443)
	)
	(via
		(at 48.767962 165.8965)
		(size 0.5)
		(drill 0.15)
		(layers "F.Cu" "B.Cu")
		(net 443)
	)
	(via
		(at 76.142962 130.6415)
		(size 0.5)
		(drill 0.15)
		(layers "F.Cu" "B.Cu")
		(net 443)
	)
	(via
		(at 50.097962 165.5565)
		(size 0.5)
		(drill 0.15)
		(layers "F.Cu" "B.Cu")
		(net 443)
	)
	(segment
		(start 48.067962 163.5365)
		(end 48.872962 163.5365)
		(width 0.5)
		(layer "B.Cu")
		(net 443)
	)
	(segment
		(start 48.767962 165.8965)
		(end 48.767962 164.8635)
		(width 0.35)
		(layer "B.Cu")
		(net 443)
	)
	(segment
		(start 48.767962 164.8635)
		(end 49.766962 163.8645)
		(width 0.35)
		(layer "B.Cu")
		(net 443)
	)
	(segment
		(start 53.917962 165.456382)
		(end 53.414844 165.9595)
		(width 0.2)
		(layer "B.Cu")
		(net 443)
	)
	(segment
		(start 50.757962 166.3565)
		(end 50.757962 164.8555)
		(width 0.35)
		(layer "B.Cu")
		(net 443)
	)
	(segment
		(start 48.057962 164.2365)
		(end 48.962962 164.2365)
		(width 0.5)
		(layer "B.Cu")
		(net 443)
	)
	(segment
		(start 48.872962 163.5365)
		(end 48.967962 163.4415)
		(width 0.5)
		(layer "B.Cu")
		(net 443)
	)
	(segment
		(start 50.097962 166.3565)
		(end 50.097962 164.1955)
		(width 0.35)
		(layer "B.Cu")
		(net 443)
	)
	(segment
		(start 50.097962 164.1955)
		(end 49.766962 163.8645)
		(width 0.35)
		(layer "B.Cu")
		(net 443)
	)
	(segment
		(start 53.917962 164.3665)
		(end 53.917962 165.456382)
		(width 0.2)
		(layer "B.Cu")
		(net 443)
	)
	(segment
		(start 49.417962 166.3565)
		(end 49.417962 164.2135)
		(width 0.35)
		(layer "B.Cu")
		(net 443)
	)
	(segment
		(start 49.417962 164.2135)
		(end 49.766962 163.8645)
		(width 0.35)
		(layer "B.Cu")
		(net 443)
	)
	(segment
		(start 53.414844 165.9595)
		(end 50.727962 165.9595)
		(width 0.2)
		(layer "B.Cu")
		(net 443)
	)
	(segment
		(start 50.757962 164.8555)
		(end 49.766962 163.8645)
		(width 0.35)
		(layer "B.Cu")
		(net 443)
	)
	(segment
		(start 72.192962 132.9415)
		(end 72.192962 153.500131)
		(width 1.75)
		(layer "In3.Cu")
		(net 443)
	)
	(segment
		(start 72.192962 153.500131)
		(end 69.911593 155.7815)
		(width 1.75)
		(layer "In3.Cu")
		(net 443)
	)
	(segment
		(start 74.842962 130.2915)
		(end 72.192962 132.9415)
		(width 1.75)
		(layer "In3.Cu")
		(net 443)
	)
	(segment
		(start 62.162962 155.7815)
		(end 54.102962 163.8415)
		(width 1.75)
		(layer "In3.Cu")
		(net 443)
	)
	(segment
		(start 54.102962 163.8415)
		(end 49.042962 163.8415)
		(width 1.75)
		(layer "In3.Cu")
		(net 443)
	)
	(segment
		(start 75.917962 130.2915)
		(end 74.842962 130.2915)
		(width 1.75)
		(layer "In3.Cu")
		(net 443)
	)
	(segment
		(start 69.911593 155.7815)
		(end 62.162962 155.7815)
		(width 1.75)
		(layer "In3.Cu")
		(net 443)
	)
	(segment
		(start 84.918962 156.0165)
		(end 84.918962 155.3825)
		(width 0.2)
		(layer "F.Cu")
		(net 444)
	)
	(segment
		(start 84.877962 154.8915)
		(end 84.877962 155.3415)
		(width 0.2)
		(layer "F.Cu")
		(net 444)
	)
	(segment
		(start 84.918962 155.3825)
		(end 84.877962 155.3415)
		(width 0.2)
		(layer "F.Cu")
		(net 444)
	)
	(segment
		(start 84.918962 156.0165)
		(end 86.665962 156.0165)
		(width 0.127)
		(layer "F.Cu")
		(net 444)
	)
	(segment
		(start 76.317962 148.2665)
		(end 76.842962 148.2665)
		(width 0.15)
		(layer "F.Cu")
		(net 445)
	)
	(segment
		(start 76.902962 148.2065)
		(end 77.317962 148.2065)
		(width 0.15)
		(layer "F.Cu")
		(net 445)
	)
	(segment
		(start 76.842962 148.2665)
		(end 76.902962 148.2065)
		(width 0.15)
		(layer "F.Cu")
		(net 445)
	)
	(segment
		(start 139.097962 131.7365)
		(end 139.647962 131.7365)
		(width 0.127)
		(layer "F.Cu")
		(net 446)
	)
	(segment
		(start 135.467962 135.9165)
		(end 135.467962 135.3665)
		(width 0.127)
		(layer "F.Cu")
		(net 446)
	)
	(segment
		(start 135.467962 135.3665)
		(end 139.097962 131.7365)
		(width 0.127)
		(layer "F.Cu")
		(net 446)
	)
	(segment
		(start 133.692962 143.6915)
		(end 134.466962 143.6915)
		(width 0.127)
		(layer "F.Cu")
		(net 446)
	)
	(segment
		(start 133.192961 143.6915)
		(end 133.039115 143.537654)
		(width 0.127)
		(layer "F.Cu")
		(net 446)
	)
	(segment
		(start 135.483806 143.9665)
		(end 136.442962 143.9665)
		(width 0.127)
		(layer "F.Cu")
		(net 446)
	)
	(segment
		(start 79.942962 151.4165)
		(end 79.642462 151.717)
		(width 0.127)
		(layer "F.Cu")
		(net 446)
	)
	(segment
		(start 79.642462 151.717)
		(end 78.473961 151.717)
		(width 0.127)
		(layer "F.Cu")
		(net 446)
	)
	(segment
		(start 133.039115 143.537654)
		(end 133.001549 143.537654)
		(width 0.127)
		(layer "F.Cu")
		(net 446)
	)
	(segment
		(start 135.220306 143.703)
		(end 135.483806 143.9665)
		(width 0.127)
		(layer "F.Cu")
		(net 446)
	)
	(segment
		(start 133.142395 143.6785)
		(end 133.692462 143.6785)
		(width 0.127)
		(layer "F.Cu")
		(net 446)
	)
	(segment
		(start 132.542962 138.8415)
		(end 135.467962 135.9165)
		(width 0.127)
		(layer "F.Cu")
		(net 446)
	)
	(segment
		(start 133.001549 143.537654)
		(end 133.142395 143.6785)
		(width 0.127)
		(layer "F.Cu")
		(net 446)
	)
	(segment
		(start 132.542962 143.079067)
		(end 132.542962 138.8415)
		(width 0.127)
		(layer "F.Cu")
		(net 446)
	)
	(segment
		(start 134.491962 143.703)
		(end 135.220306 143.703)
		(width 0.127)
		(layer "F.Cu")
		(net 446)
	)
	(segment
		(start 133.001549 143.537654)
		(end 132.542962 143.079067)
		(width 0.127)
		(layer "F.Cu")
		(net 446)
	)
	(via
		(at 79.942962 151.4165)
		(size 0.45)
		(drill 0.1)
		(layers "F.Cu" "B.Cu")
		(net 446)
	)
	(via
		(at 133.001549 143.537654)
		(size 0.45)
		(drill 0.1)
		(layers "F.Cu" "B.Cu")
		(net 446)
	)
	(segment
		(start 79.767962 151.2415)
		(end 79.252962 151.2415)
		(width 0.127)
		(layer "B.Cu")
		(net 446)
	)
	(segment
		(start 79.942962 151.4165)
		(end 79.767962 151.2415)
		(width 0.127)
		(layer "B.Cu")
		(net 446)
	)
	(segment
		(start 82.668372 160.7725)
		(end 81.290962 159.39509)
		(width 0.127)
		(layer "In2.Cu")
		(net 446)
	)
	(segment
		(start 129.674962 153.829534)
		(end 129.674962 167.263152)
		(width 0.127)
		(layer "In2.Cu")
		(net 446)
	)
	(segment
		(start 132.302662 143.537654)
		(end 131.367962 144.472354)
		(width 0.127)
		(layer "In2.Cu")
		(net 446)
	)
	(segment
		(start 127.454614 169.4835)
		(end 106.823254 169.4835)
		(width 0.127)
		(layer "In2.Cu")
		(net 446)
	)
	(segment
		(start 129.674962 167.263152)
		(end 127.454614 169.4835)
		(width 0.127)
		(layer "In2.Cu")
		(net 446)
	)
	(segment
		(start 131.367962 144.472354)
		(end 131.367962 152.136534)
		(width 0.127)
		(layer "In2.Cu")
		(net 446)
	)
	(segment
		(start 98.112254 160.7725)
		(end 82.668372 160.7725)
		(width 0.127)
		(layer "In2.Cu")
		(net 446)
	)
	(segment
		(start 106.823254 169.4835)
		(end 98.112254 160.7725)
		(width 0.127)
		(layer "In2.Cu")
		(net 446)
	)
	(segment
		(start 131.367962 152.136534)
		(end 129.674962 153.829534)
		(width 0.127)
		(layer "In2.Cu")
		(net 446)
	)
	(segment
		(start 79.442962 155.2665)
		(end 79.442962 151.9165)
		(width 0.127)
		(layer "In2.Cu")
		(net 446)
	)
	(segment
		(start 80.092962 155.9165)
		(end 79.442962 155.2665)
		(width 0.127)
		(layer "In2.Cu")
		(net 446)
	)
	(segment
		(start 81.290962 156.3895)
		(end 80.817962 155.9165)
		(width 0.127)
		(layer "In2.Cu")
		(net 446)
	)
	(segment
		(start 81.290962 159.39509)
		(end 81.290962 156.3895)
		(width 0.127)
		(layer "In2.Cu")
		(net 446)
	)
	(segment
		(start 80.817962 155.9165)
		(end 80.092962 155.9165)
		(width 0.127)
		(layer "In2.Cu")
		(net 446)
	)
	(segment
		(start 79.442962 151.9165)
		(end 79.942962 151.4165)
		(width 0.127)
		(layer "In2.Cu")
		(net 446)
	)
	(segment
		(start 133.001549 143.537654)
		(end 132.302662 143.537654)
		(width 0.127)
		(layer "In2.Cu")
		(net 446)
	)
	(segment
		(start 141.292962 132.6665)
		(end 141.087962 132.6665)
		(width 0.127)
		(layer "F.Cu")
		(net 447)
	)
	(segment
		(start 82.628674 151.714289)
		(end 82.095673 151.714289)
		(width 0.127)
		(layer "F.Cu")
		(net 447)
	)
	(segment
		(start 142.680462 143.8915)
		(end 143.142962 143.8915)
		(width 0.127)
		(layer "F.Cu")
		(net 447)
	)
	(segment
		(start 141.442962 143.8915)
		(end 141.367962 143.9665)
		(width 0.127)
		(layer "F.Cu")
		(net 447)
	)
	(segment
		(start 141.087962 132.6665)
		(end 141.077962 132.6765)
		(width 0.127)
		(layer "F.Cu")
		(net 447)
	)
	(segment
		(start 141.905462 143.8915)
		(end 141.442962 143.8915)
		(width 0.127)
		(layer "F.Cu")
		(net 447)
	)
	(segment
		(start 140.393962 143.9665)
		(end 141.367962 143.9665)
		(width 0.127)
		(layer "F.Cu")
		(net 447)
	)
	(segment
		(start 82.092962 151.717)
		(end 81.554961 151.717)
		(width 0.127)
		(layer "F.Cu")
		(net 447)
	)
	(segment
		(start 141.077962 132.6765)
		(end 140.622962 132.6765)
		(width 0.127)
		(layer "F.Cu")
		(net 447)
	)
	(segment
		(start 143.142962 143.8915)
		(end 143.217962 143.8165)
		(width 0.127)
		(layer "F.Cu")
		(net 447)
	)
	(segment
		(start 82.095673 151.714289)
		(end 82.092962 151.717)
		(width 0.127)
		(layer "F.Cu")
		(net 447)
	)
	(segment
		(start 141.905462 143.8915)
		(end 142.680462 143.8915)
		(width 0.127)
		(layer "F.Cu")
		(net 447)
	)
	(via
		(at 125.441462 159.3765)
		(size 0.45)
		(drill 0.1)
		(layers "F.Cu" "B.Cu")
		(free yes)
		(net 447)
	)
	(via
		(at 143.217962 143.8165)
		(size 0.45)
		(drill 0.1)
		(layers "F.Cu" "B.Cu")
		(net 447)
	)
	(via
		(at 82.628674 151.714289)
		(size 0.45)
		(drill 0.1)
		(layers "F.Cu" "B.Cu")
		(net 447)
	)
	(via
		(at 141.292962 132.6665)
		(size 0.45)
		(drill 0.1)
		(layers "F.Cu" "B.Cu")
		(net 447)
	)
	(segment
		(start 82.130973 151.714289)
		(end 82.083184 151.6665)
		(width 0.127)
		(layer "B.Cu")
		(net 447)
	)
	(segment
		(start 141.292962 132.6665)
		(end 142.769962 134.1435)
		(width 0.127)
		(layer "B.Cu")
		(net 447)
	)
	(segment
		(start 82.628674 151.714289)
		(end 82.130973 151.714289)
		(width 0.127)
		(layer "B.Cu")
		(net 447)
	)
	(segment
		(start 79.639462 151.83)
		(end 80.254462 151.83)
		(width 0.127)
		(layer "B.Cu")
		(net 447)
	)
	(segment
		(start 142.769962 143.378278)
		(end 143.208184 143.8165)
		(width 0.127)
		(layer "B.Cu")
		(net 447)
	)
	(segment
		(start 82.083184 151.6665)
		(end 80.417962 151.6665)
		(width 0.127)
		(layer "B.Cu")
		(net 447)
	)
	(segment
		(start 142.769962 134.1435)
		(end 142.769962 143.378278)
		(width 0.127)
		(layer "B.Cu")
		(net 447)
	)
	(segment
		(start 79.252962 152.2165)
		(end 79.639462 151.83)
		(width 0.127)
		(layer "B.Cu")
		(net 447)
	)
	(segment
		(start 80.254462 151.83)
		(end 80.417962 151.6665)
		(width 0.127)
		(layer "B.Cu")
		(net 447)
	)
	(segment
		(start 143.208184 143.8165)
		(end 143.217962 143.8165)
		(width 0.127)
		(layer "B.Cu")
		(net 447)
	)
	(segment
		(start 125.441462 160.719056)
		(end 125.441462 159.3765)
		(width 0.127)
		(layer "In2.Cu")
		(net 447)
	)
	(segment
		(start 82.628674 151.714289)
		(end 82.674573 151.760188)
		(width 0.127)
		(layer "In2.Cu")
		(net 447)
	)
	(segment
		(start 107.867074 166.9635)
		(end 119.197018 166.9635)
		(width 0.127)
		(layer "In2.Cu")
		(net 447)
	)
	(segment
		(start 82.498637 152.805825)
		(end 82.498637 153.740793)
		(width 0.127)
		(layer "In2.Cu")
		(net 447)
	)
	(segment
		(start 82.674573 152.629889)
		(end 82.498637 152.805825)
		(width 0.127)
		(layer "In2.Cu")
		(net 447)
	)
	(segment
		(start 86.458198 157.6945)
		(end 87.016198 158.2525)
		(width 0.127)
		(layer "In2.Cu")
		(net 447)
	)
	(segment
		(start 82.674573 151.760188)
		(end 82.674573 152.629889)
		(width 0.127)
		(layer "In2.Cu")
		(net 447)
	)
	(segment
		(start 99.156074 158.2525)
		(end 107.867074 166.9635)
		(width 0.127)
		(layer "In2.Cu")
		(net 447)
	)
	(segment
		(start 82.498637 153.740793)
		(end 86.452344 157.6945)
		(width 0.127)
		(layer "In2.Cu")
		(net 447)
	)
	(segment
		(start 87.016198 158.2525)
		(end 99.156074 158.2525)
		(width 0.127)
		(layer "In2.Cu")
		(net 447)
	)
	(segment
		(start 86.452344 157.6945)
		(end 86.458198 157.6945)
		(width 0.127)
		(layer "In2.Cu")
		(net 447)
	)
	(segment
		(start 119.197018 166.9635)
		(end 125.441462 160.719056)
		(width 0.127)
		(layer "In2.Cu")
		(net 447)
	)
	(segment
		(start 127.469302 157.2365)
		(end 125.441462 159.26434)
		(width 0.127)
		(layer "In3.Cu")
		(net 447)
	)
	(segment
		(start 136.13776 157.2365)
		(end 127.469302 157.2365)
		(width 0.127)
		(layer "In3.Cu")
		(net 447)
	)
	(segment
		(start 142.576802 143.8165)
		(end 138.527462 147.86584)
		(width 0.127)
		(layer "In3.Cu")
		(net 447)
	)
	(segment
		(start 125.441462 159.26434)
		(end 125.441462 159.3765)
		(width 0.127)
		(layer "In3.Cu")
		(net 447)
	)
	(segment
		(start 138.485462 154.888798)
		(end 136.13776 157.2365)
		(width 0.127)
		(layer "In3.Cu")
		(net 447)
	)
	(segment
		(start 138.485462 154.842717)
		(end 138.485462 154.888798)
		(width 0.127)
		(layer "In3.Cu")
		(net 447)
	)
	(segment
		(start 138.527462 147.86584)
		(end 138.527462 154.800717)
		(width 0.127)
		(layer "In3.Cu")
		(net 447)
	)
	(segment
		(start 138.527462 154.800717)
		(end 138.485462 154.842717)
		(width 0.127)
		(layer "In3.Cu")
		(net 447)
	)
	(segment
		(start 143.217962 143.8165)
		(end 142.576802 143.8165)
		(width 0.127)
		(layer "In3.Cu")
		(net 447)
	)
	(segment
		(start 92.067962 133.527764)
		(end 93.45 132.145726)
		(width 0.15)
		(layer "F.Cu")
		(net 448)
	)
	(segment
		(start 93.45 132.145726)
		(end 93.45 131.2)
		(width 0.15)
		(layer "F.Cu")
		(net 448)
	)
	(segment
		(start 93.45 131.2)
		(end 93.8 130.85)
		(width 0.15)
		(layer "F.Cu")
		(net 448)
	)
	(segment
		(start 92.067962 133.957236)
		(end 92.067962 133.527764)
		(width 0.15)
		(layer "F.Cu")
		(net 448)
	)
	(segment
		(start 94.434635 131.55)
		(end 92.467962 133.516673)
		(width 0.15)
		(layer "F.Cu")
		(net 449)
	)
	(segment
		(start 94.45 131.55)
		(end 94.434635 131.55)
		(width 0.15)
		(layer "F.Cu")
		(net 449)
	)
	(segment
		(start 92.467962 133.516673)
		(end 92.467962 133.957236)
		(width 0.15)
		(layer "F.Cu")
		(net 449)
	)
	(segment
		(start 92.867962 133.507236)
		(end 93.325198 133.05)
		(width 0.15)
		(layer "F.Cu")
		(net 450)
	)
	(segment
		(start 92.867962 133.957236)
		(end 92.867962 133.507236)
		(width 0.15)
		(layer "F.Cu")
		(net 450)
	)
	(segment
		(start 93.325198 133.05)
		(end 93.85 133.05)
		(width 0.15)
		(layer "F.Cu")
		(net 450)
	)
	(segment
		(start 110.866962 120.5405)
		(end 110.866962 122.5605)
		(width 0.2)
		(layer "F.Cu")
		(net 451)
	)
	(segment
		(start 110.767962 120.4415)
		(end 110.866962 120.5405)
		(width 0.2)
		(layer "F.Cu")
		(net 451)
	)
	(via
		(at 110.767962 120.4415)
		(size 0.45)
		(drill 0.1)
		(layers "F.Cu" "B.Cu")
		(net 451)
	)
	(segment
		(start 110.337962 120.0115)
		(end 110.767962 120.4415)
		(width 0.15)
		(layer "B.Cu")
		(net 451)
	)
	(segment
		(start 110.337962 119.3765)
		(end 110.337962 120.0115)
		(width 0.15)
		(layer "B.Cu")
		(net 451)
	)
	(segment
		(start 111.867962 122.5605)
		(end 111.867962 121.077897)
		(width 0.2)
		(layer "F.Cu")
		(net 452)
	)
	(segment
		(start 111.567962 120.7415)
		(end 111.542962 120.7165)
		(width 0.2)
		(layer "F.Cu")
		(net 452)
	)
	(segment
		(start 111.867962 121.077897)
		(end 111.567962 120.777897)
		(width 0.2)
		(layer "F.Cu")
		(net 452)
	)
	(segment
		(start 111.567962 120.777897)
		(end 111.567962 120.7415)
		(width 0.2)
		(layer "F.Cu")
		(net 452)
	)
	(via
		(at 111.542962 120.7165)
		(size 0.45)
		(drill 0.1)
		(layers "F.Cu" "B.Cu")
		(net 452)
	)
	(segment
		(start 109.837962 120.260103)
		(end 109.837962 119.3765)
		(width 0.15)
		(layer "B.Cu")
		(net 452)
	)
	(segment
		(start 111.542962 120.7165)
		(end 111.217962 121.0415)
		(width 0.15)
		(layer "B.Cu")
		(net 452)
	)
	(segment
		(start 110.619359 121.0415)
		(end 109.837962 120.260103)
		(width 0.15)
		(layer "B.Cu")
		(net 452)
	)
	(segment
		(start 111.217962 121.0415)
		(end 110.619359 121.0415)
		(width 0.15)
		(layer "B.Cu")
		(net 452)
	)
	(segment
		(start 112.367962 122.5605)
		(end 112.367962 120.9415)
		(width 0.2)
		(layer "F.Cu")
		(net 453)
	)
	(segment
		(start 112.367962 120.9415)
		(end 112.142962 120.7165)
		(width 0.2)
		(layer "F.Cu")
		(net 453)
	)
	(via
		(at 112.142962 120.7165)
		(size 0.45)
		(drill 0.1)
		(layers "F.Cu" "B.Cu")
		(net 453)
	)
	(segment
		(start 112.142962 120.752897)
		(end 111.529359 121.3665)
		(width 0.15)
		(layer "B.Cu")
		(net 453)
	)
	(segment
		(start 112.142962 120.7165)
		(end 112.142962 120.752897)
		(width 0.15)
		(layer "B.Cu")
		(net 453)
	)
	(segment
		(start 109.200462 120.895397)
		(end 109.200462 119.3765)
		(width 0.15)
		(layer "B.Cu")
		(net 453)
	)
	(segment
		(start 111.529359 121.3665)
		(end 109.671565 121.3665)
		(width 0.15)
		(layer "B.Cu")
		(net 453)
	)
	(segment
		(start 109.671565 121.3665)
		(end 109.200462 120.895397)
		(width 0.15)
		(layer "B.Cu")
		(net 453)
	)
	(segment
		(start 113.867962 120.9415)
		(end 114.067962 120.7415)
		(width 0.2)
		(layer "F.Cu")
		(net 454)
	)
	(segment
		(start 113.867962 122.5605)
		(end 113.867962 120.9415)
		(width 0.2)
		(layer "F.Cu")
		(net 454)
	)
	(via
		(at 114.067962 120.7415)
		(size 0.45)
		(drill 0.1)
		(layers "F.Cu" "B.Cu")
		(net 454)
	)
	(segment
		(start 111.337962 120.2665)
		(end 113.592962 120.2665)
		(width 0.15)
		(layer "B.Cu")
		(net 454)
	)
	(segment
		(start 113.592962 120.2665)
		(end 114.067962 120.7415)
		(width 0.15)
		(layer "B.Cu")
		(net 454)
	)
	(segment
		(start 110.975462 119.3765)
		(end 110.975462 119.904)
		(width 0.15)
		(layer "B.Cu")
		(net 454)
	)
	(segment
		(start 110.975462 119.904)
		(end 111.337962 120.2665)
		(width 0.15)
		(layer "B.Cu")
		(net 454)
	)
	(segment
		(start 103.119962 146.2665)
		(end 101.460962 146.2665)
		(width 0.15)
		(layer "F.Cu")
		(net 455)
	)
	(segment
		(start 101.460962 146.2665)
		(end 101.362962 146.3645)
		(width 0.15)
		(layer "F.Cu")
		(net 455)
	)
	(segment
		(start 87.667962 147.7665)
		(end 87.367962 147.7665)
		(width 0.127)
		(layer "F.Cu")
		(net 455)
	)
	(segment
		(start 86.959462 147.358)
		(end 86.959462 146.808)
		(width 0.127)
		(layer "F.Cu")
		(net 455)
	)
	(segment
		(start 86.959462 146.808)
		(end 86.767962 146.6165)
		(width 0.127)
		(layer "F.Cu")
		(net 455)
	)
	(segment
		(start 103.119962 143.2135)
		(end 103.119962 146.2665)
		(width 0.2)
		(layer "F.Cu")
		(net 455)
	)
	(segment
		(start 87.367962 147.7665)
		(end 86.959462 147.358)
		(width 0.127)
		(layer "F.Cu")
		(net 455)
	)
	(segment
		(start 100.467962 148.2915)
		(end 98.042962 148.2915)
		(width 0.15)
		(layer "F.Cu")
		(net 455)
	)
	(segment
		(start 102.547962 142.6415)
		(end 103.119962 143.2135)
		(width 0.2)
		(layer "F.Cu")
		(net 455)
	)
	(segment
		(start 101.362962 147.3965)
		(end 100.467962 148.2915)
		(width 0.15)
		(layer "F.Cu")
		(net 455)
	)
	(segment
		(start 86.767962 146.6165)
		(end 86.320962 146.6165)
		(width 0.127)
		(layer "F.Cu")
		(net 455)
	)
	(segment
		(start 101.362962 146.3645)
		(end 101.362962 147.3965)
		(width 0.15)
		(layer "F.Cu")
		(net 455)
	)
	(segment
		(start 98.042962 148.2915)
		(end 97.517962 147.7665)
		(width 0.15)
		(layer "F.Cu")
		(net 455)
	)
	(via
		(at 87.667962 147.7665)
		(size 0.45)
		(drill 0.1)
		(layers "F.Cu" "B.Cu")
		(net 455)
	)
	(via
		(at 97.517962 147.7665)
		(size 0.45)
		(drill 0.1)
		(layers "F.Cu" "B.Cu")
		(net 455)
	)
	(segment
		(start 90.504462 147.83)
		(end 90.504462 147.804232)
		(width 0.127)
		(layer "B.Cu")
		(net 455)
	)
	(segment
		(start 94.081462 145.653)
		(end 95.404462 145.653)
		(width 0.127)
		(layer "B.Cu")
		(net 455)
	)
	(segment
		(start 87.667962 147.7665)
		(end 87.731462 147.83)
		(width 0.127)
		(layer "B.Cu")
		(net 455)
	)
	(segment
		(start 90.504462 147.804232)
		(end 92.591794 145.7169)
		(width 0.127)
		(layer "B.Cu")
		(net 455)
	)
	(segment
		(start 95.404462 145.653)
		(end 97.517962 147.7665)
		(width 0.127)
		(layer "B.Cu")
		(net 455)
	)
	(segment
		(start 94.017562 145.7169)
		(end 94.081462 145.653)
		(width 0.127)
		(layer "B.Cu")
		(net 455)
	)
	(segment
		(start 87.731462 147.83)
		(end 90.504462 147.83)
		(width 0.127)
		(layer "B.Cu")
		(net 455)
	)
	(segment
		(start 92.591794 145.7169)
		(end 94.017562 145.7169)
		(width 0.127)
		(layer "B.Cu")
		(net 455)
	)
	(segment
		(start 84.877226 141.907236)
		(end 85.317962 141.907236)
		(width 0.127)
		(layer "F.Cu")
		(net 456)
	)
	(segment
		(start 94.831462 144.2665)
		(end 95.467962 144.2665)
		(width 0.127)
		(layer "F.Cu")
		(net 456)
	)
	(segment
		(start 84.537263 142.247199)
		(end 84.877226 141.907236)
		(width 0.127)
		(layer "F.Cu")
		(net 456)
	)
	(segment
		(start 94.567962 144.53)
		(end 94.831462 144.2665)
		(width 0.127)
		(layer "F.Cu")
		(net 456)
	)
	(segment
		(start 84.717962 142.477898)
		(end 84.537263 142.297199)
		(width 0.127)
		(layer "F.Cu")
		(net 456)
	)
	(segment
		(start 84.537263 142.297199)
		(end 84.537263 142.247199)
		(width 0.127)
		(layer "F.Cu")
		(net 456)
	)
	(segment
		(start 84.717962 145.9635)
		(end 84.717962 142.477898)
		(width 0.127)
		(layer "F.Cu")
		(net 456)
	)
	(via
		(at 94.567962 144.53)
		(size 0.45)
		(drill 0.1)
		(layers "F.Cu" "B.Cu")
		(net 456)
	)
	(via
		(at 84.537263 142.297199)
		(size 0.45)
		(drill 0.1)
		(layers "F.Cu" "B.Cu")
		(net 456)
	)
	(segment
		(start 94.171962 144.8625)
		(end 90.878344 144.8625)
		(width 0.127)
		(layer "In2.Cu")
		(net 456)
	)
	(segment
		(start 85.50274 142.0165)
		(end 84.817962 142.0165)
		(width 0.127)
		(layer "In2.Cu")
		(net 456)
	)
	(segment
		(start 85.754462 142.814778)
		(end 85.867962 142.701278)
		(width 0.127)
		(layer "In2.Cu")
		(net 456)
	)
	(segment
		(start 85.867962 142.701278)
		(end 85.867962 142.381722)
		(width 0.127)
		(layer "In2.Cu")
		(net 456)
	)
	(segment
		(start 90.408844 145.332)
		(end 86.673684 145.332)
		(width 0.127)
		(layer "In2.Cu")
		(net 456)
	)
	(segment
		(start 86.673684 145.332)
		(end 85.754462 144.412778)
		(width 0.127)
		(layer "In2.Cu")
		(net 456)
	)
	(segment
		(start 94.567962 144.53)
		(end 94.504462 144.53)
		(width 0.127)
		(layer "In2.Cu")
		(net 456)
	)
	(segment
		(start 90.878344 144.8625)
		(end 90.408844 145.332)
		(width 0.127)
		(layer "In2.Cu")
		(net 456)
	)
	(segment
		(start 85.754462 144.412778)
		(end 85.754462 142.814778)
		(width 0.127)
		(layer "In2.Cu")
		(net 456)
	)
	(segment
		(start 84.817962 142.0165)
		(end 84.537263 142.297199)
		(width 0.127)
		(layer "In2.Cu")
		(net 456)
	)
	(segment
		(start 85.867962 142.381722)
		(end 85.50274 142.0165)
		(width 0.127)
		(layer "In2.Cu")
		(net 456)
	)
	(segment
		(start 94.504462 144.53)
		(end 94.171962 144.8625)
		(width 0.127)
		(layer "In2.Cu")
		(net 456)
	)
	(segment
		(start 86.067962 142.852972)
		(end 86.067962 142.657236)
		(width 0.127)
		(layer "F.Cu")
		(net 457)
	)
	(segment
		(start 94.917962 144.7665)
		(end 95.467962 144.7665)
		(width 0.127)
		(layer "F.Cu")
		(net 457)
	)
	(segment
		(start 85.131462 143.4665)
		(end 85.379226 143.218736)
		(width 0.127)
		(layer "F.Cu")
		(net 457)
	)
	(segment
		(start 85.702198 143.218736)
		(end 86.067962 142.852972)
		(width 0.127)
		(layer "F.Cu")
		(net 457)
	)
	(segment
		(start 85.131462 143.4665)
		(end 85.117962 143.48)
		(width 0.127)
		(layer "F.Cu")
		(net 457)
	)
	(segment
		(start 94.567962 145.1165)
		(end 94.917962 144.7665)
		(width 0.127)
		(layer "F.Cu")
		(net 457)
	)
	(segment
		(start 85.379226 143.218736)
		(end 85.702198 143.218736)
		(width 0.127)
		(layer "F.Cu")
		(net 457)
	)
	(segment
		(start 85.117962 143.48)
		(end 85.117962 145.9635)
		(width 0.127)
		(layer "F.Cu")
		(net 457)
	)
	(via
		(at 94.567962 145.1165)
		(size 0.45)
		(drill 0.1)
		(layers "F.Cu" "B.Cu")
		(net 457)
	)
	(via
		(at 85.131462 143.4665)
		(size 0.45)
		(drill 0.1)
		(layers "F.Cu" "B.Cu")
		(net 457)
	)
	(segment
		(start 90.982726 145.1145)
		(end 90.513226 145.584)
		(width 0.127)
		(layer "In2.Cu")
		(net 457)
	)
	(segment
		(start 93.98924 145.6895)
		(end 93.646684 145.6895)
		(width 0.127)
		(layer "In2.Cu")
		(net 457)
	)
	(segment
		(start 94.567962 145.1165)
		(end 94.56224 145.1165)
		(width 0.127)
		(layer "In2.Cu")
		(net 457)
	)
	(segment
		(start 85.131462 144.18)
		(end 85.131462 143.4665)
		(width 0.127)
		(layer "In2.Cu")
		(net 457)
	)
	(segment
		(start 94.56224 145.1165)
		(end 93.98924 145.6895)
		(width 0.127)
		(layer "In2.Cu")
		(net 457)
	)
	(segment
		(start 86.535462 145.584)
		(end 85.131462 144.18)
		(width 0.127)
		(layer "In2.Cu")
		(net 457)
	)
	(segment
		(start 90.513226 145.584)
		(end 86.535462 145.584)
		(width 0.127)
		(layer "In2.Cu")
		(net 457)
	)
	(segment
		(start 93.071684 145.1145)
		(end 90.982726 145.1145)
		(width 0.127)
		(layer "In2.Cu")
		(net 457)
	)
	(segment
		(start 93.646684 145.6895)
		(end 93.071684 145.1145)
		(width 0.127)
		(layer "In2.Cu")
		(net 457)
	)
	(segment
		(start 86.467962 142.180236)
		(end 86.467962 142.657236)
		(width 0.127)
		(layer "F.Cu")
		(net 458)
	)
	(segment
		(start 94.567962 146.0665)
		(end 94.567962 145.7165)
		(width 0.127)
		(layer "F.Cu")
		(net 458)
	)
	(segment
		(start 86.304226 142.0165)
		(end 86.467962 142.180236)
		(width 0.127)
		(layer "F.Cu")
		(net 458)
	)
	(segment
		(start 94.567962 145.7165)
		(end 95.017962 145.2665)
		(width 0.127)
		(layer "F.Cu")
		(net 458)
	)
	(segment
		(start 85.967962 142.0165)
		(end 86.304226 142.0165)
		(width 0.127)
		(layer "F.Cu")
		(net 458)
	)
	(segment
		(start 95.017962 145.2665)
		(end 95.467962 145.2665)
		(width 0.127)
		(layer "F.Cu")
		(net 458)
	)
	(segment
		(start 85.442962 142.5415)
		(end 85.967962 142.0165)
		(width 0.127)
		(layer "F.Cu")
		(net 458)
	)
	(via
		(at 85.442962 142.5415)
		(size 0.45)
		(drill 0.1)
		(layers "F.Cu" "B.Cu")
		(net 458)
	)
	(via
		(at 94.567962 146.0665)
		(size 0.45)
		(drill 0.1)
		(layers "F.Cu" "B.Cu")
		(net 458)
	)
	(segment
		(start 86.287462 145.836)
		(end 84.717962 144.2665)
		(width 0.127)
		(layer "In2.Cu")
		(net 458)
	)
	(segment
		(start 93.542302 145.9415)
		(end 92.967302 145.3665)
		(width 0.127)
		(layer "In2.Cu")
		(net 458)
	)
	(segment
		(start 90.617608 145.836)
		(end 86.287462 145.836)
		(width 0.127)
		(layer "In2.Cu")
		(net 458)
	)
	(segment
		(start 91.087108 145.3665)
		(end 90.617608 145.836)
		(width 0.127)
		(layer "In2.Cu")
		(net 458)
	)
	(segment
		(start 84.717962 144.2665)
		(end 84.717962 143.2665)
		(width 0.127)
		(layer "In2.Cu")
		(net 458)
	)
	(segment
		(start 94.567962 146.0665)
		(end 94.442962 145.9415)
		(width 0.127)
		(layer "In2.Cu")
		(net 458)
	)
	(segment
		(start 94.442962 145.9415)
		(end 93.542302 145.9415)
		(width 0.127)
		(layer "In2.Cu")
		(net 458)
	)
	(segment
		(start 84.717962 143.2665)
		(end 85.442962 142.5415)
		(width 0.127)
		(layer "In2.Cu")
		(net 458)
	)
	(segment
		(start 92.967302 145.3665)
		(end 91.087108 145.3665)
		(width 0.127)
		(layer "In2.Cu")
		(net 458)
	)
	(segment
		(start 98.642962 147.5665)
		(end 99.237962 147.5665)
		(width 0.2)
		(layer "F.Cu")
		(net 463)
	)
	(segment
		(start 97.117292 147.3905)
		(end 97.241292 147.2665)
		(width 0.2)
		(layer "F.Cu")
		(net 463)
	)
	(segment
		(start 87.667962 142.657236)
		(end 87.667962 142.0665)
		(width 0.127)
		(layer "F.Cu")
		(net 463)
	)
	(segment
		(start 97.241292 147.2665)
		(end 98.342962 147.2665)
		(width 0.2)
		(layer "F.Cu")
		(net 463)
	)
	(segment
		(start 98.342962 147.2665)
		(end 98.642962 147.5665)
		(width 0.2)
		(layer "F.Cu")
		(net 463)
	)
	(segment
		(start 95.267962 146.9165)
		(end 95.741962 147.3905)
		(width 0.2)
		(layer "F.Cu")
		(net 463)
	)
	(segment
		(start 95.741962 147.3905)
		(end 97.117292 147.3905)
		(width 0.2)
		(layer "F.Cu")
		(net 463)
	)
	(via
		(at 87.667962 142.0665)
		(size 0.45)
		(drill 0.1)
		(layers "F.Cu" "B.Cu")
		(net 463)
	)
	(via
		(at 95.267962 146.9165)
		(size 0.45)
		(drill 0.1)
		(layers "F.Cu" "B.Cu")
		(net 463)
	)
	(segment
		(start 90.867962 144.5165)
		(end 93.917962 144.5165)
		(width 0.127)
		(layer "In2.Cu")
		(net 463)
	)
	(segment
		(start 94.917962 144.1165)
		(end 95.267962 144.4665)
		(width 0.127)
		(layer "In2.Cu")
		(net 463)
	)
	(segment
		(start 94.317962 144.1165)
		(end 94.917962 144.1165)
		(width 0.127)
		(layer "In2.Cu")
		(net 463)
	)
	(segment
		(start 87.330948 145.08)
		(end 90.304462 145.08)
		(width 0.127)
		(layer "In2.Cu")
		(net 463)
	)
	(segment
		(start 95.267962 144.4665)
		(end 95.267962 146.9165)
		(width 0.127)
		(layer "In2.Cu")
		(net 463)
	)
	(segment
		(start 90.304462 145.08)
		(end 90.867962 144.5165)
		(width 0.127)
		(layer "In2.Cu")
		(net 463)
	)
	(segment
		(start 86.617962 144.367014)
		(end 87.330948 145.08)
		(width 0.127)
		(layer "In2.Cu")
		(net 463)
	)
	(segment
		(start 87.667962 142.0665)
		(end 86.617962 143.1165)
		(width 0.127)
		(layer "In2.Cu")
		(net 463)
	)
	(segment
		(start 93.917962 144.5165)
		(end 94.317962 144.1165)
		(width 0.127)
		(layer "In2.Cu")
		(net 463)
	)
	(segment
		(start 86.617962 143.1165)
		(end 86.617962 144.367014)
		(width 0.127)
		(layer "In2.Cu")
		(net 463)
	)
	(segment
		(start 96.809962 174.6875)
		(end 97.513962 174.6875)
		(width 0.2)
		(layer "B.Cu")
		(net 464)
	)
	(segment
		(start 97.770462 174.944)
		(end 97.921962 175.0955)
		(width 0.2)
		(layer "B.Cu")
		(net 464)
	)
	(segment
		(start 97.921962 175.0955)
		(end 97.921962 175.1875)
		(width 0.2)
		(layer "B.Cu")
		(net 464)
	)
	(segment
		(start 98.017962 176.0625)
		(end 97.892962 176.1875)
		(width 0.2)
		(layer "B.Cu")
		(net 464)
	)
	(segment
		(start 98.017962 175.8155)
		(end 98.017962 176.0625)
		(width 0.2)
		(layer "B.Cu")
		(net 464)
	)
	(segment
		(start 100.354962 176.4915)
		(end 99.426962 176.4915)
		(width 0.254)
		(layer "B.Cu")
		(net 464)
	)
	(segment
		(start 96.809962 175.1875)
		(end 97.737962 175.1875)
		(width 0.2)
		(layer "B.Cu")
		(net 464)
	)
	(segment
		(start 96.809962 176.1875)
		(end 97.892962 176.1875)
		(width 0.2)
		(layer "B.Cu")
		(net 464)
	)
	(segment
		(start 97.737962 174.9765)
		(end 97.737962 175.1875)
		(width 0.2)
		(layer "B.Cu")
		(net 464)
	)
	(segment
		(start 97.921962 175.1875)
		(end 97.921962 175.6205)
		(width 0.2)
		(layer "B.Cu")
		(net 464)
	)
	(segment
		(start 98.684962 176.4825)
		(end 98.342962 176.1405)
		(width 0.254)
		(layer "B.Cu")
		(net 464)
	)
	(segment
		(start 97.921962 175.6205)
		(end 98.342962 176.0415)
		(width 0.2)
		(layer "B.Cu")
		(net 464)
	)
	(segment
		(start 97.513962 174.6875)
		(end 97.770462 174.944)
		(width 0.2)
		(layer "B.Cu")
		(net 464)
	)
	(segment
		(start 97.921962 175.1875)
		(end 97.921962 175.6555)
		(width 0.2)
		(layer "B.Cu")
		(net 464)
	)
	(segment
		(start 97.737962 175.1875)
		(end 97.921962 175.1875)
		(width 0.2)
		(layer "B.Cu")
		(net 464)
	)
	(segment
		(start 97.921962 175.6555)
		(end 97.889962 175.6875)
		(width 0.2)
		(layer "B.Cu")
		(net 464)
	)
	(segment
		(start 99.417962 176.4825)
		(end 98.684962 176.4825)
		(width 0.254)
		(layer "B.Cu")
		(net 464)
	)
	(segment
		(start 96.809962 175.6875)
		(end 97.889962 175.6875)
		(width 0.2)
		(layer "B.Cu")
		(net 464)
	)
	(segment
		(start 97.889962 175.6875)
		(end 98.017962 175.8155)
		(width 0.2)
		(layer "B.Cu")
		(net 464)
	)
	(segment
		(start 97.892962 176.1875)
		(end 98.295962 176.1875)
		(width 0.2)
		(layer "B.Cu")
		(net 464)
	)
	(segment
		(start 97.770462 174.944)
		(end 97.737962 174.9765)
		(width 0.2)
		(layer "B.Cu")
		(net 464)
	)
	(segment
		(start 76.492962 151.1165)
		(end 76.492962 150.3165)
		(width 0.2)
		(layer "F.Cu")
		(net 465)
	)
	(segment
		(start 76.192962 151.4165)
		(end 76.492962 151.1165)
		(width 0.2)
		(layer "F.Cu")
		(net 465)
	)
	(via
		(at 76.192962 151.4165)
		(size 0.45)
		(drill 0.1)
		(layers "F.Cu" "B.Cu")
		(net 465)
	)
	(segment
		(start 76.192962 151.4165)
		(end 76.267962 151.4165)
		(width 0.2)
		(layer "B.Cu")
		(net 465)
	)
	(segment
		(start 76.267962 151.4165)
		(end 76.927962 150.7565)
		(width 0.2)
		(layer "B.Cu")
		(net 465)
	)
	(segment
		(start 76.217962 153.3615)
		(end 76.647962 153.7915)
		(width 0.15)
		(layer "F.Cu")
		(net 466)
	)
	(segment
		(start 76.217962 152.6415)
		(end 76.217962 153.3615)
		(width 0.15)
		(layer "F.Cu")
		(net 466)
	)
	(segment
		(start 75.717962 146.6665)
		(end 76.283462 146.101)
		(width 0.15)
		(layer "F.Cu")
		(net 467)
	)
	(segment
		(start 75.717962 147.1165)
		(end 75.717962 146.6665)
		(width 0.15)
		(layer "F.Cu")
		(net 467)
	)
	(segment
		(start 76.283462 146.101)
		(end 76.283462 145.9865)
		(width 0.15)
		(layer "F.Cu")
		(net 467)
	)
	(segment
		(start 74.793962 146.076)
		(end 74.883462 145.9865)
		(width 0.15)
		(layer "F.Cu")
		(net 468)
	)
	(segment
		(start 68.957962 146.076)
		(end 74.793962 146.076)
		(width 0.15)
		(layer "F.Cu")
		(net 468)
	)
	(segment
		(start 77.267962 173.2065)
		(end 77.267962 170.8765)
		(width 0.127)
		(layer "F.Cu")
		(net 469)
	)
	(segment
		(start 77.267962 170.8765)
		(end 77.592962 170.5515)
		(width 0.127)
		(layer "F.Cu")
		(net 469)
	)
	(segment
		(start 117.617962 136.6915)
		(end 117.617962 135.9915)
		(width 0.2)
		(layer "F.Cu")
		(net 470)
	)
	(segment
		(start 118.017962 137.0915)
		(end 117.617962 136.6915)
		(width 0.2)
		(layer "F.Cu")
		(net 470)
	)
	(via
		(at 118.017962 137.0915)
		(size 0.45)
		(drill 0.1)
		(layers "F.Cu" "B.Cu")
		(net 470)
	)
	(segment
		(start 121.842962 134.4665)
		(end 121.842962 131.9915)
		(width 0.2)
		(layer "B.Cu")
		(net 470)
	)
	(segment
		(start 118.017962 137.0915)
		(end 119.217962 137.0915)
		(width 0.2)
		(layer "B.Cu")
		(net 470)
	)
	(segment
		(start 121.620462 131.769)
		(end 120.619962 131.769)
		(width 0.2)
		(layer "B.Cu")
		(net 470)
	)
	(segment
		(start 119.217962 137.0915)
		(end 121.842962 134.4665)
		(width 0.2)
		(layer "B.Cu")
		(net 470)
	)
	(segment
		(start 121.842962 131.9915)
		(end 121.620462 131.769)
		(width 0.2)
		(layer "B.Cu")
		(net 470)
	)
	(segment
		(start 90.192962 129.5715)
		(end 89.488962 129.5715)
		(width 0.2)
		(layer "F.Cu")
		(net 471)
	)
	(segment
		(start 89.488962 129.5715)
		(end 89.393962 129.6665)
		(width 0.2)
		(layer "F.Cu")
		(net 471)
	)
	(segment
		(start 41.282962 122.9215)
		(end 38.895462 125.309)
		(width 1)
		(layer "F.Cu")
		(net 472)
	)
	(segment
		(start 41.977962 122.2265)
		(end 41.977962 121.0465)
		(width 1)
		(layer "F.Cu")
		(net 472)
	)
	(segment
		(start 39.837962 164.85)
		(end 39.837962 165.312038)
		(width 0.254)
		(layer "F.Cu")
		(net 472)
	)
	(segment
		(start 41.282962 122.9215)
		(end 40.895462 123.309)
		(width 1)
		(layer "F.Cu")
		(net 472)
	)
	(segment
		(start 41.997962 121.0265)
		(end 48.230962 121.0265)
		(width 1)
		(layer "F.Cu")
		(net 472)
	)
	(segment
		(start 41.977962 121.0465)
		(end 41.997962 121.0265)
		(width 1)
		(layer "F.Cu")
		(net 472)
	)
	(segment
		(start 39.837962 165.312038)
		(end 39.3 165.85)
		(width 0.254)
		(layer "F.Cu")
		(net 472)
	)
	(segment
		(start 40.020462 124.184)
		(end 40.895462 123.309)
		(width 1)
		(layer "F.Cu")
		(net 472)
	)
	(segment
		(start 41.282962 122.9215)
		(end 41.977962 122.2265)
		(width 1)
		(layer "F.Cu")
		(net 472)
	)
	(segment
		(start 40.020462 124.184)
		(end 39.520462 124.684)
		(width 1)
		(layer "F.Cu")
		(net 472)
	)
	(via
		(at 41.617962 166.3765)
		(size 0.5)
		(drill 0.15)
		(layers "F.Cu" "B.Cu")
		(net 472)
	)
	(via
		(at 40.147962 123.4865)
		(size 0.45)
		(drill 0.1)
		(layers "F.Cu" "B.Cu")
		(net 472)
	)
	(via
		(at 39.837962 164.85)
		(size 0.45)
		(drill 0.1)
		(layers "F.Cu" "B.Cu")
		(net 472)
	)
	(via
		(at 42.937962 165.6665)
		(size 0.5)
		(drill 0.15)
		(layers "F.Cu" "B.Cu")
		(net 472)
	)
	(via
		(at 39.647962 123.9865)
		(size 0.45)
		(drill 0.1)
		(layers "F.Cu" "B.Cu")
		(net 472)
	)
	(via
		(at 41.187962 123.5565)
		(size 0.45)
		(drill 0.1)
		(layers "F.Cu" "B.Cu")
		(net 472)
	)
	(via
		(at 39.837962 164.2365)
		(size 0.45)
		(drill 0.1)
		(layers "F.Cu" "B.Cu")
		(net 472)
	)
	(via
		(at 40.587962 164.85)
		(size 0.45)
		(drill 0.1)
		(layers "F.Cu" "B.Cu")
		(net 472)
	)
	(via
		(at 42.937962 166.3665)
		(size 0.5)
		(drill 0.15)
		(layers "F.Cu" "B.Cu")
		(net 472)
	)
	(via
		(at 39.687962 125.0565)
		(size 0.45)
		(drill 0.1)
		(layers "F.Cu" "B.Cu")
		(net 472)
	)
	(via
		(at 41.617962 165.6765)
		(size 0.5)
		(drill 0.15)
		(layers "F.Cu" "B.Cu")
		(net 472)
	)
	(via
		(at 40.687962 124.0565)
		(size 0.45)
		(drill 0.1)
		(layers "F.Cu" "B.Cu")
		(net 472)
	)
	(via
		(at 43.617962 166.3765)
		(size 0.5)
		(drill 0.15)
		(layers "F.Cu" "B.Cu")
		(net 472)
	)
	(via
		(at 39.147962 124.4865)
		(size 0.45)
		(drill 0.1)
		(layers "F.Cu" "B.Cu")
		(net 472)
	)
	(via
		(at 42.277962 165.6665)
		(size 0.5)
		(drill 0.15)
		(layers "F.Cu" "B.Cu")
		(net 472)
	)
	(via
		(at 40.647962 122.9865)
		(size 0.45)
		(drill 0.1)
		(layers "F.Cu" "B.Cu")
		(net 472)
	)
	(via
		(at 40.187962 124.5565)
		(size 0.45)
		(drill 0.1)
		(layers "F.Cu" "B.Cu")
		(net 472)
	)
	(via
		(at 42.277962 166.3665)
		(size 0.5)
		(drill 0.15)
		(layers "F.Cu" "B.Cu")
		(net 472)
	)
	(via
		(at 38.647962 124.9865)
		(size 0.45)
		(drill 0.1)
		(layers "F.Cu" "B.Cu")
		(net 472)
	)
	(via
		(at 40.587962 164.2365)
		(size 0.45)
		(drill 0.1)
		(layers "F.Cu" "B.Cu")
		(net 472)
	)
	(via
		(at 39.187962 125.5565)
		(size 0.45)
		(drill 0.1)
		(layers "F.Cu" "B.Cu")
		(net 472)
	)
	(via
		(at 43.617962 165.6765)
		(size 0.5)
		(drill 0.15)
		(layers "F.Cu" "B.Cu")
		(net 472)
	)
	(segment
		(start 41.792962 164.2415)
		(end 40.592962 164.2415)
		(width 0.5)
		(layer "B.Cu")
		(net 472)
	)
	(segment
		(start 41.617962 166.3765)
		(end 41.617962 164.8225)
		(width 0.35)
		(layer "B.Cu")
		(net 472)
	)
	(segment
		(start 41.617962 164.8225)
		(end 42.602962 163.8375)
		(width 0.35)
		(layer "B.Cu")
		(net 472)
	)
	(segment
		(start 41.792962 163.4415)
		(end 40.592962 163.4415)
		(width 0.5)
		(layer "B.Cu")
		(net 472)
	)
	(segment
		(start 40.587962 163.4465)
		(end 39.857962 163.4465)
		(width 0.5)
		(layer "B.Cu")
		(net 472)
	)
	(segment
		(start 43.612962 165.229037)
		(end 43.617962 165.224037)
		(width 0.35)
		(layer "B.Cu")
		(net 472)
	)
	(segment
		(start 42.937962 166.3665)
		(end 42.937962 164.1725)
		(width 0.35)
		(layer "B.Cu")
		(net 472)
	)
	(segment
		(start 43.617962 166.3765)
		(end 43.617962 165.6765)
		(width 0.35)
		(layer "B.Cu")
		(net 472)
	)
	(segment
		(start 43.617962 164.8525)
		(end 42.602962 163.8375)
		(width 0.35)
		(layer "B.Cu")
		(net 472)
	)
	(segment
		(start 40.587962 164.2365)
		(end 39.837962 164.2365)
		(width 0.5)
		(layer "B.Cu")
		(net 472)
	)
	(segment
		(start 39.857962 163.4465)
		(end 39.847962 163.4565)
		(width 0.5)
		(layer "B.Cu")
		(net 472)
	)
	(segment
		(start 43.617962 165.6765)
		(end 43.612962 165.6715)
		(width 0.35)
		(layer "B.Cu")
		(net 472)
	)
	(segment
		(start 40.592962 163.4415)
		(end 40.587962 163.4465)
		(width 0.5)
		(layer "B.Cu")
		(net 472)
	)
	(segment
		(start 42.277962 164.1625)
		(end 42.602962 163.8375)
		(width 0.35)
		(layer "B.Cu")
		(net 472)
	)
	(segment
		(start 42.937962 164.1725)
		(end 42.602962 163.8375)
		(width 0.35)
		(layer "B.Cu")
		(net 472)
	)
	(segment
		(start 46.119844 165.9865)
		(end 43.677962 165.9865)
		(width 0.2)
		(layer "B.Cu")
		(net 472)
	)
	(segment
		(start 42.277962 166.3665)
		(end 42.277962 164.1625)
		(width 0.35)
		(layer "B.Cu")
		(net 472)
	)
	(segment
		(start 46.753962 165.352382)
		(end 46.119844 165.9865)
		(width 0.2)
		(layer "B.Cu")
		(net 472)
	)
	(segment
		(start 40.592962 164.2415)
		(end 40.587962 164.2365)
		(width 0.5)
		(layer "B.Cu")
		(net 472)
	)
	(segment
		(start 43.617962 165.224037)
		(end 43.617962 164.8525)
		(width 0.35)
		(layer "B.Cu")
		(net 472)
	)
	(segment
		(start 43.612962 165.6715)
		(end 43.612962 165.229037)
		(width 0.35)
		(layer "B.Cu")
		(net 472)
	)
	(segment
		(start 46.753962 164.3825)
		(end 46.753962 165.352382)
		(width 0.2)
		(layer "B.Cu")
		(net 472)
	)
	(segment
		(start 39.392962 124.7915)
		(end 39.367962 124.7915)
		(width 1)
		(layer "In3.Cu")
		(net 472)
	)
	(segment
		(start 40.755462 123.429)
		(end 39.392962 124.7915)
		(width 1)
		(layer "In3.Cu")
		(net 472)
	)
	(segment
		(start 72.957962 157.2915)
		(end 72.957962 156.1465)
		(width 0.2)
		(layer "F.Cu")
		(net 473)
	)
	(segment
		(start 73.017962 158.525502)
		(end 73.017962 159.6715)
		(width 0.2)
		(layer "F.Cu")
		(net 474)
	)
	(segment
		(start 116.527962 138.7515)
		(end 117.587962 138.7515)
		(width 0.2)
		(layer "F.Cu")
		(net 475)
	)
	(segment
		(start 72.982962 162.0665)
		(end 72.982962 160.9015)
		(width 0.2)
		(layer "F.Cu")
		(net 476)
	)
	(segment
		(start 57.882962 134.8515)
		(end 58.467962 134.2665)
		(width 0.2)
		(layer "F.Cu")
		(net 477)
	)
	(segment
		(start 57.367962 134.8515)
		(end 57.882962 134.8515)
		(width 0.2)
		(layer "F.Cu")
		(net 477)
	)
	(segment
		(start 116.467962 134.4565)
		(end 117.582962 134.4565)
		(width 0.2)
		(layer "F.Cu")
		(net 478)
	)
	(segment
		(start 135.787962 155.4215)
		(end 136.342962 154.8665)
		(width 0.2)
		(layer "F.Cu")
		(net 479)
	)
	(segment
		(start 136.342962 154.8665)
		(end 137.302962 154.8665)
		(width 0.2)
		(layer "F.Cu")
		(net 479)
	)
	(segment
		(start 135.787962 156.0165)
		(end 135.787962 155.4215)
		(width 0.2)
		(layer "F.Cu")
		(net 479)
	)
	(segment
		(start 132.267962 154.5665)
		(end 131.437962 155.3965)
		(width 0.2)
		(layer "F.Cu")
		(net 480)
	)
	(segment
		(start 131.437962 155.3965)
		(end 131.437962 156.0165)
		(width 0.2)
		(layer "F.Cu")
		(net 480)
	)
	(segment
		(start 132.902962 154.5665)
		(end 132.267962 154.5665)
		(width 0.2)
		(layer "F.Cu")
		(net 480)
	)
	(segment
		(start 112.893962 117.2665)
		(end 112.893962 116.0555)
		(width 0.15)
		(layer "B.Cu")
		(net 481)
	)
	(segment
		(start 88.242962 122.0515)
		(end 88.242962 120.9915)
		(width 0.15)
		(layer "F.Cu")
		(net 482)
	)
	(segment
		(start 83.147962 120.7415)
		(end 84.192962 120.7415)
		(width 0.254)
		(layer "F.Cu")
		(net 483)
	)
	(segment
		(start 80.367962 124.4665)
		(end 81.347962 124.4665)
		(width 0.2)
		(layer "F.Cu")
		(net 484)
	)
	(segment
		(start 97.966962 144.7665)
		(end 99.768962 144.7665)
		(width 0.127)
		(layer "F.Cu")
		(net 485)
	)
	(segment
		(start 99.768962 144.7665)
		(end 100.318962 145.3165)
		(width 0.127)
		(layer "F.Cu")
		(net 485)
	)
	(segment
		(start 94.017962 139.507236)
		(end 94.483698 139.507236)
		(width 0.127)
		(layer "F.Cu")
		(net 486)
	)
	(segment
		(start 94.483698 139.507236)
		(end 94.717964 139.741502)
		(width 0.127)
		(layer "F.Cu")
		(net 486)
	)
	(segment
		(start 76.373962 136.5825)
		(end 76.373962 136.0415)
		(width 0.127)
		(layer "F.Cu")
		(net 486)
	)
	(segment
		(start 77.387962 137.5965)
		(end 76.373962 136.5825)
		(width 0.127)
		(layer "F.Cu")
		(net 486)
	)
	(segment
		(start 94.717964 139.741502)
		(end 94.717964 139.8165)
		(width 0.127)
		(layer "F.Cu")
		(net 486)
	)
	(via
		(at 94.717964 139.8165)
		(size 0.45)
		(drill 0.1)
		(layers "F.Cu" "B.Cu")
		(net 486)
	)
	(via
		(at 77.387962 137.5965)
		(size 0.45)
		(drill 0.1)
		(layers "F.Cu" "B.Cu")
		(net 486)
	)
	(segment
		(start 86.485184 137.4185)
		(end 88.883184 139.8165)
		(width 0.127)
		(layer "B.Cu")
		(net 486)
	)
	(segment
		(start 88.883184 139.8165)
		(end 94.717964 139.8165)
		(width 0.127)
		(layer "B.Cu")
		(net 486)
	)
	(segment
		(start 77.387962 137.5965)
		(end 77.565962 137.4185)
		(width 0.127)
		(layer "B.Cu")
		(net 486)
	)
	(segment
		(start 77.565962 137.4185)
		(end 86.485184 137.4185)
		(width 0.127)
		(layer "B.Cu")
		(net 486)
	)
	(segment
		(start 74.497962 136.0415)
		(end 75.359962 136.0415)
		(width 0.15)
		(layer "F.Cu")
		(net 487)
	)
	(segment
		(start 74.492962 136.0465)
		(end 74.497962 136.0415)
		(width 0.15)
		(layer "F.Cu")
		(net 487)
	)
	(segment
		(start 86.467962 134.434236)
		(end 86.406462 134.495736)
		(width 0.127)
		(layer "F.Cu")
		(net 488)
	)
	(segment
		(start 76.357962 133.3315)
		(end 76.342962 133.3165)
		(width 0.127)
		(layer "F.Cu")
		(net 488)
	)
	(segment
		(start 85.710094 134.349368)
		(end 85.856462 134.495736)
		(width 0.127)
		(layer "F.Cu")
		(net 488)
	)
	(segment
		(start 86.467962 133.957236)
		(end 86.467962 134.434236)
		(width 0.127)
		(layer "F.Cu")
		(net 488)
	)
	(segment
		(start 85.710094 134.349368)
		(end 85.20083 134.349368)
		(width 0.127)
		(layer "F.Cu")
		(net 488)
	)
	(segment
		(start 85.20083 134.349368)
		(end 84.567962 133.7165)
		(width 0.127)
		(layer "F.Cu")
		(net 488)
	)
	(segment
		(start 76.357962 134.1265)
		(end 76.357962 133.3315)
		(width 0.127)
		(layer "F.Cu")
		(net 488)
	)
	(segment
		(start 86.406462 134.495736)
		(end 85.856462 134.495736)
		(width 0.127)
		(layer "F.Cu")
		(net 488)
	)
	(via
		(at 76.357962 134.1265)
		(size 0.45)
		(drill 0.1)
		(layers "F.Cu" "B.Cu")
		(net 488)
	)
	(via
		(at 84.567962 133.7165)
		(size 0.45)
		(drill 0.1)
		(layers "F.Cu" "B.Cu")
		(net 488)
	)
	(segment
		(start 78.794962 131.6895)
		(end 82.540962 131.6895)
		(width 0.127)
		(layer "B.Cu")
		(net 488)
	)
	(segment
		(start 76.357962 134.1265)
		(end 78.794962 131.6895)
		(width 0.127)
		(layer "B.Cu")
		(net 488)
	)
	(segment
		(start 82.540962 131.6895)
		(end 84.567962 133.7165)
		(width 0.127)
		(layer "B.Cu")
		(net 488)
	)
	(segment
		(start 74.842962 133.3165)
		(end 74.842962 132.7165)
		(width 0.15)
		(layer "F.Cu")
		(net 489)
	)
	(segment
		(start 74.757962 132.6315)
		(end 74.842962 132.7165)
		(width 0.15)
		(layer "F.Cu")
		(net 489)
	)
	(segment
		(start 74.757962 132.1915)
		(end 74.757962 132.6315)
		(width 0.15)
		(layer "F.Cu")
		(net 489)
	)
	(segment
		(start 96.961962 146.7655)
		(end 98.519316 146.7655)
		(width 0.127)
		(layer "F.Cu")
		(net 490)
	)
	(segment
		(start 98.519316 146.7655)
		(end 98.783816 147.03)
		(width 0.127)
		(layer "F.Cu")
		(net 490)
	)
	(segment
		(start 102.267962 145.7665)
		(end 102.547962 145.4865)
		(width 0.2)
		(layer "F.Cu")
		(net 490)
	)
	(segment
		(start 101.417962 145.7665)
		(end 100.197962 146.9865)
		(width 0.2)
		(layer "F.Cu")
		(net 490)
	)
	(segment
		(start 100.154462 147.03)
		(end 100.197962 146.9865)
		(width 0.127)
		(layer "F.Cu")
		(net 490)
	)
	(segment
		(start 101.817962 145.7665)
		(end 102.267962 145.7665)
		(width 0.2)
		(layer "F.Cu")
		(net 490)
	)
	(segment
		(start 102.547962 144.6165)
		(end 102.547962 143.6165)
		(width 0.2)
		(layer "F.Cu")
		(net 490)
	)
	(segment
		(start 101.817962 145.7665)
		(end 101.417962 145.7665)
		(width 0.2)
		(layer "F.Cu")
		(net 490)
	)
	(segment
		(start 100.197962 146.9865)
		(end 100.197962 147.5665)
		(width 0.2)
		(layer "F.Cu")
		(net 490)
	)
	(segment
		(start 98.783816 147.03)
		(end 100.154462 147.03)
		(width 0.127)
		(layer "F.Cu")
		(net 490)
	)
	(segment
		(start 102.547962 145.4865)
		(end 102.547962 144.6165)
		(width 0.2)
		(layer "F.Cu")
		(net 490)
	)
	(segment
		(start 66.822962 145.0605)
		(end 66.757962 145.1255)
		(width 0.127)
		(layer "F.Cu")
		(net 491)
	)
	(segment
		(start 66.832962 143.9065)
		(end 66.822962 143.9165)
		(width 0.127)
		(layer "F.Cu")
		(net 491)
	)
	(segment
		(start 66.822962 143.9165)
		(end 66.822962 145.0605)
		(width 0.127)
		(layer "F.Cu")
		(net 491)
	)
	(segment
		(start 67.812962 143.9065)
		(end 66.832962 143.9065)
		(width 0.127)
		(layer "F.Cu")
		(net 491)
	)
	(segment
		(start 85.592962 120.7415)
		(end 87 120.7415)
		(width 0.254)
		(layer "F.Cu")
		(net 498)
	)
	(via
		(at 87 120.7415)
		(size 0.45)
		(drill 0.1)
		(layers "F.Cu" "B.Cu")
		(net 498)
	)
	(segment
		(start 86.5 120.7415)
		(end 87 120.7415)
		(width 0.254)
		(layer "B.Cu")
		(net 498)
	)
	(segment
		(start 86 119.4395)
		(end 86 117.43)
		(width 0.254)
		(layer "B.Cu")
		(net 499)
	)
	(segment
		(start 75.687962 153.7915)
		(end 75.687962 154.1865)
		(width 0.15)
		(layer "F.Cu")
		(net 500)
	)
	(segment
		(start 75.687962 154.1865)
		(end 76.017962 154.5165)
		(width 0.15)
		(layer "F.Cu")
		(net 500)
	)
	(via
		(at 76.017962 154.5165)
		(size 0.45)
		(drill 0.1)
		(layers "F.Cu" "B.Cu")
		(net 500)
	)
	(segment
		(start 74.148 154.048)
		(end 74.148 152.9)
		(width 0.15)
		(layer "B.Cu")
		(net 500)
	)
	(segment
		(start 74.6165 154.5165)
		(end 74.148 154.048)
		(width 0.15)
		(layer "B.Cu")
		(net 500)
	)
	(segment
		(start 76.017962 154.5165)
		(end 74.6165 154.5165)
		(width 0.15)
		(layer "B.Cu")
		(net 500)
	)
	(segment
		(start 68.06 168.85)
		(end 68.12 168.91)
		(width 0.2)
		(layer "F.Cu")
		(net 501)
	)
	(segment
		(start 73.46 177.54)
		(end 73.262962 177.342962)
		(width 0.2)
		(layer "F.Cu")
		(net 501)
	)
	(segment
		(start 72.992962 176.4615)
		(end 72.717962 176.1865)
		(width 0.2)
		(layer "F.Cu")
		(net 501)
	)
	(segment
		(start 67.397962 168.95)
		(end 67.397962 168.75)
		(width 0.2)
		(layer "F.Cu")
		(net 501)
	)
	(segment
		(start 73.262962 176.8115)
		(end 72.992962 176.5415)
		(width 0.2)
		(layer "F.Cu")
		(net 501)
	)
	(segment
		(start 67.397962 168.95)
		(end 67.497962 168.85)
		(width 0.2)
		(layer "F.Cu")
		(net 501)
	)
	(segment
		(start 67.397962 170.4165)
		(end 67.397962 169.4165)
		(width 0.2)
		(layer "F.Cu")
		(net 501)
	)
	(segment
		(start 72.717962 175.6165)
		(end 72.817962 175.5165)
		(width 0.2)
		(layer "F.Cu")
		(net 501)
	)
	(segment
		(start 67.397962 168.307038)
		(end 67.405 168.3)
		(width 0.2)
		(layer "F.Cu")
		(net 501)
	)
	(segment
		(start 72.817962 174.7915)
		(end 72.817962 175.5165)
		(width 0.2)
		(layer "F.Cu")
		(net 501)
	)
	(segment
		(start 72.717962 176.2665)
		(end 72.717962 176.2415)
		(width 0.2)
		(layer "F.Cu")
		(net 501)
	)
	(segment
		(start 67.547962 170.5665)
		(end 67.397962 170.4165)
		(width 0.254)
		(layer "F.Cu")
		(net 501)
	)
	(segment
		(start 68.592962 170.0665)
		(end 67.747962 170.0665)
		(width 0.2)
		(layer "F.Cu")
		(net 501)
	)
	(segment
		(start 67.747962 170.0665)
		(end 67.397962 170.4165)
		(width 0.2)
		(layer "F.Cu")
		(net 501)
	)
	(segment
		(start 67.497962 168.85)
		(end 68.06 168.85)
		(width 0.2)
		(layer "F.Cu")
		(net 501)
	)
	(segment
		(start 67.405 168.3)
		(end 67.405 167.275)
		(width 0.2)
		(layer "F.Cu")
		(net 501)
	)
	(segment
		(start 72.992962 176.5415)
		(end 72.992962 176.4615)
		(width 0.2)
		(layer "F.Cu")
		(net 501)
	)
	(segment
		(start 67.397962 168.75)
		(end 67.397962 168.307038)
		(width 0.2)
		(layer "F.Cu")
		(net 501)
	)
	(segment
		(start 73.262962 177.342962)
		(end 73.262962 176.8115)
		(width 0.2)
		(layer "F.Cu")
		(net 501)
	)
	(segment
		(start 68.592962 170.5665)
		(end 67.547962 170.5665)
		(width 0.254)
		(layer "F.Cu")
		(net 501)
	)
	(segment
		(start 67.397962 169.4165)
		(end 67.397962 168.95)
		(width 0.2)
		(layer "F.Cu")
		(net 501)
	)
	(segment
		(start 67.497962 168.85)
		(end 67.397962 168.75)
		(width 0.2)
		(layer "F.Cu")
		(net 501)
	)
	(segment
		(start 72.717962 176.1825)
		(end 72.717962 175.6165)
		(width 0.2)
		(layer "F.Cu")
		(net 501)
	)
	(via
		(at 73.46 177.54)
		(size 0.45)
		(drill 0.1)
		(layers "F.Cu" "B.Cu")
		(net 501)
	)
	(via
		(at 68.12 168.91)
		(size 0.45)
		(drill 0.1)
		(layers "F.Cu" "B.Cu")
		(net 501)
	)
	(segment
		(start 68.674 169.464)
		(end 68.674 171.574)
		(width 0.2)
		(layer "B.Cu")
		(net 501)
	)
	(segment
		(start 68.12 168.91)
		(end 68.674 169.464)
		(width 0.2)
		(layer "B.Cu")
		(net 501)
	)
	(segment
		(start 73.46 176.36)
		(end 73.46 177.54)
		(width 0.2)
		(layer "B.Cu")
		(net 501)
	)
	(segment
		(start 68.674 171.574)
		(end 73.46 176.36)
		(width 0.2)
		(layer "B.Cu")
		(net 501)
	)
	(segment
		(start 128.637661 171.577)
		(end 128.266548 171.205887)
		(width 0.254)
		(layer "B.Cu")
		(net 502)
	)
	(segment
		(start 127.3 177.72)
		(end 131.906 177.72)
		(width 0.254)
		(layer "B.Cu")
		(net 502)
	)
	(segment
		(start 130.429 171.577)
		(end 128.637661 171.577)
		(width 0.254)
		(layer "B.Cu")
		(net 502)
	)
	(segment
		(start 131.906 177.72)
		(end 133.731 175.895)
		(width 0.254)
		(layer "B.Cu")
		(net 502)
	)
	(segment
		(start 133.731 174.879)
		(end 130.429 171.577)
		(width 0.254)
		(layer "B.Cu")
		(net 502)
	)
	(segment
		(start 133.731 175.895)
		(end 133.731 174.879)
		(width 0.254)
		(layer "B.Cu")
		(net 502)
	)
	(segment
		(start 124.33 176.908)
		(end 124.968 177.546)
		(width 0.254)
		(layer "B.Cu")
		(net 503)
	)
	(segment
		(start 126.301 178.7)
		(end 127.28 178.7)
		(width 0.254)
		(layer "B.Cu")
		(net 503)
	)
	(segment
		(start 127.28 178.7)
		(end 127.3 178.68)
		(width 0.254)
		(layer "B.Cu")
		(net 503)
	)
	(segment
		(start 125.73 177.546)
		(end 126.301 178.117)
		(width 0.254)
		(layer "B.Cu")
		(net 503)
	)
	(segment
		(start 124.968 177.546)
		(end 125.73 177.546)
		(width 0.254)
		(layer "B.Cu")
		(net 503)
	)
	(segment
		(start 126.301 178.117)
		(end 126.301 178.7)
		(width 0.254)
		(layer "B.Cu")
		(net 503)
	)
	(segment
		(start 123.237 176.908)
		(end 124.33 176.908)
		(width 0.254)
		(layer "B.Cu")
		(net 503)
	)
	(segment
		(start 125.329 173.756)
		(end 124.714 174.371)
		(width 0.254)
		(layer "B.Cu")
		(net 505)
	)
	(segment
		(start 124.714 174.371)
		(end 123.237 174.371)
		(width 0.254)
		(layer "B.Cu")
		(net 505)
	)
	(segment
		(start 125.73 173.756)
		(end 125.329 173.756)
		(width 0.254)
		(layer "B.Cu")
		(net 505)
	)
	(segment
		(start 124.714 175.641)
		(end 123.237 175.641)
		(width 0.254)
		(layer "B.Cu")
		(net 506)
	)
	(segment
		(start 125.73 176.256)
		(end 125.329 176.256)
		(width 0.254)
		(layer "B.Cu")
		(net 506)
	)
	(segment
		(start 125.329 176.256)
		(end 124.714 175.641)
		(width 0.254)
		(layer "B.Cu")
		(net 506)
	)
	(zone
		(net 0)
		(net_name "")
		(layer "F.Cu")
		(hatch edge 0.5)
		(connect_pads
			(clearance 0)
		)
		(min_thickness 0.25)
		(filled_areas_thickness no)
		(keepout
			(tracks allowed)
			(vias allowed)
			(pads allowed)
			(copperpour not_allowed)
			(footprints allowed)
		)
		(placement
			(enabled no)
			(sheetname "")
		)
		(fill
			(thermal_gap 0.5)
			(thermal_bridge_width 0.5)
		)
		(polygon
			(pts
				(xy 110.351464 156.7765) (xy 111.551464 156.7765) (xy 111.551464 158.2765) (xy 110.351464 158.2765)
			)
		)
	)
	(zone
		(net 0)
		(net_name "")
		(layer "F.Cu")
		(hatch edge 0.5)
		(connect_pads
			(clearance 0)
		)
		(min_thickness 0.127)
		(filled_areas_thickness no)
		(keepout
			(tracks allowed)
			(vias allowed)
			(pads allowed)
			(copperpour not_allowed)
			(footprints allowed)
		)
		(placement
			(enabled no)
			(sheetname "")
		)
		(fill
			(thermal_gap 0.2)
			(thermal_bridge_width 0.35)
		)
		(polygon
			(pts
				(xy 48.857962 128.3165) (xy 48.397962 132.7965) (xy 52.587962 132.8265) (xy 52.627962 128.2065)
				(xy 49.077962 127.9365)
			)
		)
	)
	(zone
		(net 0)
		(net_name "")
		(layer "F.Cu")
		(hatch edge 0.508)
		(connect_pads
			(clearance 0)
		)
		(min_thickness 0.127)
		(filled_areas_thickness no)
		(keepout
			(tracks allowed)
			(vias allowed)
			(pads allowed)
			(copperpour not_allowed)
			(footprints allowed)
		)
		(placement
			(enabled no)
			(sheetname "")
		)
		(fill
			(thermal_gap 0.127)
			(thermal_bridge_width 0.25)
		)
		(polygon
			(pts
				(xy 111.217962 120.3915) (xy 111.217962 130.7915) (xy 110.367962 131.6415) (xy 108.217962 131.6415)
				(xy 107.117962 130.5415) (xy 107.117962 129.0915) (xy 106.942962 128.9165) (xy 105.767962 128.9165)
				(xy 104.242962 127.3915) (xy 104.242962 120.3915)
			)
		)
	)
	(zone
		(net 0)
		(net_name "")
		(layer "F.Cu")
		(hatch edge 0.5)
		(connect_pads
			(clearance 0)
		)
		(min_thickness 0.25)
		(filled_areas_thickness no)
		(keepout
			(tracks allowed)
			(vias allowed)
			(pads allowed)
			(copperpour not_allowed)
			(footprints allowed)
		)
		(placement
			(enabled no)
			(sheetname "")
		)
		(fill
			(thermal_gap 0.5)
			(thermal_bridge_width 0.5)
		)
		(polygon
			(pts
				(xy 107.567962 155.5665) (xy 108.767962 155.5665) (xy 108.767962 157.0665) (xy 107.567962 157.0665)
			)
		)
	)
	(zone
		(net 443)
		(net_name "/Supply/V_{BUS}")
		(layer "F.Cu")
		(hatch edge 0.5)
		(priority 22)
		(connect_pads
			(clearance 0.3)
		)
		(min_thickness 0.25)
		(filled_areas_thickness no)
		(fill yes
			(thermal_gap 0.5)
			(thermal_bridge_width 0.5)
		)
		(polygon
			(pts
				(xy 74.2 133.6) (xy 74.2 131.2) (xy 76.4 131.2) (xy 76.4 129.5) (xy 73 129.5) (xy 73 133.6)
			)
		)
	)
	(zone
		(net 3)
		(net_name "GND")
		(layer "F.Cu")
		(hatch edge 0.5)
		(priority 16)
		(connect_pads
			(clearance 0.15)
		)
		(min_thickness 0.15)
		(filled_areas_thickness no)
		(fill yes
			(thermal_gap 0.2)
			(thermal_bridge_width 0.35)
			(smoothing fillet)
			(radius 0.1)
		)
		(polygon
			(pts
				(xy 49.627962 122.6765) (xy 54.607962 122.6365) (xy 54.567962 111.7365) (xy 36.867962 111.7065)
				(xy 36.887962 129.8265) (xy 43.727962 129.8265)
			)
		)
	)
	(zone
		(net 472)
		(net_name "Net-(D301-C)")
		(layer "F.Cu")
		(hatch edge 0.5)
		(priority 17)
		(connect_pads
			(clearance 0.15)
		)
		(min_thickness 0.127)
		(filled_areas_thickness no)
		(fill yes
			(thermal_gap 0.15)
			(thermal_bridge_width 0.35)
			(smoothing fillet)
			(radius 0.1)
		)
		(polygon
			(pts
				(xy 46.867962 123.6165) (xy 49.357962 122.3865) (xy 49.357962 119.3565) (xy 46.837962 119.3365)
				(xy 40.787962 119.8465) (xy 40.397962 122.1965) (xy 38.167962 124.6465) (xy 38.167962 126.3065)
				(xy 41.927962 126.3065)
			)
		)
	)
	(zone
		(net 3)
		(net_name "GND")
		(layer "F.Cu")
		(hatch edge 0.5)
		(priority 19)
		(connect_pads
			(clearance 0.15)
		)
		(min_thickness 0.15)
		(filled_areas_thickness no)
		(fill yes
			(thermal_gap 0.15)
			(thermal_bridge_width 0.4)
			(smoothing fillet)
			(radius 0.125)
		)
		(polygon
			(pts
				(xy 76.127962 125.2165) (xy 76.127962 120.9765) (xy 76.907962 120.0265) (xy 76.887962 118.4165)
				(xy 75.837962 117.1065) (xy 73.287962 117.0865) (xy 73.327962 124.4165) (xy 74.037962 125.2165)
			)
		)
	)
	(zone
		(net 1)
		(net_name "GNDD")
		(layers "F.Cu" "B.Cu")
		(hatch edge 0.5)
		(priority 6)
		(connect_pads
			(clearance 0.3)
		)
		(min_thickness 0.15)
		(filled_areas_thickness no)
		(fill yes
			(thermal_gap 0.15)
			(thermal_bridge_width 0.35)
			(smoothing fillet)
			(radius 0.1)
		)
		(polygon
			(pts
				(xy 52.017962 132.9665) (xy 49.197962 132.9665) (xy 39.982962 138.2715) (xy 39.982962 149.571568)
				(xy 64.432023 149.5769) (xy 64.437962 140.9465) (xy 61.472057 137.329542) (xy 57.847962 137.3265)
			)
		)
	)
	(zone
		(net 0)
		(net_name "")
		(layers "F.Cu" "B.Cu" "In1.Cu" "In2.Cu" "In3.Cu" "In4.Cu")
		(hatch edge 0.5)
		(connect_pads
			(clearance 0)
		)
		(min_thickness 0.25)
		(filled_areas_thickness no)
		(keepout
			(tracks not_allowed)
			(vias not_allowed)
			(pads not_allowed)
			(copperpour not_allowed)
			(footprints allowed)
		)
		(placement
			(enabled no)
			(sheetname "")
		)
		(fill
			(thermal_gap 0.5)
			(thermal_bridge_width 0.5)
		)
		(polygon
			(pts
				(xy 39.722962 149.831568) (xy 39.967962 151.8665) (xy 63.792962 151.8665) (xy 64.632023 149.8669)
			)
		)
	)
	(zone
		(net 0)
		(net_name "")
		(layers "F.Cu" "B.Cu" "In1.Cu" "In2.Cu" "In3.Cu" "In4.Cu")
		(hatch edge 0.5)
		(connect_pads
			(clearance 0)
		)
		(min_thickness 0.25)
		(filled_areas_thickness no)
		(keepout
			(tracks allowed)
			(vias allowed)
			(pads allowed)
			(copperpour not_allowed)
			(footprints allowed)
		)
		(placement
			(enabled no)
			(sheetname "")
		)
		(fill
			(thermal_gap 0.5)
			(thermal_bridge_width 0.5)
		)
		(polygon
			(pts
				(xy 57.217962 120.5665) (xy 57.217962 124.0665) (xy 55.492962 124.9165) (xy 55.492962 126.7915)
				(xy 57.217962 127.3665) (xy 57.217962 128.0915) (xy 72.292962 128.0915) (xy 72.292962 127.3915)
				(xy 74.017962 126.7915) (xy 74.017962 124.9165) (xy 72.292962 124.0915) (xy 72.292962 120.5665)
				(xy 57.242962 120.5665)
			)
		)
	)
	(zone
		(net 90)
		(net_name "/Ethernet/VSS")
		(layers "F.Cu" "B.Cu" "In1.Cu" "In2.Cu" "In3.Cu" "In4.Cu")
		(hatch edge 0.5)
		(priority 3)
		(connect_pads
			(clearance 0.5)
		)
		(min_thickness 0.125)
		(filled_areas_thickness no)
		(fill yes
			(thermal_gap 0.18)
			(thermal_bridge_width 0.35)
			(smoothing fillet)
			(radius 0.1)
		)
		(polygon
			(pts
				(xy 47.81 123.85) (xy 45.285929 128) (xy 45.277962 135.4465) (xy 54.342962 135.4665) (xy 54.382962 123.8765)
			)
		)
	)
	(zone
		(net 0)
		(net_name "")
		(layers "F.Cu" "In1.Cu")
		(hatch edge 0.5)
		(connect_pads
			(clearance 0)
		)
		(min_thickness 0.127)
		(filled_areas_thickness no)
		(keepout
			(tracks allowed)
			(vias allowed)
			(pads allowed)
			(copperpour not_allowed)
			(footprints allowed)
		)
		(placement
			(enabled no)
			(sheetname "")
		)
		(fill
			(thermal_gap 0.2)
			(thermal_bridge_width 0.35)
		)
		(polygon
			(pts
				(xy 107.255 155.2665) (xy 108.955 155.2665) (xy 108.955 157.3665) (xy 107.255 157.3665)
			)
		)
	)
	(zone
		(net 0)
		(net_name "")
		(layers "F.Cu" "In1.Cu")
		(hatch edge 0.5)
		(connect_pads
			(clearance 0)
		)
		(min_thickness 0.127)
		(filled_areas_thickness no)
		(keepout
			(tracks allowed)
			(vias allowed)
			(pads allowed)
			(copperpour not_allowed)
			(footprints allowed)
		)
		(placement
			(enabled no)
			(sheetname "")
		)
		(fill
			(thermal_gap 0.2)
			(thermal_bridge_width 0.35)
		)
		(polygon
			(pts
				(xy 119.44 156.4665) (xy 121.14 156.4665) (xy 121.14 158.5665) (xy 119.44 158.5665)
			)
		)
	)
	(zone
		(net 0)
		(net_name "")
		(layers "F.Cu" "In1.Cu")
		(hatch edge 0.5)
		(connect_pads
			(clearance 0)
		)
		(min_thickness 0.127)
		(filled_areas_thickness no)
		(keepout
			(tracks allowed)
			(vias allowed)
			(pads allowed)
			(copperpour not_allowed)
			(footprints allowed)
		)
		(placement
			(enabled no)
			(sheetname "")
		)
		(fill
			(thermal_gap 0.2)
			(thermal_bridge_width 0.35)
		)
		(polygon
			(pts
				(xy 119.45 153.9665) (xy 121.15 153.9665) (xy 121.15 156.2665) (xy 119.45 156.2665)
			)
		)
	)
	(zone
		(net 0)
		(net_name "")
		(layers "F.Cu" "In1.Cu")
		(hatch edge 0.5)
		(connect_pads
			(clearance 0)
		)
		(min_thickness 0.127)
		(filled_areas_thickness no)
		(keepout
			(tracks allowed)
			(vias allowed)
			(pads allowed)
			(copperpour not_allowed)
			(footprints allowed)
		)
		(placement
			(enabled no)
			(sheetname "")
		)
		(fill
			(thermal_gap 0.2)
			(thermal_bridge_width 0.35)
		)
		(polygon
			(pts
				(xy 117.02 152.7) (xy 118.72 152.7) (xy 118.72 155) (xy 117.02 155)
			)
		)
	)
	(zone
		(net 0)
		(net_name "")
		(layers "F.Cu" "In1.Cu")
		(hatch edge 0.5)
		(connect_pads
			(clearance 0)
		)
		(min_thickness 0.127)
		(filled_areas_thickness no)
		(keepout
			(tracks allowed)
			(vias allowed)
			(pads allowed)
			(copperpour not_allowed)
			(footprints allowed)
		)
		(placement
			(enabled no)
			(sheetname "")
		)
		(fill
			(thermal_gap 0.2)
			(thermal_bridge_width 0.35)
		)
		(polygon
			(pts
				(xy 110.101464 156.4765) (xy 111.801464 156.4765) (xy 111.801464 158.5765) (xy 110.101464 158.5765)
			)
		)
	)
	(zone
		(net 0)
		(net_name "")
		(layers "F.Cu" "In1.Cu")
		(hatch edge 0.5)
		(connect_pads
			(clearance 0)
		)
		(min_thickness 0.127)
		(filled_areas_thickness no)
		(keepout
			(tracks allowed)
			(vias allowed)
			(pads allowed)
			(copperpour not_allowed)
			(footprints allowed)
		)
		(placement
			(enabled no)
			(sheetname "")
		)
		(fill
			(thermal_gap 0.2)
			(thermal_bridge_width 0.35)
		)
		(polygon
			(pts
				(xy 117.02 155.1665) (xy 118.72 155.1665) (xy 118.72 157.4665) (xy 117.02 157.4665)
			)
		)
	)
	(zone
		(net 0)
		(net_name "")
		(layer "B.Cu")
		(hatch edge 0.5)
		(connect_pads
			(clearance 0)
		)
		(min_thickness 0.3)
		(filled_areas_thickness no)
		(keepout
			(tracks allowed)
			(vias allowed)
			(pads allowed)
			(copperpour not_allowed)
			(footprints allowed)
		)
		(placement
			(enabled no)
			(sheetname "")
		)
		(fill
			(thermal_gap 0.5)
			(thermal_bridge_width 0.5)
		)
		(polygon
			(pts
				(xy 54.762962 127.1065) (xy 54.75 135.0395) (xy 57.847962 137.3265) (xy 61.75 137.329542) (xy 61.75 127.5)
				(xy 72.292962 120.5665) (xy 72.317962 111.7415) (xy 52.25 111.7165) (xy 52.25 123.866288) (xy 54.777962 123.8765)
			)
		)
	)
	(zone
		(net 47)
		(net_name "/Ethernet/POE_12V")
		(layer "B.Cu")
		(hatch edge 0.5)
		(priority 9)
		(connect_pads
			(clearance 0.2)
		)
		(min_thickness 0.15)
		(filled_areas_thickness no)
		(fill yes
			(thermal_gap 0.2)
			(thermal_bridge_width 0.35)
			(smoothing fillet)
			(radius 0.15)
		)
		(polygon
			(pts
				(xy 54.387962 166.4065) (xy 54.387962 168.7365) (xy 53.047962 169.3165) (xy 53.037962 170.2065)
				(xy 53.677962 170.2065) (xy 53.917962 171.2765) (xy 59.567962 171.2965) (xy 59.737962 170.5865)
				(xy 61.637962 170.5865) (xy 61.627962 166.1565) (xy 61.277962 165.7965) (xy 61.277962 164.2865)
				(xy 60.917962 164.2865) (xy 60.927962 165.9465) (xy 58.149316 165.937565) (xy 58.169286 163.6765)
				(xy 55.187962 163.6765)
			)
		)
	)
	(zone
		(net 0)
		(net_name "")
		(layer "B.Cu")
		(name "No_GND")
		(hatch edge 0.5)
		(connect_pads
			(clearance 0)
		)
		(min_thickness 0.25)
		(filled_areas_thickness no)
		(keepout
			(tracks allowed)
			(vias allowed)
			(pads allowed)
			(copperpour not_allowed)
			(footprints allowed)
		)
		(placement
			(enabled no)
			(sheetname "")
		)
		(fill
			(thermal_gap 0.5)
			(thermal_bridge_width 0.5)
		)
		(polygon
			(pts
				(xy 110 151.8) (xy 127.9 151.8) (xy 123 156.5) (xy 123 162) (xy 110 162)
			)
		)
	)
	(zone
		(net 472)
		(net_name "Net-(D301-C)")
		(layer "B.Cu")
		(hatch edge 0.5)
		(priority 21)
		(connect_pads yes
			(clearance 0.15)
		)
		(min_thickness 0.25)
		(filled_areas_thickness no)
		(fill yes
			(thermal_gap 0.5)
			(thermal_bridge_width 0.5)
			(smoothing fillet)
			(radius 0.2)
		)
		(polygon
			(pts
				(xy 43.9 165.4) (xy 43.9 166.65) (xy 40.55 166.65) (xy 39.6 165.85) (xy 39.6 163) (xy 40.85 163)
				(xy 40.85 165.1) (xy 41.05 165.4)
			)
		)
	)
	(zone
		(net 111)
		(net_name "/USB/SW_FTDI")
		(layer "B.Cu")
		(hatch edge 0.5)
		(priority 14)
		(connect_pads yes
			(clearance 0.127)
		)
		(min_thickness 0.127)
		(filled_areas_thickness no)
		(fill yes
			(thermal_gap 0.2)
			(thermal_bridge_width 0.35)
			(smoothing fillet)
			(radius 0.15)
		)
		(polygon
			(pts
				(xy 86.942962 125.8165) (xy 86.942962 127.5415) (xy 87.642962 127.5415) (xy 87.642962 126.3415)
				(xy 87.817962 126.2165) (xy 89.267962 126.1165) (xy 92.067962 126.1165) (xy 92.067962 123.9665)
				(xy 89.267962 123.9915)
			)
		)
	)
	(zone
		(net 0)
		(net_name "")
		(layer "B.Cu")
		(hatch edge 0.508)
		(connect_pads
			(clearance 0)
		)
		(min_thickness 0.127)
		(filled_areas_thickness no)
		(keepout
			(tracks allowed)
			(vias allowed)
			(pads allowed)
			(copperpour not_allowed)
			(footprints allowed)
		)
		(placement
			(enabled no)
			(sheetname "")
		)
		(fill
			(thermal_gap 0.127)
			(thermal_bridge_width 0.25)
		)
		(polygon
			(pts
				(xy 86.625 176.78) (xy 92.025 176.78) (xy 92.05 176.755) (xy 92.05 165.055) (xy 92.9 164.205) (xy 95.375 164.205)
				(xy 104.6 173.43) (xy 122.25 173.43) (xy 125.6 170.08) (xy 125.6 169.05) (xy 126 168.675) (xy 140.1 168.675)
				(xy 140.1 158.13) (xy 139.575 157.605) (xy 129.39 157.72) (xy 125.5 161.455) (xy 122.825 161.455)
				(xy 122.275 160.855) (xy 122.275 159.418889) (xy 120.225 157.255) (xy 115.5 157.255) (xy 109.71 157.27)
				(xy 109.685671 154.594329) (xy 112.42 151.84) (xy 125.345 151.84) (xy 137.441606 139.705) (xy 138.025 137.553717)
				(xy 138.025 130.23) (xy 139.325 128.93) (xy 139.325 124.555) (xy 138.475 123.705) (xy 132.725 123.705)
				(xy 128.1 119.08) (xy 121.325 119.08) (xy 120.55 119.855) (xy 120.55 123.73) (xy 121.675 124.855)
				(xy 121.675 133.68) (xy 117.325 138.03) (xy 106.9 138.03) (xy 106.375 137.505) (xy 106.375 135.055)
				(xy 111.425 130.005) (xy 111.425 127.255) (xy 109.225 125.055) (xy 103.075 125.055) (xy 102.8 125.33)
				(xy 102.8 127.505) (xy 102.825 127.53) (xy 99.325 130.93) (xy 97.925 132.33) (xy 97.925 155.355)
				(xy 96.7 156.58) (xy 81.25 156.58) (xy 80.3 155.63) (xy 76.325 155.63) (xy 75.675 156.28) (xy 75.675 162.205)
				(xy 77.55 164.08) (xy 83.88 164.12) (xy 83.935 174.11)
			)
		)
	)
	(zone
		(net 0)
		(net_name "")
		(layer "B.Cu")
		(hatch edge 0.5)
		(connect_pads
			(clearance 0)
		)
		(min_thickness 0.15)
		(filled_areas_thickness no)
		(keepout
			(tracks allowed)
			(vias allowed)
			(pads allowed)
			(copperpour not_allowed)
			(footprints allowed)
		)
		(placement
			(enabled no)
			(sheetname "")
		)
		(fill
			(thermal_gap 0.15)
			(thermal_bridge_width 0.4)
		)
		(polygon
			(pts
				(xy 127.947962 115.3665) (xy 128.407962 115.3665) (xy 128.407962 116.6665) (xy 127.947962 116.6565)
			)
		)
	)
	(zone
		(net 77)
		(net_name "/Supply/OUT_5V")
		(layer "B.Cu")
		(hatch edge 0.5)
		(priority 18)
		(connect_pads yes
			(clearance 0.15)
		)
		(min_thickness 0.127)
		(filled_areas_thickness no)
		(fill yes
			(thermal_gap 0.15)
			(thermal_bridge_width 0.35)
			(smoothing fillet)
			(radius 0.1)
		)
		(polygon
			(pts
				(xy 56.067962 159.8665) (xy 58.467962 160.0665) (xy 63.957962 160.0665) (xy 66.507962 159.8765)
				(xy 68.707962 159.8765) (xy 68.997962 159.5565) (xy 69.487962 159.5465) (xy 69.487962 158.7765)
				(xy 68.907962 158.7565) (xy 68.377962 158.4265) (xy 63.937962 158.3565) (xy 58.457962 158.3665)
				(xy 56.067962 158.6665)
			)
		)
	)
	(zone
		(net 59)
		(net_name "/Supply/SW_5V")
		(layer "B.Cu")
		(hatch edge 0.5)
		(priority 15)
		(connect_pads yes
			(clearance 0.127)
		)
		(min_thickness 0.127)
		(filled_areas_thickness no)
		(fill yes
			(thermal_gap 0.2)
			(thermal_bridge_width 0.35)
			(smoothing fillet)
			(radius 0.15)
		)
		(polygon
			(pts
				(xy 53.917962 155.6415) (xy 55.517962 155.6415) (xy 55.917962 155.5165) (xy 56.417962 155.5165)
				(xy 57.492962 154.4665) (xy 59.592962 154.4665) (xy 59.592962 155.8665) (xy 58.442962 155.8665)
				(xy 57.092962 155.8415) (xy 56.692962 156.0915) (xy 55.917962 156.0915) (xy 55.517962 155.9915)
				(xy 53.917962 155.9915)
			)
		)
	)
	(zone
		(net 10)
		(net_name "+5V")
		(layer "B.Cu")
		(hatch edge 0.5)
		(priority 10)
		(connect_pads
			(clearance 0.2)
		)
		(min_thickness 0.2)
		(filled_areas_thickness no)
		(fill yes
			(thermal_gap 0.2)
			(thermal_bridge_width 0.35)
			(smoothing fillet)
			(radius 0.1)
		)
		(polygon
			(pts
				(xy 68.917962 160.9465) (xy 72.462962 160.9915) (xy 72.462962 157.3315) (xy 68.917962 157.2865)
			)
		)
	)
	(zone
		(net 49)
		(net_name "/Supply/SW_3V3")
		(layer "B.Cu")
		(hatch edge 0.5)
		(priority 14)
		(connect_pads yes
			(clearance 0.127)
		)
		(min_thickness 0.127)
		(filled_areas_thickness no)
		(fill yes
			(thermal_gap 0.2)
			(thermal_bridge_width 0.35)
			(smoothing fillet)
			(radius 0.15)
		)
		(polygon
			(pts
				(xy 65.817962 163.9165) (xy 65.817962 165.6415) (xy 66.517962 165.6415) (xy 66.517962 164.4415)
				(xy 66.692962 164.3165) (xy 68.142962 164.2165) (xy 70.942962 164.2165) (xy 70.942962 162.8665)
				(xy 68.142962 162.8665)
			)
		)
	)
	(zone
		(net 21)
		(net_name "/Supply/VCC_IN")
		(layer "B.Cu")
		(hatch edge 0.5)
		(priority 4)
		(connect_pads
			(clearance 0.2)
		)
		(min_thickness 0.2)
		(filled_areas_thickness no)
		(fill yes
			(thermal_gap 0.2)
			(thermal_bridge_width 0.35)
			(smoothing fillet)
			(radius 0.15)
		)
		(polygon
			(pts
				(xy 41.167962 159.8865) (xy 39.6 161.25) (xy 39.6 162.3) (xy 43.217962 162.3015) (xy 43.267962 161.2665)
				(xy 46.642962 161.2665) (xy 46.642962 163.0665) (xy 47.527962 163.0565) (xy 48.022962 162.3015)
				(xy 50.417962 162.3015) (xy 50.417962 161.2915) (xy 53.792962 161.2915) (xy 53.792962 163.0415)
				(xy 55.042962 163.0415) (xy 55.042962 162.2515) (xy 57.592962 162.2515) (xy 57.592962 161.2165)
				(xy 60.917962 161.2165) (xy 60.917962 163.1165) (xy 61.267962 163.1415) (xy 61.292962 160.8165)
				(xy 57.592962 160.2915) (xy 53.992962 159.3415) (xy 47.642962 159.3365) (xy 47.642962 156.4165)
				(xy 46.842962 156.4165) (xy 46.842962 156.9165) (xy 43.967962 156.9165) (xy 43.967962 158.3415)
				(xy 43.217962 158.3415) (xy 43.217962 159.2215) (xy 42.777962 160.0265) (xy 41.597962 160.0365)
				(xy 41.597962 159.3665) (xy 41.167962 159.3665)
			)
		)
	)
	(zone
		(net 45)
		(net_name "/Supply/SW_M2")
		(layer "B.Cu")
		(hatch edge 0.5)
		(priority 14)
		(connect_pads yes
			(clearance 0.127)
		)
		(min_thickness 0.127)
		(filled_areas_thickness no)
		(fill yes
			(thermal_gap 0.2)
			(thermal_bridge_width 0.35)
			(smoothing fillet)
			(radius 0.15)
		)
		(polygon
			(pts
				(xy 109.949029 133.762792) (xy 109.949029 135.487792) (xy 110.649029 135.487792) (xy 110.649029 134.287792)
				(xy 110.824029 134.162792) (xy 112.274029 134.062792) (xy 115.074029 134.062792) (xy 115.074029 132.712792)
				(xy 112.274029 132.712792)
			)
		)
	)
	(zone
		(net 3)
		(net_name "GND")
		(layer "B.Cu")
		(hatch edge 0.508)
		(connect_pads
			(clearance 0.2)
		)
		(min_thickness 0.15)
		(filled_areas_thickness no)
		(fill yes
			(thermal_gap 0.22)
			(thermal_bridge_width 0.22)
			(smoothing fillet)
			(radius 0.15)
		)
		(polygon
			(pts
				(xy 143.927962 179.6165) (xy 36.877962 179.6165) (xy 36.877962 111.6165) (xy 143.927962 111.6665)
			)
		)
	)
	(zone
		(net 43)
		(net_name "VCC")
		(layer "B.Cu")
		(hatch edge 0.5)
		(priority 8)
		(connect_pads
			(clearance 0.2)
		)
		(min_thickness 0.2)
		(filled_areas_thickness no)
		(fill yes
			(thermal_gap 0.2)
			(thermal_bridge_width 0.4)
			(smoothing fillet)
			(radius 0.15)
		)
		(polygon
			(pts
				(xy 40.657962 153.6465) (xy 40.637962 156.9765) (xy 46.842962 156.9165) (xy 46.842962 156.4165)
				(xy 47.642962 156.4165) (xy 47.642962 156.3415) (xy 50.792962 156.3415) (xy 51.292962 155.6) (xy 54.532962 155.5965)
				(xy 54.532962 154.9965) (xy 52.992962 154.99) (xy 52.987962 154.1065) (xy 52.217962 153.7165) (xy 52.217962 152.9865)
				(xy 43.037962 152.9815)
			)
		)
	)
	(zone
		(net 9)
		(net_name "+3V3")
		(layer "B.Cu")
		(hatch edge 0.508)
		(priority 13)
		(connect_pads
			(clearance 0.2)
		)
		(min_thickness 0.2)
		(filled_areas_thickness no)
		(fill yes
			(thermal_gap 0.2)
			(thermal_bridge_width 0.35)
			(smoothing fillet)
			(radius 0.1)
		)
		(polygon
			(pts
				(xy 74.265258 165.545872) (xy 74.265258 166.685872) (xy 75.895258 166.685872) (xy 75.910258 163.850872)
				(xy 73.267962 163.850872) (xy 73.267962 165.5665)
			)
		)
	)
	(zone
		(net 1)
		(net_name "GNDD")
		(layers "B.Cu" "In1.Cu" "In2.Cu" "In3.Cu" "In4.Cu")
		(hatch edge 0.5)
		(priority 5)
		(connect_pads
			(clearance 0.6)
		)
		(min_thickness 0.15)
		(filled_areas_thickness no)
		(fill yes
			(thermal_gap 0.15)
			(thermal_bridge_width 0.35)
			(smoothing fillet)
			(radius 0.1)
		)
		(polygon
			(pts
				(xy 52.017962 132.9665) (xy 49.197962 132.9665) (xy 39.692962 138.3215) (xy 39.722962 149.831568)
				(xy 64.57 149.78) (xy 64.607962 141.0265) (xy 61.472057 137.329542) (xy 57.847962 137.3265)
			)
		)
	)
	(zone
		(net 3)
		(net_name "GND")
		(layers "In1.Cu" "In2.Cu" "In3.Cu" "In4.Cu")
		(hatch edge 0.508)
		(connect_pads
			(clearance 0.125)
		)
		(min_thickness 0.125)
		(filled_areas_thickness no)
		(fill yes
			(thermal_gap 0.125)
			(thermal_bridge_width 0.25)
			(smoothing fillet)
			(radius 0.15)
		)
		(polygon
			(pts
				(xy 143.917962 152.6) (xy 143.917962 166.13325) (xy 143.917962 179.6665) (xy 36.867962 179.6665)
				(xy 36.867962 111.6665) (xy 143.917962 111.7165)
			)
		)
	)
	(zone
		(net 43)
		(net_name "VCC")
		(layer "In2.Cu")
		(hatch edge 0.5)
		(priority 7)
		(connect_pads
			(clearance 0.25)
		)
		(min_thickness 0.25)
		(filled_areas_thickness no)
		(fill yes
			(thermal_gap 0.5)
			(thermal_bridge_width 0.5)
			(smoothing fillet)
			(radius 0.2)
		)
		(polygon
			(pts
				(xy 65.467962 157.9665) (xy 63.792962 151.8665) (xy 58.717962 151.857024) (xy 42.817962 151.857024)
				(xy 42.857962 157.7665) (xy 58.017962 164.8265) (xy 61.647962 166.3915) (xy 64.13262 166.3915)
			)
		)
	)
	(zone
		(net 9)
		(net_name "+3V3")
		(layer "In2.Cu")
		(hatch edge 0.5)
		(priority 1)
		(connect_pads
			(clearance 0.15)
		)
		(min_thickness 0.15)
		(filled_areas_thickness no)
		(fill yes
			(thermal_gap 0.2)
			(thermal_bridge_width 0.35)
			(smoothing fillet)
			(radius 0.1)
		)
		(polygon
			(pts
				(xy 75.467962 163.7415) (xy 73.592962 163.7415) (xy 65.18 168.42) (xy 65.85 169.6) (xy 70.527502 172.818629)
				(xy 73.477962 179.6865) (xy 143.967962 179.6665) (xy 143.967962 111.7165) (xy 118.467962 111.7165)
				(xy 118.467962 120.0165) (xy 140.067962 124.4415) (xy 140.017962 138.7665) (xy 139.992962 151.1415)
				(xy 128.817962 160.7665) (xy 125.317962 171.6165) (xy 109.285971 171.634288) (xy 104.417962 173.1165)
				(xy 88.844267 173.1165) (xy 83.091307 170.968155)
			)
		)
	)
	(zone
		(net 472)
		(net_name "Net-(D301-C)")
		(layer "In2.Cu")
		(hatch edge 0.5)
		(priority 4)
		(connect_pads
			(clearance 0.15)
		)
		(min_thickness 0.127)
		(filled_areas_thickness no)
		(fill yes
			(thermal_gap 0.15)
			(thermal_bridge_width 0.35)
			(smoothing fillet)
			(radius 0.1)
		)
		(polygon
			(pts
				(xy 36.857962 166.7865) (xy 43.637962 166.7865) (xy 44.247962 162.3165) (xy 42.427962 162.1865)
				(xy 40.017962 157.7465) (xy 40.037962 127.0465) (xy 42.797962 124.0965) (xy 42.807962 121.7465)
				(xy 39.897962 121.7465) (xy 36.867962 123.4665)
			)
		)
	)
	(zone
		(net 30)
		(net_name "/USB/USB_1V2")
		(layer "In2.Cu")
		(hatch edge 0.508)
		(priority 12)
		(connect_pads
			(clearance 0.127)
		)
		(min_thickness 0.127)
		(filled_areas_thickness no)
		(fill yes
			(thermal_gap 0.127)
			(thermal_bridge_width 0.25)
			(smoothing fillet)
			(radius 0.15)
		)
		(polygon
			(pts
				(xy 86.847962 144.6565) (xy 94.367962 144.7415) (xy 94.517962 144.5915) (xy 94.517962 139.8165)
				(xy 96.367962 137.9665) (xy 96.367962 137.6665) (xy 95.767962 136.9565) (xy 90.792962 136.9565)
				(xy 86.267962 132.5415) (xy 85.917962 132.5415) (xy 85.167962 133.2915) (xy 85.167962 136.4665)
				(xy 83.792962 137.8415) (xy 83.792962 138.4665) (xy 86.842962 141.5165)
			)
		)
	)
	(zone
		(net 0)
		(net_name "")
		(layer "In2.Cu")
		(hatch edge 0.5)
		(connect_pads
			(clearance 0)
		)
		(min_thickness 0.25)
		(filled_areas_thickness no)
		(keepout
			(tracks allowed)
			(vias allowed)
			(pads allowed)
			(copperpour not_allowed)
			(footprints allowed)
		)
		(placement
			(enabled no)
			(sheetname "")
		)
		(fill
			(thermal_gap 0.5)
			(thermal_bridge_width 0.5)
		)
		(polygon
			(pts
				(xy 115.5 152.6) (xy 118.69 152.53) (xy 120.3 154.07) (xy 122.5 154.04) (xy 127.816299 149.215222)
				(xy 127.817962 146.7665) (xy 139.167962 135.5415) (xy 139.167962 130.0915) (xy 140.417962 128.9165)
				(xy 140.417962 125.6665) (xy 138.992962 124.2415) (xy 133.967962 124.2415) (xy 130.892962 127.2415)
				(xy 130.642962 127.4915) (xy 130.642962 130.405399) (xy 118.807087 142.051462) (xy 118.781701 146.14034)
				(xy 116.792962 148.1915) (xy 115.467962 148.1915)
			)
		)
	)
	(zone
		(net 47)
		(net_name "/Ethernet/POE_12V")
		(layer "In2.Cu")
		(hatch edge 0.508)
		(priority 11)
		(connect_pads
			(clearance 0.2)
		)
		(min_thickness 0.2)
		(filled_areas_thickness no)
		(fill yes
			(thermal_gap 0.2)
			(thermal_bridge_width 0.35)
			(smoothing fillet)
			(radius 0.15)
		)
		(polygon
			(pts
				(xy 55.797962 162.9765) (xy 54.917962 164.4965) (xy 54.377962 166.5865) (xy 54.377962 169.8665)
				(xy 61.647962 169.6965) (xy 61.647962 166.0165) (xy 58.017962 164.8265) (xy 58.017962 162.9765)
			)
		)
	)
	(zone
		(net 27)
		(net_name "/USB/USB_3V3")
		(layer "In3.Cu")
		(hatch edge 0.508)
		(priority 6)
		(connect_pads
			(clearance 0.127)
		)
		(min_thickness 0.127)
		(filled_areas_thickness no)
		(fill yes
			(thermal_gap 0.127)
			(thermal_bridge_width 0.25)
			(smoothing fillet)
			(radius 0.15)
		)
		(polygon
			(pts
				(xy 93.317962 146.3915) (xy 92.042962 146.3915) (xy 91.067962 145.4165) (xy 91.067962 145.0415)
				(xy 87.520834 145.044372) (xy 81.517962 139.0915) (xy 81.517962 134.3415) (xy 81.742962 134.1165)
				(xy 84.292962 134.1165) (xy 86.117962 132.2915) (xy 86.117962 130.7665) (xy 87.192962 129.6915)
				(xy 92.842962 129.6915) (xy 93.242962 130.0915) (xy 93.242962 134.8915) (xy 94.367962 136.0165)
				(xy 95.592962 136.0165) (xy 95.592962 141.8165) (xy 94.767962 142.6415) (xy 93.717962 142.6415)
				(xy 93.317962 143.0415)
			)
		)
	)
	(zone
		(net 3)
		(net_name "GND")
		(layer "In3.Cu")
		(hatch edge 0.508)
		(priority 4)
		(connect_pads
			(clearance 0.127)
		)
		(min_thickness 0.127)
		(filled_areas_thickness no)
		(fill yes
			(thermal_gap 0.127)
			(thermal_bridge_width 0.25)
			(smoothing fillet)
			(radius 0.15)
		)
		(polygon
			(pts
				(xy 115.467962 154.806936) (xy 122.492962 154.6165) (xy 127.816299 149.215222) (xy 127.817632 147.252378)
				(xy 141.75 134.18) (xy 141.840609 126.339147) (xy 139.742962 124.2415) (xy 133.967962 124.2415)
				(xy 130.925569 127.211154) (xy 130.42 127.04) (xy 130.27 127.25) (xy 130.642962 127.65) (xy 130.642962 130.367424)
				(xy 119.307323 141.553252) (xy 119.281701 145.68034) (xy 116.792962 148.1915) (xy 115.467962 148.1915)
			)
		)
	)
	(zone
		(net 0)
		(net_name "")
		(layer "In3.Cu")
		(hatch edge 0.508)
		(connect_pads
			(clearance 0)
		)
		(min_thickness 0.127)
		(filled_areas_thickness no)
		(keepout
			(tracks not_allowed)
			(vias allowed)
			(pads allowed)
			(copperpour allowed)
			(footprints allowed)
		)
		(placement
			(enabled no)
			(sheetname "")
		)
		(fill
			(thermal_gap 0.127)
			(thermal_bridge_width 0.25)
		)
		(polygon
			(pts
				(xy 115.467962 154.806936) (xy 122.492962 154.6165) (xy 127.816299 149.215222) (xy 127.817962 146.7665)
				(xy 139.167962 135.5415) (xy 139.167962 130.0915) (xy 140.417962 128.9165) (xy 140.417962 125.6665)
				(xy 138.992962 124.2415) (xy 133.967962 124.2415) (xy 132.430462 125.7415) (xy 130.93 127.20683)
				(xy 130.892962 127.2415) (xy 130.642962 127.4915) (xy 130.642962 127.84) (xy 130.642962 130.405399)
				(xy 119.307087 141.591462) (xy 119.281701 145.68034) (xy 116.792962 148.1915) (xy 115.467962 148.1915)
			)
		)
	)
	(zone
		(net 10)
		(net_name "+5V")
		(layer "In3.Cu")
		(hatch edge 0.5)
		(priority 3)
		(connect_pads
			(clearance 0.15)
		)
		(min_thickness 0.15)
		(filled_areas_thickness no)
		(fill yes
			(thermal_gap 0.2)
			(thermal_bridge_width 0.35)
			(smoothing fillet)
			(radius 0.1)
		)
		(polygon
			(pts
				(xy 66.827962 158.7865) (xy 66.817962 154.864659) (xy 70.65 149.94) (xy 74.417962 128.164659) (xy 74.417962 111.614659)
				(xy 132.95 111.7165) (xy 134.55 124.2415) (xy 137.63 146.33) (xy 138.74 166.53) (xy 133.13 172.14)
				(xy 113.44 172.14) (xy 113.44001 179.654377) (xy 81.067962 179.6415)
			)
		)
	)
	(zone
		(net 443)
		(net_name "/Supply/V_{BUS}")
		(layer "In3.Cu")
		(hatch edge 0.5)
		(priority 20)
		(connect_pads
			(clearance 0.2)
		)
		(min_thickness 0.15)
		(filled_areas_thickness no)
		(fill yes
			(thermal_gap 0.15)
			(thermal_bridge_width 0.4)
			(smoothing fillet)
			(radius 0.15)
		)
		(polygon
			(pts
				(xy 47.697962 166.6865) (xy 51.017962 166.7265) (xy 51.617916 165.053171) (xy 55.037962 165.0765)
				(xy 70.317962 156.5865) (xy 73.407962 153.5365) (xy 73.397962 135.5565) (xy 76.727962 130.8965)
				(xy 76.727962 129.3265) (xy 73.517962 129.3065) (xy 70.617962 131.7065) (xy 70.657962 152.5565)
				(xy 69.317962 154.2065) (xy 61.997962 154.1765) (xy 47.697962 162.6965)
			)
		)
	)
)
